G04 ================== begin FILE IDENTIFICATION RECORD ==================*
G04 Layout Name:  x887571-005_osp.brd*
G04 Film Name:    fab-sh1*
G04 File Format:  Gerber RS274X*
G04 File Origin:  Cadence Allegro 16.3-S036*
G04 Origin Date:  Thu Jul 03 00:06:56 2014*
G04 *
G04 Layer:  DRAWING FORMAT/OUTLINE*
G04 Layer:  DRAWING FORMAT/TITLE_BLOCK*
G04 Layer:  DRAWING FORMAT/TITLE_DATA*
G04 Layer:  DRAWING FORMAT/REVISION_BLOCK*
G04 Layer:  DRAWING FORMAT/REVISION_DATA*
G04 Layer:  DRAWING FORMAT/FAB-SHT1*
G04 *
G04 Offset:    (0.0000 0.0000)*
G04 Mirror:    No*
G04 Mode:      Positive*
G04 Rotation:  0*
G04 FullContactRelief:  No*
G04 UndefLineWidth:     4.0000*
G04 ================== end FILE IDENTIFICATION RECORD ====================*
%FSLAX25Y25*MOIN*%
%IR0*IPPOS*OFA0.00000B0.00000*MIA0B0*SFA1.00000B1.00000*%
%ADD10C,.01*%
%ADD11C,.02*%
%ADD12C,.012*%
%ADD13C,.0201*%
%ADD14C,.05*%
%ADD15C,.015*%
%ADD16C,.025*%
%ADD17C,.018*%
%ADD18C,.006*%
%ADD19C,.009*%
%ADD20C,.004*%
G75*
%LPD*%
G75*
G54D10*
G01X384900Y-690000D02*
Y-680000D01*
X380583Y-687167D01*
X386417D01*
G01X393000Y-690333D02*
X392767Y-690167D01*
Y-689833D01*
X393000Y-689667D01*
X393233Y-689833D01*
Y-690167D01*
X393000Y-690333D01*
G01X412000Y-680000D02*
Y-690000D01*
G01X409317Y-680000D02*
X414683D01*
G01X421500Y-690000D02*
X420567Y-689833D01*
X419750Y-689167D01*
X419050Y-688167D01*
X418583Y-687000D01*
X418350Y-685667D01*
Y-684333D01*
X418583Y-683000D01*
X419050Y-681833D01*
X419750Y-680833D01*
X420567Y-680167D01*
X421500Y-680000D01*
X422433Y-680167D01*
X423250Y-680833D01*
X423950Y-681833D01*
X424417Y-683000D01*
X424650Y-684333D01*
Y-685667D01*
X424417Y-687000D01*
X423950Y-688167D01*
X423250Y-689167D01*
X422433Y-689833D01*
X421500Y-690000D01*
G01X428667Y-680000D02*
Y-690000D01*
X433333D01*
G01X442833D02*
X438167D01*
Y-680000D01*
X442833D01*
G01X440967Y-684833D02*
X438167D01*
G01X447667Y-690000D02*
Y-680000D01*
X450583D01*
X451517Y-680500D01*
X452100Y-681167D01*
X452333Y-682500D01*
X452100Y-683833D01*
X451400Y-684667D01*
X450583Y-685167D01*
X447667D01*
G01X450583D02*
X452333Y-690000D01*
G01X456583D02*
X459500Y-680000D01*
X462417Y-690000D01*
G01X461367Y-686500D02*
X457633D01*
G01X466317Y-690000D02*
Y-680000D01*
X471683Y-690000D01*
Y-680000D01*
G01X481067Y-680833D02*
X480367Y-680333D01*
X479550Y-680000D01*
X478617D01*
X477567Y-680500D01*
X476750Y-681333D01*
X476167Y-682333D01*
X475700Y-684000D01*
X475583Y-685500D01*
X475817Y-687000D01*
X476167Y-688000D01*
X476867Y-689000D01*
X477683Y-689667D01*
X478500Y-690000D01*
X479317D01*
X480133Y-689667D01*
X480833Y-689167D01*
X481417Y-688500D01*
G01X490333Y-690000D02*
X485667D01*
Y-680000D01*
X490333D01*
G01X488467Y-684833D02*
X485667D01*
G01X495050Y-688667D02*
X495983Y-689500D01*
X497033Y-690000D01*
X497967D01*
X498900Y-689500D01*
X499600Y-688667D01*
X499950Y-687500D01*
X499717Y-686334D01*
X499133Y-685333D01*
X498083Y-684667D01*
X496683Y-684333D01*
X495867Y-683667D01*
X495517Y-682500D01*
X495750Y-681333D01*
X496333Y-680500D01*
X497150Y-680000D01*
X497967D01*
X498783Y-680333D01*
X499483Y-681167D01*
G01X380933Y-658000D02*
X381633Y-659167D01*
X382567Y-659833D01*
X383617Y-660000D01*
X384550Y-659833D01*
X385483Y-659000D01*
X386067Y-658000D01*
X386183Y-657000D01*
X385950Y-655834D01*
X385133Y-655000D01*
X384317Y-654667D01*
X383267D01*
G01X384317D02*
X385017Y-654167D01*
X385600Y-653334D01*
X385833Y-652333D01*
X385600Y-651333D01*
X385017Y-650500D01*
X383967Y-650000D01*
X382917Y-650167D01*
X381867Y-650833D01*
G01X393000Y-660333D02*
X392767Y-660167D01*
Y-659833D01*
X393000Y-659667D01*
X393233Y-659833D01*
Y-660167D01*
X393000Y-660333D01*
G01X409433Y-660000D02*
Y-650000D01*
X411767D01*
X412700Y-650500D01*
X413400Y-651167D01*
X413983Y-652167D01*
X414450Y-653334D01*
X414567Y-655000D01*
X414450Y-656667D01*
X413983Y-657833D01*
X413400Y-658834D01*
X412700Y-659500D01*
X411767Y-660000D01*
X409433D01*
G01X421500D02*
X420567Y-659833D01*
X419750Y-659167D01*
X419050Y-658167D01*
X418583Y-657000D01*
X418350Y-655667D01*
Y-654333D01*
X418583Y-653000D01*
X419050Y-651833D01*
X419750Y-650833D01*
X420567Y-650167D01*
X421500Y-650000D01*
X422433Y-650167D01*
X423250Y-650833D01*
X423950Y-651833D01*
X424417Y-653000D01*
X424650Y-654333D01*
Y-655667D01*
X424417Y-657000D01*
X423950Y-658167D01*
X423250Y-659167D01*
X422433Y-659833D01*
X421500Y-660000D01*
G01X437817D02*
Y-650000D01*
X443183Y-660000D01*
Y-650000D01*
G01X450000Y-660000D02*
X449067Y-659833D01*
X448250Y-659167D01*
X447550Y-658167D01*
X447083Y-657000D01*
X446850Y-655667D01*
Y-654333D01*
X447083Y-653000D01*
X447550Y-651833D01*
X448250Y-650833D01*
X449067Y-650167D01*
X450000Y-650000D01*
X450933Y-650167D01*
X451750Y-650833D01*
X452450Y-651833D01*
X452917Y-653000D01*
X453150Y-654333D01*
Y-655667D01*
X452917Y-657000D01*
X452450Y-658167D01*
X451750Y-659167D01*
X450933Y-659833D01*
X450000Y-660000D01*
G01X459500Y-650000D02*
Y-660000D01*
G01X456817Y-650000D02*
X462183D01*
G01X476050Y-658667D02*
X476983Y-659500D01*
X478033Y-660000D01*
X478967D01*
X479900Y-659500D01*
X480600Y-658667D01*
X480950Y-657500D01*
X480717Y-656334D01*
X480133Y-655333D01*
X479083Y-654667D01*
X477683Y-654333D01*
X476867Y-653667D01*
X476517Y-652500D01*
X476750Y-651333D01*
X477333Y-650500D01*
X478150Y-650000D01*
X478967D01*
X479783Y-650333D01*
X480483Y-651167D01*
G01X490567Y-650833D02*
X489867Y-650333D01*
X489050Y-650000D01*
X488117D01*
X487067Y-650500D01*
X486250Y-651333D01*
X485667Y-652333D01*
X485200Y-654000D01*
X485083Y-655500D01*
X485317Y-657000D01*
X485667Y-658000D01*
X486367Y-659000D01*
X487183Y-659667D01*
X488000Y-660000D01*
X488817D01*
X489633Y-659667D01*
X490333Y-659167D01*
X490917Y-658500D01*
G01X494583Y-660000D02*
X497500Y-650000D01*
X500417Y-660000D01*
G01X499367Y-656500D02*
X495633D01*
G01X504667Y-650000D02*
Y-660000D01*
X509333D01*
G01X518833D02*
X514167D01*
Y-650000D01*
X518833D01*
G01X516967Y-654833D02*
X514167D01*
G01X532933Y-660000D02*
Y-650000D01*
X535267D01*
X536200Y-650500D01*
X536900Y-651167D01*
X537483Y-652167D01*
X537950Y-653334D01*
X538067Y-655000D01*
X537950Y-656667D01*
X537483Y-657833D01*
X536900Y-658834D01*
X536200Y-659500D01*
X535267Y-660000D01*
X532933D01*
G01X542667D02*
Y-650000D01*
X545583D01*
X546517Y-650500D01*
X547100Y-651167D01*
X547333Y-652500D01*
X547100Y-653833D01*
X546400Y-654667D01*
X545583Y-655167D01*
X542667D01*
G01X545583D02*
X547333Y-660000D01*
G01X551583D02*
X554500Y-650000D01*
X557417Y-660000D01*
G01X556367Y-656500D02*
X552633D01*
G01X560500Y-650000D02*
X562133Y-660000D01*
X564000Y-650000D01*
X565867Y-660000D01*
X567500Y-650000D01*
G01X572100D02*
X574900D01*
G01X573500D02*
Y-660000D01*
G01X572100D02*
X574900D01*
G01X580317D02*
Y-650000D01*
X585683Y-660000D01*
Y-650000D01*
G01X593200Y-655000D02*
X595533D01*
Y-658000D01*
X594833Y-659000D01*
X594017Y-659667D01*
X592850Y-660000D01*
X591683Y-659667D01*
X590867Y-659000D01*
X590167Y-658000D01*
X589700Y-656833D01*
X589467Y-655500D01*
Y-654333D01*
X589700Y-653334D01*
X590167Y-652167D01*
X590867Y-651167D01*
X591567Y-650500D01*
X592500Y-650000D01*
X593317D01*
X594250Y-650333D01*
X594950Y-651000D01*
G01X381283Y-621667D02*
X381983Y-620667D01*
X382800Y-620167D01*
X383733Y-620000D01*
X384900Y-620333D01*
X385717Y-621167D01*
X385950Y-622167D01*
X385833Y-623167D01*
X385367Y-624000D01*
X383033Y-625667D01*
X381983Y-626833D01*
X381283Y-628500D01*
X381050Y-630000D01*
X385950D01*
G01X393000Y-630333D02*
X392767Y-630167D01*
Y-629833D01*
X393000Y-629667D01*
X393233Y-629833D01*
Y-630167D01*
X393000Y-630333D01*
G01X412933Y-624667D02*
X413400Y-624167D01*
X413750Y-623334D01*
X413983Y-622167D01*
X413750Y-621167D01*
X413283Y-620500D01*
X412467Y-620000D01*
X409317D01*
Y-630000D01*
X413167D01*
X413983Y-629333D01*
X414450Y-628333D01*
X414683Y-627167D01*
X414450Y-626000D01*
X413750Y-625000D01*
X412933Y-624667D01*
X409317D01*
G01X419167Y-630000D02*
Y-620000D01*
X422083D01*
X423017Y-620500D01*
X423600Y-621167D01*
X423833Y-622500D01*
X423600Y-623833D01*
X422900Y-624667D01*
X422083Y-625167D01*
X419167D01*
G01X422083D02*
X423833Y-630000D01*
G01X433333D02*
X428667D01*
Y-620000D01*
X433333D01*
G01X431467Y-624833D02*
X428667D01*
G01X437583Y-630000D02*
X440500Y-620000D01*
X443417Y-630000D01*
G01X442367Y-626500D02*
X438633D01*
G01X447433Y-630000D02*
Y-620000D01*
G01X451867D02*
X447433Y-626167D01*
G01X452567Y-630000D02*
X449417Y-623334D01*
G01X466083Y-630000D02*
X469000Y-620000D01*
X471917Y-630000D01*
G01X470867Y-626500D02*
X467133D01*
G01X476167Y-620000D02*
Y-630000D01*
X480833D01*
G01X485667Y-620000D02*
Y-630000D01*
X490333D01*
G01X504550Y-628667D02*
X505483Y-629500D01*
X506533Y-630000D01*
X507467D01*
X508400Y-629500D01*
X509100Y-628667D01*
X509450Y-627500D01*
X509217Y-626334D01*
X508633Y-625333D01*
X507583Y-624667D01*
X506183Y-624333D01*
X505367Y-623667D01*
X505017Y-622500D01*
X505250Y-621333D01*
X505833Y-620500D01*
X506650Y-620000D01*
X507467D01*
X508283Y-620333D01*
X508983Y-621167D01*
G01X514050Y-630000D02*
Y-620000D01*
G01X518950D02*
Y-630000D01*
G01Y-625000D02*
X514050D01*
G01X523083Y-630000D02*
X526000Y-620000D01*
X528917Y-630000D01*
G01X527867Y-626500D02*
X524133D01*
G01X533167Y-630000D02*
Y-620000D01*
X536083D01*
X537017Y-620500D01*
X537600Y-621167D01*
X537833Y-622500D01*
X537600Y-623833D01*
X536900Y-624667D01*
X536083Y-625167D01*
X533167D01*
G01X536083D02*
X537833Y-630000D01*
G01X542667D02*
Y-620000D01*
X545467D01*
X546400Y-620500D01*
X547100Y-621667D01*
X547333Y-623000D01*
X547100Y-624333D01*
X546517Y-625333D01*
X545467Y-625834D01*
X542667D01*
G01X566333Y-630000D02*
X561667D01*
Y-620000D01*
X566333D01*
G01X564467Y-624833D02*
X561667D01*
G01X570933Y-630000D02*
Y-620000D01*
X573267D01*
X574200Y-620500D01*
X574900Y-621167D01*
X575483Y-622167D01*
X575950Y-623334D01*
X576067Y-625000D01*
X575950Y-626667D01*
X575483Y-627833D01*
X574900Y-628834D01*
X574200Y-629500D01*
X573267Y-630000D01*
X570933D01*
G01X583700Y-625000D02*
X586033D01*
Y-628000D01*
X585333Y-629000D01*
X584517Y-629667D01*
X583350Y-630000D01*
X582183Y-629667D01*
X581367Y-629000D01*
X580667Y-628000D01*
X580200Y-626833D01*
X579967Y-625500D01*
Y-624333D01*
X580200Y-623334D01*
X580667Y-622167D01*
X581367Y-621167D01*
X582067Y-620500D01*
X583000Y-620000D01*
X583817D01*
X584750Y-620333D01*
X585450Y-621000D01*
G01X594833Y-630000D02*
X590167D01*
Y-620000D01*
X594833D01*
G01X592967Y-624833D02*
X590167D01*
G01X599550Y-628667D02*
X600483Y-629500D01*
X601533Y-630000D01*
X602467D01*
X603400Y-629500D01*
X604100Y-628667D01*
X604450Y-627500D01*
X604217Y-626334D01*
X603633Y-625333D01*
X602583Y-624667D01*
X601183Y-624333D01*
X600367Y-623667D01*
X600017Y-622500D01*
X600250Y-621333D01*
X600833Y-620500D01*
X601650Y-620000D01*
X602467D01*
X603283Y-620333D01*
X603983Y-621167D01*
G01X383500Y-600000D02*
Y-590000D01*
X382100Y-592000D01*
G01Y-600000D02*
X384900D01*
G01X393000Y-600333D02*
X392767Y-600167D01*
Y-599833D01*
X393000Y-599667D01*
X393233Y-599833D01*
Y-600167D01*
X393000Y-600333D01*
G01X409433Y-600000D02*
Y-590000D01*
X411767D01*
X412700Y-590500D01*
X413400Y-591167D01*
X413983Y-592167D01*
X414450Y-593334D01*
X414567Y-595000D01*
X414450Y-596667D01*
X413983Y-597833D01*
X413400Y-598834D01*
X412700Y-599500D01*
X411767Y-600000D01*
X409433D01*
G01X420100Y-590000D02*
X422900D01*
G01X421500D02*
Y-600000D01*
G01X420100D02*
X422900D01*
G01X427967D02*
Y-590000D01*
X431000Y-598333D01*
X434033Y-590000D01*
Y-600000D01*
G01X442833D02*
X438167D01*
Y-590000D01*
X442833D01*
G01X440967Y-594833D02*
X438167D01*
G01X447317Y-600000D02*
Y-590000D01*
X452683Y-600000D01*
Y-590000D01*
G01X457050Y-598667D02*
X457983Y-599500D01*
X459033Y-600000D01*
X459967D01*
X460900Y-599500D01*
X461600Y-598667D01*
X461950Y-597500D01*
X461717Y-596334D01*
X461133Y-595333D01*
X460083Y-594667D01*
X458683Y-594333D01*
X457867Y-593667D01*
X457517Y-592500D01*
X457750Y-591333D01*
X458333Y-590500D01*
X459150Y-590000D01*
X459967D01*
X460783Y-590333D01*
X461483Y-591167D01*
G01X467600Y-590000D02*
X470400D01*
G01X469000D02*
Y-600000D01*
G01X467600D02*
X470400D01*
G01X478500D02*
X477567Y-599833D01*
X476750Y-599167D01*
X476050Y-598167D01*
X475583Y-597000D01*
X475350Y-595667D01*
Y-594333D01*
X475583Y-593000D01*
X476050Y-591833D01*
X476750Y-590833D01*
X477567Y-590167D01*
X478500Y-590000D01*
X479433Y-590167D01*
X480250Y-590833D01*
X480950Y-591833D01*
X481417Y-593000D01*
X481650Y-594333D01*
Y-595667D01*
X481417Y-597000D01*
X480950Y-598167D01*
X480250Y-599167D01*
X479433Y-599833D01*
X478500Y-600000D01*
G01X485317D02*
Y-590000D01*
X490683Y-600000D01*
Y-590000D01*
G01X495050Y-598667D02*
X495983Y-599500D01*
X497033Y-600000D01*
X497967D01*
X498900Y-599500D01*
X499600Y-598667D01*
X499950Y-597500D01*
X499717Y-596334D01*
X499133Y-595333D01*
X498083Y-594667D01*
X496683Y-594333D01*
X495867Y-593667D01*
X495517Y-592500D01*
X495750Y-591333D01*
X496333Y-590500D01*
X497150Y-590000D01*
X497967D01*
X498783Y-590333D01*
X499483Y-591167D01*
G01X513583Y-600000D02*
X516500Y-590000D01*
X519417Y-600000D01*
G01X518367Y-596500D02*
X514633D01*
G01X523667Y-600000D02*
Y-590000D01*
X526583D01*
X527517Y-590500D01*
X528100Y-591167D01*
X528333Y-592500D01*
X528100Y-593833D01*
X527400Y-594667D01*
X526583Y-595167D01*
X523667D01*
G01X526583D02*
X528333Y-600000D01*
G01X537833D02*
X533167D01*
Y-590000D01*
X537833D01*
G01X535967Y-594833D02*
X533167D01*
G01X553100Y-590000D02*
X555900D01*
G01X554500D02*
Y-600000D01*
G01X553100D02*
X555900D01*
G01X561317D02*
Y-590000D01*
X566683Y-600000D01*
Y-590000D01*
G01X581600D02*
X584400D01*
G01X583000D02*
Y-600000D01*
G01X581600D02*
X584400D01*
G01X589817D02*
Y-590000D01*
X595183Y-600000D01*
Y-590000D01*
G01X604567Y-590833D02*
X603867Y-590333D01*
X603050Y-590000D01*
X602117D01*
X601067Y-590500D01*
X600250Y-591333D01*
X599667Y-592333D01*
X599200Y-594000D01*
X599083Y-595500D01*
X599317Y-597000D01*
X599667Y-598000D01*
X600367Y-599000D01*
X601183Y-599667D01*
X602000Y-600000D01*
X602817D01*
X603633Y-599667D01*
X604333Y-599167D01*
X604917Y-598500D01*
G01X609050Y-600000D02*
Y-590000D01*
G01X613950D02*
Y-600000D01*
G01Y-595000D02*
X609050D01*
G01X623333Y-600000D02*
X618667D01*
Y-590000D01*
X623333D01*
G01X621467Y-594833D02*
X618667D01*
G01X628050Y-598667D02*
X628983Y-599500D01*
X630033Y-600000D01*
X630967D01*
X631900Y-599500D01*
X632600Y-598667D01*
X632950Y-597500D01*
X632717Y-596334D01*
X632133Y-595333D01*
X631083Y-594667D01*
X629683Y-594333D01*
X628867Y-593667D01*
X628517Y-592500D01*
X628750Y-591333D01*
X629333Y-590500D01*
X630150Y-590000D01*
X630967D01*
X631783Y-590333D01*
X632483Y-591167D01*
G01X380933Y-560000D02*
Y-567167D01*
X381400Y-568667D01*
X382333Y-569667D01*
X383500Y-570000D01*
X384667Y-569667D01*
X385600Y-568667D01*
X386067Y-567167D01*
Y-560000D01*
G01X390317Y-570000D02*
Y-560000D01*
X395683Y-570000D01*
Y-560000D01*
G01X400167D02*
Y-570000D01*
X404833D01*
G01X414333D02*
X409667D01*
Y-560000D01*
X414333D01*
G01X412467Y-564833D02*
X409667D01*
G01X419050Y-568667D02*
X419983Y-569500D01*
X421033Y-570000D01*
X421967D01*
X422900Y-569500D01*
X423600Y-568667D01*
X423950Y-567500D01*
X423717Y-566334D01*
X423133Y-565333D01*
X422083Y-564667D01*
X420683Y-564333D01*
X419867Y-563667D01*
X419517Y-562500D01*
X419750Y-561333D01*
X420333Y-560500D01*
X421150Y-560000D01*
X421967D01*
X422783Y-560333D01*
X423483Y-561167D01*
G01X428550Y-568667D02*
X429483Y-569500D01*
X430533Y-570000D01*
X431467D01*
X432400Y-569500D01*
X433100Y-568667D01*
X433450Y-567500D01*
X433217Y-566334D01*
X432633Y-565333D01*
X431583Y-564667D01*
X430183Y-564333D01*
X429367Y-563667D01*
X429017Y-562500D01*
X429250Y-561333D01*
X429833Y-560500D01*
X430650Y-560000D01*
X431467D01*
X432283Y-560333D01*
X432983Y-561167D01*
G01X450000Y-570000D02*
X449067Y-569833D01*
X448250Y-569167D01*
X447550Y-568167D01*
X447083Y-567000D01*
X446850Y-565667D01*
Y-564333D01*
X447083Y-563000D01*
X447550Y-561833D01*
X448250Y-560833D01*
X449067Y-560167D01*
X450000Y-560000D01*
X450933Y-560167D01*
X451750Y-560833D01*
X452450Y-561833D01*
X452917Y-563000D01*
X453150Y-564333D01*
Y-565667D01*
X452917Y-567000D01*
X452450Y-568167D01*
X451750Y-569167D01*
X450933Y-569833D01*
X450000Y-570000D01*
G01X459500Y-560000D02*
Y-570000D01*
G01X456817Y-560000D02*
X462183D01*
G01X466550Y-570000D02*
Y-560000D01*
G01X471450D02*
Y-570000D01*
G01Y-565000D02*
X466550D01*
G01X480833Y-570000D02*
X476167D01*
Y-560000D01*
X480833D01*
G01X478967Y-564833D02*
X476167D01*
G01X485667Y-570000D02*
Y-560000D01*
X488583D01*
X489517Y-560500D01*
X490100Y-561167D01*
X490333Y-562500D01*
X490100Y-563833D01*
X489400Y-564667D01*
X488583Y-565167D01*
X485667D01*
G01X488583D02*
X490333Y-570000D01*
G01X494000Y-560000D02*
X495633Y-570000D01*
X497500Y-560000D01*
X499367Y-570000D01*
X501000Y-560000D01*
G01X505600D02*
X508400D01*
G01X507000D02*
Y-570000D01*
G01X505600D02*
X508400D01*
G01X514050Y-568667D02*
X514983Y-569500D01*
X516033Y-570000D01*
X516967D01*
X517900Y-569500D01*
X518600Y-568667D01*
X518950Y-567500D01*
X518717Y-566334D01*
X518133Y-565333D01*
X517083Y-564667D01*
X515683Y-564333D01*
X514867Y-563667D01*
X514517Y-562500D01*
X514750Y-561333D01*
X515333Y-560500D01*
X516150Y-560000D01*
X516967D01*
X517783Y-560333D01*
X518483Y-561167D01*
G01X528333Y-570000D02*
X523667D01*
Y-560000D01*
X528333D01*
G01X526467Y-564833D02*
X523667D01*
G01X542550Y-568667D02*
X543483Y-569500D01*
X544533Y-570000D01*
X545467D01*
X546400Y-569500D01*
X547100Y-568667D01*
X547450Y-567500D01*
X547217Y-566334D01*
X546633Y-565333D01*
X545583Y-564667D01*
X544183Y-564333D01*
X543367Y-563667D01*
X543017Y-562500D01*
X543250Y-561333D01*
X543833Y-560500D01*
X544650Y-560000D01*
X545467D01*
X546283Y-560333D01*
X546983Y-561167D01*
G01X552167Y-570000D02*
Y-560000D01*
X554967D01*
X555900Y-560500D01*
X556600Y-561667D01*
X556833Y-563000D01*
X556600Y-564333D01*
X556017Y-565333D01*
X554967Y-565834D01*
X552167D01*
G01X566333Y-570000D02*
X561667D01*
Y-560000D01*
X566333D01*
G01X564467Y-564833D02*
X561667D01*
G01X576067Y-560833D02*
X575367Y-560333D01*
X574550Y-560000D01*
X573617D01*
X572567Y-560500D01*
X571750Y-561333D01*
X571167Y-562333D01*
X570700Y-564000D01*
X570583Y-565500D01*
X570817Y-567000D01*
X571167Y-568000D01*
X571867Y-569000D01*
X572683Y-569667D01*
X573500Y-570000D01*
X574317D01*
X575133Y-569667D01*
X575833Y-569167D01*
X576417Y-568500D01*
G01X581600Y-560000D02*
X584400D01*
G01X583000D02*
Y-570000D01*
G01X581600D02*
X584400D01*
G01X590283D02*
Y-560000D01*
X594717D01*
G01X593083Y-564833D02*
X590283D01*
G01X600600Y-560000D02*
X603400D01*
G01X602000D02*
Y-570000D01*
G01X600600D02*
X603400D01*
G01X613833D02*
X609167D01*
Y-560000D01*
X613833D01*
G01X611967Y-564833D02*
X609167D01*
G01X618433Y-570000D02*
Y-560000D01*
X620767D01*
X621700Y-560500D01*
X622400Y-561167D01*
X622983Y-562167D01*
X623450Y-563334D01*
X623567Y-565000D01*
X623450Y-566667D01*
X622983Y-567833D01*
X622400Y-568834D01*
X621700Y-569500D01*
X620767Y-570000D01*
X618433D01*
G01X630500Y-570333D02*
X630267Y-570167D01*
Y-569833D01*
X630500Y-569667D01*
X630733Y-569833D01*
Y-570167D01*
X630500Y-570333D01*
G01Y-565834D02*
X630267Y-565667D01*
Y-565333D01*
X630500Y-565167D01*
X630733Y-565333D01*
Y-565667D01*
X630500Y-565834D01*
G01X396750Y-773334D02*
X400250Y-780000D01*
G01Y-773334D02*
X396750Y-780000D01*
G01X406250Y-773334D02*
X409750Y-780000D01*
G01Y-773334D02*
X406250Y-780000D01*
G01X415750Y-773334D02*
X419250Y-780000D01*
G01Y-773334D02*
X415750Y-780000D01*
G01X435217Y-776667D02*
X438017D01*
G01X436500Y-774500D02*
Y-778834D01*
G01X443900Y-780333D02*
X448100Y-770000D01*
G01X453983Y-776667D02*
X457017D01*
G01X396750Y-743334D02*
X400250Y-750000D01*
G01Y-743334D02*
X396750Y-750000D01*
G01X406250Y-743334D02*
X409750Y-750000D01*
G01Y-743334D02*
X406250Y-750000D01*
G01X425717Y-746667D02*
X428517D01*
G01X427000Y-744500D02*
Y-748834D01*
G01X434400Y-750333D02*
X438600Y-740000D01*
G01X444483Y-746667D02*
X447517D01*
G01X395583Y-720000D02*
X398500Y-710000D01*
X401417Y-720000D01*
G01X400367Y-716500D02*
X396633D01*
G01X405317Y-720000D02*
Y-710000D01*
X410683Y-720000D01*
Y-710000D01*
G01X418200Y-715000D02*
X420533D01*
Y-718000D01*
X419833Y-719000D01*
X419017Y-719667D01*
X417850Y-720000D01*
X416683Y-719667D01*
X415867Y-719000D01*
X415167Y-718000D01*
X414700Y-716833D01*
X414467Y-715500D01*
Y-714333D01*
X414700Y-713334D01*
X415167Y-712167D01*
X415867Y-711167D01*
X416567Y-710500D01*
X417500Y-710000D01*
X418317D01*
X419250Y-710333D01*
X419950Y-711000D01*
G01X424667Y-710000D02*
Y-720000D01*
X429333D01*
G01X438833D02*
X434167D01*
Y-710000D01*
X438833D01*
G01X436967Y-714833D02*
X434167D01*
G01X443550Y-718667D02*
X444483Y-719500D01*
X445533Y-720000D01*
X446467D01*
X447400Y-719500D01*
X448100Y-718667D01*
X448450Y-717500D01*
X448217Y-716334D01*
X447633Y-715333D01*
X446583Y-714667D01*
X445183Y-714333D01*
X444367Y-713667D01*
X444017Y-712500D01*
X444250Y-711333D01*
X444833Y-710500D01*
X445650Y-710000D01*
X446467D01*
X447283Y-710333D01*
X447983Y-711167D01*
G01X463717Y-716667D02*
X466517D01*
G01X465000Y-714500D02*
Y-718834D01*
G01X472400Y-720333D02*
X476600Y-710000D01*
G01X482483Y-716667D02*
X485517D01*
G01X610167Y1257000D02*
Y1267000D01*
X613083D01*
X614017Y1266500D01*
X614600Y1265833D01*
X614833Y1264500D01*
X614600Y1263167D01*
X613900Y1262333D01*
X613083Y1261833D01*
X610167D01*
G01X613083D02*
X614833Y1257000D01*
G01X624333D02*
X619667D01*
Y1267000D01*
X624333D01*
G01X622467Y1262167D02*
X619667D01*
G01X628583Y1267000D02*
X631500Y1257000D01*
X634417Y1267000D01*
G01X620393Y1204523D02*
X620860Y1205023D01*
X621210Y1205856D01*
X621443Y1207023D01*
X621210Y1208023D01*
X620743Y1208690D01*
X619927Y1209190D01*
X616777D01*
Y1199190D01*
X620627D01*
X621443Y1199857D01*
X621910Y1200857D01*
X622143Y1202023D01*
X621910Y1203190D01*
X621210Y1204190D01*
X620393Y1204523D01*
X616777D01*
G01X616353Y1229220D02*
X619270Y1239220D01*
X622187Y1229220D01*
G01X621137Y1232720D02*
X617403D01*
G01X645583Y-725000D02*
X648500Y-715000D01*
X651417Y-725000D01*
G01X650367Y-721500D02*
X646633D01*
G01X655667Y-725000D02*
Y-715000D01*
X658467D01*
X659400Y-715500D01*
X660100Y-716667D01*
X660333Y-718000D01*
X660100Y-719333D01*
X659517Y-720333D01*
X658467Y-720834D01*
X655667D01*
G01X664583Y-715000D02*
X667500Y-725000D01*
X670417Y-715000D01*
G01X674433Y-725000D02*
Y-715000D01*
X676767D01*
X677700Y-715500D01*
X678400Y-716167D01*
X678983Y-717167D01*
X679450Y-718334D01*
X679567Y-720000D01*
X679450Y-721667D01*
X678983Y-722833D01*
X678400Y-723834D01*
X677700Y-724500D01*
X676767Y-725000D01*
X674433D01*
G01X645583Y-695000D02*
X648500Y-685000D01*
X651417Y-695000D01*
G01X650367Y-691500D02*
X646633D01*
G01X655667Y-695000D02*
Y-685000D01*
X658467D01*
X659400Y-685500D01*
X660100Y-686667D01*
X660333Y-688000D01*
X660100Y-689333D01*
X659517Y-690333D01*
X658467Y-690834D01*
X655667D01*
G01X664583Y-685000D02*
X667500Y-695000D01*
X670417Y-685000D01*
G01X674433Y-695000D02*
Y-685000D01*
X676767D01*
X677700Y-685500D01*
X678400Y-686167D01*
X678983Y-687167D01*
X679450Y-688334D01*
X679567Y-690000D01*
X679450Y-691667D01*
X678983Y-692833D01*
X678400Y-693834D01*
X677700Y-694500D01*
X676767Y-695000D01*
X674433D01*
G01X645583Y-670000D02*
X648500Y-660000D01*
X651417Y-670000D01*
G01X650367Y-666500D02*
X646633D01*
G01X655667Y-670000D02*
Y-660000D01*
X658467D01*
X659400Y-660500D01*
X660100Y-661667D01*
X660333Y-663000D01*
X660100Y-664333D01*
X659517Y-665333D01*
X658467Y-665834D01*
X655667D01*
G01X664583Y-660000D02*
X667500Y-670000D01*
X670417Y-660000D01*
G01X674433Y-670000D02*
Y-660000D01*
X676767D01*
X677700Y-660500D01*
X678400Y-661167D01*
X678983Y-662167D01*
X679450Y-663334D01*
X679567Y-665000D01*
X679450Y-666667D01*
X678983Y-667833D01*
X678400Y-668834D01*
X677700Y-669500D01*
X676767Y-670000D01*
X674433D01*
G01X650833Y-655000D02*
X646167D01*
Y-645000D01*
X650833D01*
G01X648967Y-649833D02*
X646167D01*
G01X655317Y-655000D02*
Y-645000D01*
X660683Y-655000D01*
Y-645000D01*
G01X668200Y-650000D02*
X670533D01*
Y-653000D01*
X669833Y-654000D01*
X669017Y-654667D01*
X667850Y-655000D01*
X666683Y-654667D01*
X665867Y-654000D01*
X665167Y-653000D01*
X664700Y-651833D01*
X664467Y-650500D01*
Y-649333D01*
X664700Y-648334D01*
X665167Y-647167D01*
X665867Y-646167D01*
X666567Y-645500D01*
X667500Y-645000D01*
X668317D01*
X669250Y-645333D01*
X669950Y-646000D01*
G01X674667Y-655000D02*
Y-645000D01*
X677583D01*
X678517Y-645500D01*
X679100Y-646167D01*
X679333Y-647500D01*
X679100Y-648833D01*
X678400Y-649667D01*
X677583Y-650167D01*
X674667D01*
G01X677583D02*
X679333Y-655000D01*
G01X651067Y-620833D02*
X650367Y-620333D01*
X649550Y-620000D01*
X648617D01*
X647567Y-620500D01*
X646750Y-621333D01*
X646167Y-622333D01*
X645700Y-624000D01*
X645583Y-625500D01*
X645817Y-627000D01*
X646167Y-628000D01*
X646867Y-629000D01*
X647683Y-629667D01*
X648500Y-630000D01*
X649317D01*
X650133Y-629667D01*
X650833Y-629167D01*
X651417Y-628500D01*
G01X655550Y-630000D02*
Y-620000D01*
G01X660450D02*
Y-630000D01*
G01Y-625000D02*
X655550D01*
G01X664933Y-630000D02*
Y-620000D01*
G01X669367D02*
X664933Y-626167D01*
G01X670067Y-630000D02*
X666917Y-623334D01*
G01X687433Y-624667D02*
X687900Y-624167D01*
X688250Y-623334D01*
X688483Y-622167D01*
X688250Y-621167D01*
X687783Y-620500D01*
X686967Y-620000D01*
X683817D01*
Y-630000D01*
X687667D01*
X688483Y-629333D01*
X688950Y-628333D01*
X689183Y-627167D01*
X688950Y-626000D01*
X688250Y-625000D01*
X687433Y-624667D01*
X683817D01*
G01X696000Y-630000D02*
Y-625500D01*
X693667Y-620000D01*
G01X698333D02*
X696000Y-625500D01*
G01X705500Y-630333D02*
X705267Y-630167D01*
Y-629833D01*
X705500Y-629667D01*
X705733Y-629833D01*
Y-630167D01*
X705500Y-630333D01*
G01Y-625834D02*
X705267Y-625667D01*
Y-625333D01*
X705500Y-625167D01*
X705733Y-625333D01*
Y-625667D01*
X705500Y-625834D01*
G01X645933Y-600000D02*
Y-590000D01*
X648267D01*
X649200Y-590500D01*
X649900Y-591167D01*
X650483Y-592167D01*
X650950Y-593334D01*
X651067Y-595000D01*
X650950Y-596667D01*
X650483Y-597833D01*
X649900Y-598834D01*
X649200Y-599500D01*
X648267Y-600000D01*
X645933D01*
G01X655667D02*
Y-590000D01*
X658583D01*
X659517Y-590500D01*
X660100Y-591167D01*
X660333Y-592500D01*
X660100Y-593833D01*
X659400Y-594667D01*
X658583Y-595167D01*
X655667D01*
G01X658583D02*
X660333Y-600000D01*
G01X664817D02*
Y-590000D01*
X670183Y-600000D01*
Y-590000D01*
G01X687433Y-594667D02*
X687900Y-594167D01*
X688250Y-593334D01*
X688483Y-592167D01*
X688250Y-591167D01*
X687783Y-590500D01*
X686967Y-590000D01*
X683817D01*
Y-600000D01*
X687667D01*
X688483Y-599333D01*
X688950Y-598333D01*
X689183Y-597167D01*
X688950Y-596000D01*
X688250Y-595000D01*
X687433Y-594667D01*
X683817D01*
G01X696000Y-600000D02*
Y-595500D01*
X693667Y-590000D01*
G01X698333D02*
X696000Y-595500D01*
G01X705500Y-600333D02*
X705267Y-600167D01*
Y-599833D01*
X705500Y-599667D01*
X705733Y-599833D01*
Y-600167D01*
X705500Y-600333D01*
G01Y-595834D02*
X705267Y-595667D01*
Y-595333D01*
X705500Y-595167D01*
X705733Y-595333D01*
Y-595667D01*
X705500Y-595834D01*
G01X679550Y-568667D02*
X680483Y-569500D01*
X681533Y-570000D01*
X682467D01*
X683400Y-569500D01*
X684100Y-568667D01*
X684450Y-567500D01*
X684217Y-566334D01*
X683633Y-565333D01*
X682583Y-564667D01*
X681183Y-564333D01*
X680367Y-563667D01*
X680017Y-562500D01*
X680250Y-561333D01*
X680833Y-560500D01*
X681650Y-560000D01*
X682467D01*
X683283Y-560333D01*
X683983Y-561167D01*
G01X690100Y-560000D02*
X692900D01*
G01X691500D02*
Y-570000D01*
G01X690100D02*
X692900D01*
G01X701700Y-565000D02*
X704033D01*
Y-568000D01*
X703333Y-569000D01*
X702517Y-569667D01*
X701350Y-570000D01*
X700183Y-569667D01*
X699367Y-569000D01*
X698667Y-568000D01*
X698200Y-566833D01*
X697967Y-565500D01*
Y-564333D01*
X698200Y-563334D01*
X698667Y-562167D01*
X699367Y-561167D01*
X700067Y-560500D01*
X701000Y-560000D01*
X701817D01*
X702750Y-560333D01*
X703450Y-561000D01*
G01X707817Y-570000D02*
Y-560000D01*
X713183Y-570000D01*
Y-560000D01*
G01X717083Y-570000D02*
X720000Y-560000D01*
X722917Y-570000D01*
G01X721867Y-566500D02*
X718133D01*
G01X729500Y-560000D02*
Y-570000D01*
G01X726817Y-560000D02*
X732183D01*
G01X736433D02*
Y-567167D01*
X736900Y-568667D01*
X737833Y-569667D01*
X739000Y-570000D01*
X740167Y-569667D01*
X741100Y-568667D01*
X741567Y-567167D01*
Y-560000D01*
G01X746167Y-570000D02*
Y-560000D01*
X749083D01*
X750017Y-560500D01*
X750600Y-561167D01*
X750833Y-562500D01*
X750600Y-563833D01*
X749900Y-564667D01*
X749083Y-565167D01*
X746167D01*
G01X749083D02*
X750833Y-570000D01*
G01X760333D02*
X755667D01*
Y-560000D01*
X760333D01*
G01X758467Y-564833D02*
X755667D01*
G01X727933Y1257000D02*
Y1267000D01*
X730267D01*
X731200Y1266500D01*
X731900Y1265833D01*
X732483Y1264833D01*
X732950Y1263666D01*
X733067Y1262000D01*
X732950Y1260333D01*
X732483Y1259167D01*
X731900Y1258166D01*
X731200Y1257500D01*
X730267Y1257000D01*
X727933D01*
G01X742333D02*
X737667D01*
Y1267000D01*
X742333D01*
G01X740467Y1262167D02*
X737667D01*
G01X747050Y1258333D02*
X747983Y1257500D01*
X749033Y1257000D01*
X749967D01*
X750900Y1257500D01*
X751600Y1258333D01*
X751950Y1259500D01*
X751717Y1260666D01*
X751133Y1261667D01*
X750083Y1262333D01*
X748683Y1262667D01*
X747867Y1263333D01*
X747517Y1264500D01*
X747750Y1265667D01*
X748333Y1266500D01*
X749150Y1267000D01*
X749967D01*
X750783Y1266667D01*
X751483Y1265833D01*
G01X761567Y1266167D02*
X760867Y1266667D01*
X760050Y1267000D01*
X759117D01*
X758067Y1266500D01*
X757250Y1265667D01*
X756667Y1264667D01*
X756200Y1263000D01*
X756083Y1261500D01*
X756317Y1260000D01*
X756667Y1259000D01*
X757367Y1258000D01*
X758183Y1257333D01*
X759000Y1257000D01*
X759817D01*
X760633Y1257333D01*
X761333Y1257833D01*
X761917Y1258500D01*
G01X766167Y1257000D02*
Y1267000D01*
X769083D01*
X770017Y1266500D01*
X770600Y1265833D01*
X770833Y1264500D01*
X770600Y1263167D01*
X769900Y1262333D01*
X769083Y1261833D01*
X766167D01*
G01X769083D02*
X770833Y1257000D01*
G01X776600Y1267000D02*
X779400D01*
G01X778000D02*
Y1257000D01*
G01X776600D02*
X779400D01*
G01X785167D02*
Y1267000D01*
X787967D01*
X788900Y1266500D01*
X789600Y1265333D01*
X789833Y1264000D01*
X789600Y1262667D01*
X789017Y1261667D01*
X787967Y1261166D01*
X785167D01*
G01X797000Y1267000D02*
Y1257000D01*
G01X794317Y1267000D02*
X799683D01*
G01X805100D02*
X807900D01*
G01X806500D02*
Y1257000D01*
G01X805100D02*
X807900D01*
G01X816000D02*
X815067Y1257167D01*
X814250Y1257833D01*
X813550Y1258833D01*
X813083Y1260000D01*
X812850Y1261333D01*
Y1262667D01*
X813083Y1264000D01*
X813550Y1265167D01*
X814250Y1266167D01*
X815067Y1266833D01*
X816000Y1267000D01*
X816933Y1266833D01*
X817750Y1266167D01*
X818450Y1265167D01*
X818917Y1264000D01*
X819150Y1262667D01*
Y1261333D01*
X818917Y1260000D01*
X818450Y1258833D01*
X817750Y1257833D01*
X816933Y1257167D01*
X816000Y1257000D01*
G01X822817D02*
Y1267000D01*
X828183Y1257000D01*
Y1267000D01*
G01X816250Y-590000D02*
X815317Y-590333D01*
X814617Y-591167D01*
X814150Y-592167D01*
X813800Y-593500D01*
X813683Y-595000D01*
X813800Y-596500D01*
X814150Y-597833D01*
X814617Y-598834D01*
X815317Y-599667D01*
X816250Y-600000D01*
X817183Y-599667D01*
X817883Y-598834D01*
X818350Y-597833D01*
X818700Y-596500D01*
X818817Y-595000D01*
X818700Y-593500D01*
X818350Y-592167D01*
X817883Y-591167D01*
X817183Y-590333D01*
X816250Y-590000D01*
G01X823533Y-591667D02*
X824233Y-590667D01*
X825050Y-590167D01*
X825983Y-590000D01*
X827150Y-590333D01*
X827967Y-591167D01*
X828200Y-592167D01*
X828083Y-593167D01*
X827617Y-594000D01*
X825283Y-595667D01*
X824233Y-596833D01*
X823533Y-598500D01*
X823300Y-600000D01*
X828200D01*
G01X833150Y-600333D02*
X837350Y-590000D01*
G01X844750Y-600000D02*
Y-590000D01*
X843350Y-592000D01*
G01Y-600000D02*
X846150D01*
G01X854250D02*
Y-590000D01*
X852850Y-592000D01*
G01Y-600000D02*
X855650D01*
G01X861650Y-600333D02*
X865850Y-590000D01*
G01X873250Y-600000D02*
Y-590000D01*
X871850Y-592000D01*
G01Y-600000D02*
X874650D01*
G01X884150D02*
Y-590000D01*
X879833Y-597167D01*
X885667D01*
G01X831183Y-570000D02*
Y-560000D01*
X833517D01*
X834450Y-560500D01*
X835150Y-561167D01*
X835733Y-562167D01*
X836200Y-563334D01*
X836317Y-565000D01*
X836200Y-566667D01*
X835733Y-567833D01*
X835150Y-568834D01*
X834450Y-569500D01*
X833517Y-570000D01*
X831183D01*
G01X840333D02*
X843250Y-560000D01*
X846167Y-570000D01*
G01X845117Y-566500D02*
X841383D01*
G01X852750Y-560000D02*
Y-570000D01*
G01X850067Y-560000D02*
X855433D01*
G01X864583Y-570000D02*
X859917D01*
Y-560000D01*
X864583D01*
G01X862717Y-564833D02*
X859917D01*
G01X896050Y-788667D02*
X896983Y-789500D01*
X898033Y-790000D01*
X898967D01*
X899900Y-789500D01*
X900600Y-788667D01*
X900950Y-787500D01*
X900717Y-786334D01*
X900133Y-785333D01*
X899083Y-784667D01*
X897683Y-784333D01*
X896867Y-783667D01*
X896517Y-782500D01*
X896750Y-781333D01*
X897333Y-780500D01*
X898150Y-780000D01*
X898967D01*
X899783Y-780333D01*
X900483Y-781167D01*
G01X910567Y-780833D02*
X909867Y-780333D01*
X909050Y-780000D01*
X908117D01*
X907067Y-780500D01*
X906250Y-781333D01*
X905667Y-782333D01*
X905200Y-784000D01*
X905083Y-785500D01*
X905317Y-787000D01*
X905667Y-788000D01*
X906367Y-789000D01*
X907183Y-789667D01*
X908000Y-790000D01*
X908817D01*
X909633Y-789667D01*
X910333Y-789167D01*
X910917Y-788500D01*
G01X914583Y-790000D02*
X917500Y-780000D01*
X920417Y-790000D01*
G01X919367Y-786500D02*
X915633D01*
G01X924667Y-780000D02*
Y-790000D01*
X929333D01*
G01X938833D02*
X934167D01*
Y-780000D01*
X938833D01*
G01X936967Y-784833D02*
X934167D01*
G01X898800Y-733667D02*
X899733Y-734500D01*
X900783Y-735000D01*
X901717D01*
X902650Y-734500D01*
X903350Y-733667D01*
X903700Y-732500D01*
X903467Y-731334D01*
X902883Y-730333D01*
X901833Y-729667D01*
X900433Y-729333D01*
X899617Y-728667D01*
X899267Y-727500D01*
X899500Y-726333D01*
X900083Y-725500D01*
X900900Y-725000D01*
X901717D01*
X902533Y-725333D01*
X903233Y-726167D01*
G01X909350Y-725000D02*
X912150D01*
G01X910750D02*
Y-735000D01*
G01X909350D02*
X912150D01*
G01X918033Y-725000D02*
X922467D01*
X918033Y-735000D01*
X922467D01*
G01X932083D02*
X927417D01*
Y-725000D01*
X932083D01*
G01X930217Y-729833D02*
X927417D01*
G01X903500Y-630000D02*
Y-640000D01*
G01X900817Y-630000D02*
X906183D01*
G01X911600D02*
X914400D01*
G01X913000D02*
Y-640000D01*
G01X911600D02*
X914400D01*
G01X922500Y-630000D02*
Y-640000D01*
G01X919817Y-630000D02*
X925183D01*
G01X929667D02*
Y-640000D01*
X934333D01*
G01X943833D02*
X939167D01*
Y-630000D01*
X943833D01*
G01X941967Y-634833D02*
X939167D01*
G01X930933Y1257000D02*
Y1267000D01*
X933267D01*
X934200Y1266500D01*
X934900Y1265833D01*
X935483Y1264833D01*
X935950Y1263666D01*
X936067Y1262000D01*
X935950Y1260333D01*
X935483Y1259167D01*
X934900Y1258166D01*
X934200Y1257500D01*
X933267Y1257000D01*
X930933D01*
G01X940783D02*
Y1267000D01*
X945217D01*
G01X943583Y1262167D02*
X940783D01*
G01X952500Y1267000D02*
Y1257000D01*
G01X949817Y1267000D02*
X955183D01*
G01X953500Y-790000D02*
Y-780000D01*
X952100Y-782000D01*
G01Y-790000D02*
X954900D01*
G01X963000Y-790333D02*
X962767Y-790167D01*
Y-789833D01*
X963000Y-789667D01*
X963233Y-789833D01*
Y-790167D01*
X963000Y-790333D01*
G01Y-785834D02*
X962767Y-785667D01*
Y-785333D01*
X963000Y-785167D01*
X963233Y-785333D01*
Y-785667D01*
X963000Y-785834D01*
G01X972500Y-790000D02*
Y-780000D01*
X971100Y-782000D01*
G01Y-790000D02*
X973900D01*
G01X948183Y-735000D02*
Y-725000D01*
X950517D01*
X951450Y-725500D01*
X952150Y-726167D01*
X952733Y-727167D01*
X953200Y-728334D01*
X953317Y-730000D01*
X953200Y-731667D01*
X952733Y-732833D01*
X952150Y-733834D01*
X951450Y-734500D01*
X950517Y-735000D01*
X948183D01*
G01X962817Y-725833D02*
X962117Y-725333D01*
X961300Y-725000D01*
X960367D01*
X959317Y-725500D01*
X958500Y-726333D01*
X957917Y-727333D01*
X957450Y-729000D01*
X957333Y-730500D01*
X957567Y-732000D01*
X957917Y-733000D01*
X958617Y-734000D01*
X959433Y-734667D01*
X960250Y-735000D01*
X961067D01*
X961883Y-734667D01*
X962583Y-734167D01*
X963167Y-733500D01*
G01X967417Y-725000D02*
Y-735000D01*
X972083D01*
G01X981817Y-725833D02*
X981117Y-725333D01*
X980300Y-725000D01*
X979367D01*
X978317Y-725500D01*
X977500Y-726333D01*
X976917Y-727333D01*
X976450Y-729000D01*
X976333Y-730500D01*
X976567Y-732000D01*
X976917Y-733000D01*
X977617Y-734000D01*
X978433Y-734667D01*
X979250Y-735000D01*
X980067D01*
X980883Y-734667D01*
X981583Y-734167D01*
X982167Y-733500D01*
G01X971167Y1282520D02*
Y1292520D01*
X974083D01*
X975017Y1292020D01*
X975600Y1291353D01*
X975833Y1290020D01*
X975600Y1288687D01*
X974900Y1287853D01*
X974083Y1287353D01*
X971167D01*
G01X974083D02*
X975833Y1282520D01*
G01X985333D02*
X980667D01*
Y1292520D01*
X985333D01*
G01X983467Y1287687D02*
X980667D01*
G01X989583Y1292520D02*
X992500Y1282520D01*
X995417Y1292520D01*
G01X1000600D02*
X1003400D01*
G01X1002000D02*
Y1282520D01*
G01X1000600D02*
X1003400D01*
G01X1009050Y1283853D02*
X1009983Y1283020D01*
X1011033Y1282520D01*
X1011967D01*
X1012900Y1283020D01*
X1013600Y1283853D01*
X1013950Y1285020D01*
X1013717Y1286186D01*
X1013133Y1287187D01*
X1012083Y1287853D01*
X1010683Y1288187D01*
X1009867Y1288853D01*
X1009517Y1290020D01*
X1009750Y1291187D01*
X1010333Y1292020D01*
X1011150Y1292520D01*
X1011967D01*
X1012783Y1292187D01*
X1013483Y1291353D01*
G01X1019600Y1292520D02*
X1022400D01*
G01X1021000D02*
Y1282520D01*
G01X1019600D02*
X1022400D01*
G01X1030500D02*
X1029567Y1282687D01*
X1028750Y1283353D01*
X1028050Y1284353D01*
X1027583Y1285520D01*
X1027350Y1286853D01*
Y1288187D01*
X1027583Y1289520D01*
X1028050Y1290687D01*
X1028750Y1291687D01*
X1029567Y1292353D01*
X1030500Y1292520D01*
X1031433Y1292353D01*
X1032250Y1291687D01*
X1032950Y1290687D01*
X1033417Y1289520D01*
X1033650Y1288187D01*
Y1286853D01*
X1033417Y1285520D01*
X1032950Y1284353D01*
X1032250Y1283353D01*
X1031433Y1282687D01*
X1030500Y1282520D01*
G01X1037317D02*
Y1292520D01*
X1042683Y1282520D01*
Y1292520D01*
G01X1047050Y1283853D02*
X1047983Y1283020D01*
X1049033Y1282520D01*
X1049967D01*
X1050900Y1283020D01*
X1051600Y1283853D01*
X1051950Y1285020D01*
X1051717Y1286186D01*
X1051133Y1287187D01*
X1050083Y1287853D01*
X1048683Y1288187D01*
X1047867Y1288853D01*
X1047517Y1290020D01*
X1047750Y1291187D01*
X1048333Y1292020D01*
X1049150Y1292520D01*
X1049967D01*
X1050783Y1292187D01*
X1051483Y1291353D01*
G01X1000817Y-725833D02*
X1000117Y-725333D01*
X999300Y-725000D01*
X998367D01*
X997317Y-725500D01*
X996500Y-726333D01*
X995917Y-727333D01*
X995450Y-729000D01*
X995333Y-730500D01*
X995567Y-732000D01*
X995917Y-733000D01*
X996617Y-734000D01*
X997433Y-734667D01*
X998250Y-735000D01*
X999067D01*
X999883Y-734667D01*
X1000583Y-734167D01*
X1001167Y-733500D01*
G01X1005417Y-725000D02*
Y-735000D01*
X1010083D01*
G01X1014333D02*
X1017250Y-725000D01*
X1020167Y-735000D01*
G01X1019117Y-731500D02*
X1015383D01*
G01X1024300Y-733667D02*
X1025233Y-734500D01*
X1026283Y-735000D01*
X1027217D01*
X1028150Y-734500D01*
X1028850Y-733667D01*
X1029200Y-732500D01*
X1028967Y-731334D01*
X1028383Y-730333D01*
X1027333Y-729667D01*
X1025933Y-729333D01*
X1025117Y-728667D01*
X1024767Y-727500D01*
X1025000Y-726333D01*
X1025583Y-725500D01*
X1026400Y-725000D01*
X1027217D01*
X1028033Y-725333D01*
X1028733Y-726167D01*
G01X1033800Y-733667D02*
X1034733Y-734500D01*
X1035783Y-735000D01*
X1036717D01*
X1037650Y-734500D01*
X1038350Y-733667D01*
X1038700Y-732500D01*
X1038467Y-731334D01*
X1037883Y-730333D01*
X1036833Y-729667D01*
X1035433Y-729333D01*
X1034617Y-728667D01*
X1034267Y-727500D01*
X1034500Y-726333D01*
X1035083Y-725500D01*
X1035900Y-725000D01*
X1036717D01*
X1037533Y-725333D01*
X1038233Y-726167D01*
G01X1057817Y-725833D02*
X1057117Y-725333D01*
X1056300Y-725000D01*
X1055367D01*
X1054317Y-725500D01*
X1053500Y-726333D01*
X1052917Y-727333D01*
X1052450Y-729000D01*
X1052333Y-730500D01*
X1052567Y-732000D01*
X1052917Y-733000D01*
X1053617Y-734000D01*
X1054433Y-734667D01*
X1055250Y-735000D01*
X1056067D01*
X1056883Y-734667D01*
X1057583Y-734167D01*
X1058167Y-733500D01*
G01X1064750Y-735000D02*
X1063817Y-734833D01*
X1063000Y-734167D01*
X1062300Y-733167D01*
X1061833Y-732000D01*
X1061600Y-730667D01*
Y-729333D01*
X1061833Y-728000D01*
X1062300Y-726833D01*
X1063000Y-725833D01*
X1063817Y-725167D01*
X1064750Y-725000D01*
X1065683Y-725167D01*
X1066500Y-725833D01*
X1067200Y-726833D01*
X1067667Y-728000D01*
X1067900Y-729333D01*
Y-730667D01*
X1067667Y-732000D01*
X1067200Y-733167D01*
X1066500Y-734167D01*
X1065683Y-734833D01*
X1064750Y-735000D01*
G01X1071683D02*
Y-725000D01*
X1074017D01*
X1074950Y-725500D01*
X1075650Y-726167D01*
X1076233Y-727167D01*
X1076700Y-728334D01*
X1076817Y-730000D01*
X1076700Y-731667D01*
X1076233Y-732833D01*
X1075650Y-733834D01*
X1074950Y-734500D01*
X1074017Y-735000D01*
X1071683D01*
G01X1086083D02*
X1081417D01*
Y-725000D01*
X1086083D01*
G01X1084217Y-729833D02*
X1081417D01*
G01X1007933Y1257000D02*
Y1267000D01*
X1010267D01*
X1011200Y1266500D01*
X1011900Y1265833D01*
X1012483Y1264833D01*
X1012950Y1263666D01*
X1013067Y1262000D01*
X1012950Y1260333D01*
X1012483Y1259167D01*
X1011900Y1258166D01*
X1011200Y1257500D01*
X1010267Y1257000D01*
X1007933D01*
G01X1017083D02*
X1020000Y1267000D01*
X1022917Y1257000D01*
G01X1021867Y1260500D02*
X1018133D01*
G01X1029500Y1267000D02*
Y1257000D01*
G01X1026817Y1267000D02*
X1032183D01*
G01X1041333Y1257000D02*
X1036667D01*
Y1267000D01*
X1041333D01*
G01X1039467Y1262167D02*
X1036667D01*
G01X1033347Y-541390D02*
Y-531390D01*
X1036380Y-539723D01*
X1039413Y-531390D01*
Y-541390D01*
G01X1043430Y-540057D02*
X1044363Y-540890D01*
X1045413Y-541390D01*
X1046347D01*
X1047280Y-540890D01*
X1047980Y-540057D01*
X1048330Y-538890D01*
X1048097Y-537724D01*
X1047513Y-536723D01*
X1046463Y-536057D01*
X1045063Y-535723D01*
X1044247Y-535057D01*
X1043897Y-533890D01*
X1044130Y-532723D01*
X1044713Y-531890D01*
X1045530Y-531390D01*
X1046347D01*
X1047163Y-531723D01*
X1047863Y-532557D01*
G01X1062547Y-541390D02*
Y-531390D01*
X1065347D01*
X1066280Y-531890D01*
X1066980Y-533057D01*
X1067213Y-534390D01*
X1066980Y-535723D01*
X1066397Y-536723D01*
X1065347Y-537224D01*
X1062547D01*
G01X1071813Y-541390D02*
Y-531390D01*
X1074147D01*
X1075080Y-531890D01*
X1075780Y-532557D01*
X1076363Y-533557D01*
X1076830Y-534724D01*
X1076947Y-536390D01*
X1076830Y-538057D01*
X1076363Y-539223D01*
X1075780Y-540224D01*
X1075080Y-540890D01*
X1074147Y-541390D01*
X1071813D01*
G01X1080847D02*
Y-531390D01*
X1083880Y-539723D01*
X1086913Y-531390D01*
Y-541390D01*
G01X1099963Y-531390D02*
X1102880Y-541390D01*
X1105797Y-531390D01*
G01X1114713Y-541390D02*
X1110047D01*
Y-531390D01*
X1114713D01*
G01X1112847Y-536223D02*
X1110047D01*
G01X1119547Y-541390D02*
Y-531390D01*
X1122463D01*
X1123397Y-531890D01*
X1123980Y-532557D01*
X1124213Y-533890D01*
X1123980Y-535223D01*
X1123280Y-536057D01*
X1122463Y-536557D01*
X1119547D01*
G01X1122463D02*
X1124213Y-541390D01*
G01X1131380Y-541723D02*
X1131147Y-541557D01*
Y-541223D01*
X1131380Y-541057D01*
X1131613Y-541223D01*
Y-541557D01*
X1131380Y-541723D01*
G01Y-537224D02*
X1131147Y-537057D01*
Y-536723D01*
X1131380Y-536557D01*
X1131613Y-536723D01*
Y-537057D01*
X1131380Y-537224D01*
G01X1147463Y-541390D02*
X1150380Y-531390D01*
X1153297Y-541390D01*
G01X1152247Y-537890D02*
X1148513D01*
G01X1159880Y-541723D02*
X1159647Y-541557D01*
Y-541223D01*
X1159880Y-541057D01*
X1160113Y-541223D01*
Y-541557D01*
X1159880Y-541723D01*
G01X1169380Y-541390D02*
Y-531390D01*
X1167980Y-533390D01*
G01Y-541390D02*
X1170780D01*
G01X1032467Y-522110D02*
Y-512110D01*
X1035500Y-520443D01*
X1038533Y-512110D01*
Y-522110D01*
G01X1042550Y-520777D02*
X1043483Y-521610D01*
X1044533Y-522110D01*
X1045467D01*
X1046400Y-521610D01*
X1047100Y-520777D01*
X1047450Y-519610D01*
X1047217Y-518444D01*
X1046633Y-517443D01*
X1045583Y-516777D01*
X1044183Y-516443D01*
X1043367Y-515777D01*
X1043017Y-514610D01*
X1043250Y-513443D01*
X1043833Y-512610D01*
X1044650Y-512110D01*
X1045467D01*
X1046283Y-512443D01*
X1046983Y-513277D01*
G01X1061667Y-522110D02*
Y-512110D01*
X1064467D01*
X1065400Y-512610D01*
X1066100Y-513777D01*
X1066333Y-515110D01*
X1066100Y-516443D01*
X1065517Y-517443D01*
X1064467Y-517944D01*
X1061667D01*
G01X1070583Y-522110D02*
X1073500Y-512110D01*
X1076417Y-522110D01*
G01X1075367Y-518610D02*
X1071633D01*
G01X1080667Y-522110D02*
Y-512110D01*
X1083583D01*
X1084517Y-512610D01*
X1085100Y-513277D01*
X1085333Y-514610D01*
X1085100Y-515943D01*
X1084400Y-516777D01*
X1083583Y-517277D01*
X1080667D01*
G01X1083583D02*
X1085333Y-522110D01*
G01X1092500Y-512110D02*
Y-522110D01*
G01X1089817Y-512110D02*
X1095183D01*
G01X1108817Y-522110D02*
Y-512110D01*
X1114183Y-522110D01*
Y-512110D01*
G01X1121000Y-522110D02*
X1120067Y-521943D01*
X1119250Y-521277D01*
X1118550Y-520277D01*
X1118083Y-519110D01*
X1117850Y-517777D01*
Y-516443D01*
X1118083Y-515110D01*
X1118550Y-513943D01*
X1119250Y-512943D01*
X1120067Y-512277D01*
X1121000Y-512110D01*
X1121933Y-512277D01*
X1122750Y-512943D01*
X1123450Y-513943D01*
X1123917Y-515110D01*
X1124150Y-516443D01*
Y-517777D01*
X1123917Y-519110D01*
X1123450Y-520277D01*
X1122750Y-521277D01*
X1121933Y-521943D01*
X1121000Y-522110D01*
G01X1130500Y-522443D02*
X1130267Y-522277D01*
Y-521943D01*
X1130500Y-521777D01*
X1130733Y-521943D01*
Y-522277D01*
X1130500Y-522443D01*
G01Y-517944D02*
X1130267Y-517777D01*
Y-517443D01*
X1130500Y-517277D01*
X1130733Y-517443D01*
Y-517777D01*
X1130500Y-517944D01*
G01X1147050Y-522110D02*
X1151950Y-512110D01*
G01X1147050D02*
X1151950Y-522110D01*
G01X1159000D02*
X1159817Y-521943D01*
X1160750Y-521443D01*
X1161333Y-520610D01*
X1161567Y-519443D01*
X1161333Y-518277D01*
X1160633Y-517277D01*
X1159583Y-516777D01*
X1158417D01*
X1157717Y-516443D01*
X1157133Y-515610D01*
X1156900Y-514443D01*
X1157250Y-513277D01*
X1158067Y-512443D01*
X1159000Y-512110D01*
X1159933Y-512443D01*
X1160750Y-513277D01*
X1161100Y-514443D01*
X1160867Y-515610D01*
X1160283Y-516443D01*
X1159583Y-516777D01*
X1158417D01*
X1157367Y-517277D01*
X1156667Y-518277D01*
X1156433Y-519443D01*
X1156667Y-520610D01*
X1157250Y-521443D01*
X1158183Y-521943D01*
X1159000Y-522110D01*
G01X1168500D02*
X1169317Y-521943D01*
X1170250Y-521443D01*
X1170833Y-520610D01*
X1171067Y-519443D01*
X1170833Y-518277D01*
X1170133Y-517277D01*
X1169083Y-516777D01*
X1167917D01*
X1167217Y-516443D01*
X1166633Y-515610D01*
X1166400Y-514443D01*
X1166750Y-513277D01*
X1167567Y-512443D01*
X1168500Y-512110D01*
X1169433Y-512443D01*
X1170250Y-513277D01*
X1170600Y-514443D01*
X1170367Y-515610D01*
X1169783Y-516443D01*
X1169083Y-516777D01*
X1167917D01*
X1166867Y-517277D01*
X1166167Y-518277D01*
X1165933Y-519443D01*
X1166167Y-520610D01*
X1166750Y-521443D01*
X1167683Y-521943D01*
X1168500Y-522110D01*
G01X1177767D02*
X1178000Y-519943D01*
X1178350Y-518110D01*
X1178817Y-516443D01*
X1179400Y-514610D01*
X1180333Y-512110D01*
X1175667D01*
G01X1184933Y-520610D02*
X1185633Y-521443D01*
X1186450Y-521943D01*
X1187500Y-522110D01*
X1188550Y-521777D01*
X1189367Y-521110D01*
X1189950Y-519943D01*
X1190067Y-518610D01*
X1189833Y-517277D01*
X1189250Y-516443D01*
X1188433Y-515777D01*
X1187617Y-515610D01*
X1186800Y-515777D01*
X1185750Y-516443D01*
X1186100Y-512110D01*
X1189250D01*
G01X1196767Y-522110D02*
X1197000Y-519943D01*
X1197350Y-518110D01*
X1197817Y-516443D01*
X1198400Y-514610D01*
X1199333Y-512110D01*
X1194667D01*
G01X1206500Y-522110D02*
Y-512110D01*
X1205100Y-514110D01*
G01Y-522110D02*
X1207900D01*
G01X1214483Y-518777D02*
X1217517D01*
G01X1225500Y-512110D02*
X1224567Y-512443D01*
X1223867Y-513277D01*
X1223400Y-514277D01*
X1223050Y-515610D01*
X1222933Y-517110D01*
X1223050Y-518610D01*
X1223400Y-519943D01*
X1223867Y-520944D01*
X1224567Y-521777D01*
X1225500Y-522110D01*
X1226433Y-521777D01*
X1227133Y-520944D01*
X1227600Y-519943D01*
X1227950Y-518610D01*
X1228067Y-517110D01*
X1227950Y-515610D01*
X1227600Y-514277D01*
X1227133Y-513277D01*
X1226433Y-512443D01*
X1225500Y-512110D01*
G01X1235000D02*
X1234067Y-512443D01*
X1233367Y-513277D01*
X1232900Y-514277D01*
X1232550Y-515610D01*
X1232433Y-517110D01*
X1232550Y-518610D01*
X1232900Y-519943D01*
X1233367Y-520944D01*
X1234067Y-521777D01*
X1235000Y-522110D01*
X1235933Y-521777D01*
X1236633Y-520944D01*
X1237100Y-519943D01*
X1237450Y-518610D01*
X1237567Y-517110D01*
X1237450Y-515610D01*
X1237100Y-514277D01*
X1236633Y-513277D01*
X1235933Y-512443D01*
X1235000Y-512110D01*
G01X1241933Y-520610D02*
X1242633Y-521443D01*
X1243450Y-521943D01*
X1244500Y-522110D01*
X1245550Y-521777D01*
X1246367Y-521110D01*
X1246950Y-519943D01*
X1247067Y-518610D01*
X1246833Y-517277D01*
X1246250Y-516443D01*
X1245433Y-515777D01*
X1244617Y-515610D01*
X1243800Y-515777D01*
X1242750Y-516443D01*
X1243100Y-512110D01*
X1246250D01*
G01X1100067Y1266167D02*
X1099367Y1266667D01*
X1098550Y1267000D01*
X1097617D01*
X1096567Y1266500D01*
X1095750Y1265667D01*
X1095167Y1264667D01*
X1094700Y1263000D01*
X1094583Y1261500D01*
X1094817Y1260000D01*
X1095167Y1259000D01*
X1095867Y1258000D01*
X1096683Y1257333D01*
X1097500Y1257000D01*
X1098317D01*
X1099133Y1257333D01*
X1099833Y1257833D01*
X1100417Y1258500D01*
G01X1104550Y1257000D02*
Y1267000D01*
G01X1109450D02*
Y1257000D01*
G01Y1262000D02*
X1104550D01*
G01X1113933Y1257000D02*
Y1267000D01*
G01X1118367D02*
X1113933Y1260833D01*
G01X1119067Y1257000D02*
X1115917Y1263666D01*
G01X1108933Y-735000D02*
Y-725000D01*
X1111267D01*
X1112200Y-725500D01*
X1112900Y-726167D01*
X1113483Y-727167D01*
X1113950Y-728334D01*
X1114067Y-730000D01*
X1113950Y-731667D01*
X1113483Y-732833D01*
X1112900Y-733834D01*
X1112200Y-734500D01*
X1111267Y-735000D01*
X1108933D01*
G01X1121000D02*
X1120067Y-734833D01*
X1119250Y-734167D01*
X1118550Y-733167D01*
X1118083Y-732000D01*
X1117850Y-730667D01*
Y-729333D01*
X1118083Y-728000D01*
X1118550Y-726833D01*
X1119250Y-725833D01*
X1120067Y-725167D01*
X1121000Y-725000D01*
X1121933Y-725167D01*
X1122750Y-725833D01*
X1123450Y-726833D01*
X1123917Y-728000D01*
X1124150Y-729333D01*
Y-730667D01*
X1123917Y-732000D01*
X1123450Y-733167D01*
X1122750Y-734167D01*
X1121933Y-734833D01*
X1121000Y-735000D01*
G01X1133067Y-725833D02*
X1132367Y-725333D01*
X1131550Y-725000D01*
X1130617D01*
X1129567Y-725500D01*
X1128750Y-726333D01*
X1128167Y-727333D01*
X1127700Y-729000D01*
X1127583Y-730500D01*
X1127817Y-732000D01*
X1128167Y-733000D01*
X1128867Y-734000D01*
X1129683Y-734667D01*
X1130500Y-735000D01*
X1131317D01*
X1132133Y-734667D01*
X1132833Y-734167D01*
X1133417Y-733500D01*
G01X1137433Y-725000D02*
Y-732167D01*
X1137900Y-733667D01*
X1138833Y-734667D01*
X1140000Y-735000D01*
X1141167Y-734667D01*
X1142100Y-733667D01*
X1142567Y-732167D01*
Y-725000D01*
G01X1146467Y-735000D02*
Y-725000D01*
X1149500Y-733333D01*
X1152533Y-725000D01*
Y-735000D01*
G01X1161333D02*
X1156667D01*
Y-725000D01*
X1161333D01*
G01X1159467Y-729833D02*
X1156667D01*
G01X1165817Y-735000D02*
Y-725000D01*
X1171183Y-735000D01*
Y-725000D01*
G01X1178000D02*
Y-735000D01*
G01X1175317Y-725000D02*
X1180683D01*
G01X1194317Y-735000D02*
Y-725000D01*
X1199683Y-735000D01*
Y-725000D01*
G01X1203933D02*
Y-732167D01*
X1204400Y-733667D01*
X1205333Y-734667D01*
X1206500Y-735000D01*
X1207667Y-734667D01*
X1208600Y-733667D01*
X1209067Y-732167D01*
Y-725000D01*
G01X1212967Y-735000D02*
Y-725000D01*
X1216000Y-733333D01*
X1219033Y-725000D01*
Y-735000D01*
G01X1226433Y-729667D02*
X1226900Y-729167D01*
X1227250Y-728334D01*
X1227483Y-727167D01*
X1227250Y-726167D01*
X1226783Y-725500D01*
X1225967Y-725000D01*
X1222817D01*
Y-735000D01*
X1226667D01*
X1227483Y-734333D01*
X1227950Y-733333D01*
X1228183Y-732167D01*
X1227950Y-731000D01*
X1227250Y-730000D01*
X1226433Y-729667D01*
X1222817D01*
G01X1237333Y-735000D02*
X1232667D01*
Y-725000D01*
X1237333D01*
G01X1235467Y-729833D02*
X1232667D01*
G01X1242167Y-735000D02*
Y-725000D01*
X1245083D01*
X1246017Y-725500D01*
X1246600Y-726167D01*
X1246833Y-727500D01*
X1246600Y-728833D01*
X1245900Y-729667D01*
X1245083Y-730167D01*
X1242167D01*
G01X1245083D02*
X1246833Y-735000D01*
G01X1180933Y1257000D02*
Y1267000D01*
X1183267D01*
X1184200Y1266500D01*
X1184900Y1265833D01*
X1185483Y1264833D01*
X1185950Y1263666D01*
X1186067Y1262000D01*
X1185950Y1260333D01*
X1185483Y1259167D01*
X1184900Y1258166D01*
X1184200Y1257500D01*
X1183267Y1257000D01*
X1180933D01*
G01X1190083D02*
X1193000Y1267000D01*
X1195917Y1257000D01*
G01X1194867Y1260500D02*
X1191133D01*
G01X1202500Y1267000D02*
Y1257000D01*
G01X1199817Y1267000D02*
X1205183D01*
G01X1214333Y1257000D02*
X1209667D01*
Y1267000D01*
X1214333D01*
G01X1212467Y1262167D02*
X1209667D01*
G01X1215000Y-600000D02*
X1216633Y-610000D01*
X1218500Y-600000D01*
X1220367Y-610000D01*
X1222000Y-600000D01*
G01X1225083Y-610000D02*
X1228000Y-600000D01*
X1230917Y-610000D01*
G01X1229867Y-606500D02*
X1226133D01*
G01X1235050Y-608667D02*
X1235983Y-609500D01*
X1237033Y-610000D01*
X1237967D01*
X1238900Y-609500D01*
X1239600Y-608667D01*
X1239950Y-607500D01*
X1239717Y-606334D01*
X1239133Y-605333D01*
X1238083Y-604667D01*
X1236683Y-604333D01*
X1235867Y-603667D01*
X1235517Y-602500D01*
X1235750Y-601333D01*
X1236333Y-600500D01*
X1237150Y-600000D01*
X1237967D01*
X1238783Y-600333D01*
X1239483Y-601167D01*
G01X1244550Y-610000D02*
Y-600000D01*
G01X1249450D02*
Y-610000D01*
G01Y-605000D02*
X1244550D01*
G01X1273517Y-608834D02*
X1274333Y-609667D01*
X1275267Y-610000D01*
X1276200Y-609667D01*
X1277017Y-608667D01*
X1277600Y-607167D01*
X1277833Y-605667D01*
Y-603833D01*
X1277600Y-602333D01*
X1277017Y-601000D01*
X1276317Y-600333D01*
X1275500Y-600000D01*
X1274567Y-600333D01*
X1273867Y-601000D01*
X1273400Y-602000D01*
X1273167Y-603334D01*
X1273400Y-604500D01*
X1273983Y-605667D01*
X1274683Y-606334D01*
X1275500Y-606500D01*
X1276433Y-606167D01*
X1277133Y-605333D01*
X1277833Y-603833D01*
G01X1285000Y-610000D02*
X1285817Y-609833D01*
X1286750Y-609333D01*
X1287333Y-608500D01*
X1287567Y-607333D01*
X1287333Y-606167D01*
X1286633Y-605167D01*
X1285583Y-604667D01*
X1284417D01*
X1283717Y-604333D01*
X1283133Y-603500D01*
X1282900Y-602333D01*
X1283250Y-601167D01*
X1284067Y-600333D01*
X1285000Y-600000D01*
X1285933Y-600333D01*
X1286750Y-601167D01*
X1287100Y-602333D01*
X1286867Y-603500D01*
X1286283Y-604333D01*
X1285583Y-604667D01*
X1284417D01*
X1283367Y-605167D01*
X1282667Y-606167D01*
X1282433Y-607333D01*
X1282667Y-608500D01*
X1283250Y-609333D01*
X1284183Y-609833D01*
X1285000Y-610000D01*
G01X1294500Y-600000D02*
X1293567Y-600333D01*
X1292867Y-601167D01*
X1292400Y-602167D01*
X1292050Y-603500D01*
X1291933Y-605000D01*
X1292050Y-606500D01*
X1292400Y-607833D01*
X1292867Y-608834D01*
X1293567Y-609667D01*
X1294500Y-610000D01*
X1295433Y-609667D01*
X1296133Y-608834D01*
X1296600Y-607833D01*
X1296950Y-606500D01*
X1297067Y-605000D01*
X1296950Y-603500D01*
X1296600Y-602167D01*
X1296133Y-601167D01*
X1295433Y-600333D01*
X1294500Y-600000D01*
G01X1301433Y-608500D02*
X1302133Y-609333D01*
X1302950Y-609833D01*
X1304000Y-610000D01*
X1305050Y-609667D01*
X1305867Y-609000D01*
X1306450Y-607833D01*
X1306567Y-606500D01*
X1306333Y-605167D01*
X1305750Y-604333D01*
X1304933Y-603667D01*
X1304117Y-603500D01*
X1303300Y-603667D01*
X1302250Y-604333D01*
X1302600Y-600000D01*
X1305750D01*
G01X1311283Y-601667D02*
X1311983Y-600667D01*
X1312800Y-600167D01*
X1313733Y-600000D01*
X1314900Y-600333D01*
X1315717Y-601167D01*
X1315950Y-602167D01*
X1315833Y-603167D01*
X1315367Y-604000D01*
X1313033Y-605667D01*
X1311983Y-606833D01*
X1311283Y-608500D01*
X1311050Y-610000D01*
X1315950D01*
G01X1321483Y-606667D02*
X1324517D01*
G01X1330283Y-605834D02*
X1331100Y-604667D01*
X1331800Y-604000D01*
X1332733Y-603667D01*
X1333550Y-604000D01*
X1334133Y-604667D01*
X1334600Y-605667D01*
X1334717Y-606833D01*
X1334600Y-607833D01*
X1334133Y-608834D01*
X1333433Y-609667D01*
X1332617Y-610000D01*
X1331683Y-609667D01*
X1330867Y-608667D01*
X1330400Y-607167D01*
X1330283Y-605500D01*
X1330517Y-603334D01*
X1330867Y-602167D01*
X1331450Y-601000D01*
X1332267Y-600167D01*
X1333083Y-600000D01*
X1333900Y-600333D01*
X1334483Y-601167D01*
G01X1339433Y-608000D02*
X1340133Y-609167D01*
X1341067Y-609833D01*
X1342117Y-610000D01*
X1343050Y-609833D01*
X1343983Y-609000D01*
X1344567Y-608000D01*
X1344683Y-607000D01*
X1344450Y-605834D01*
X1343633Y-605000D01*
X1342817Y-604667D01*
X1341767D01*
G01X1342817D02*
X1343517Y-604167D01*
X1344100Y-603334D01*
X1344333Y-602333D01*
X1344100Y-601333D01*
X1343517Y-600500D01*
X1342467Y-600000D01*
X1341417Y-600167D01*
X1340367Y-600833D01*
G01X1349517Y-608834D02*
X1350333Y-609667D01*
X1351267Y-610000D01*
X1352200Y-609667D01*
X1353017Y-608667D01*
X1353600Y-607167D01*
X1353833Y-605667D01*
Y-603833D01*
X1353600Y-602333D01*
X1353017Y-601000D01*
X1352317Y-600333D01*
X1351500Y-600000D01*
X1350567Y-600333D01*
X1349867Y-601000D01*
X1349400Y-602000D01*
X1349167Y-603334D01*
X1349400Y-604500D01*
X1349983Y-605667D01*
X1350683Y-606334D01*
X1351500Y-606500D01*
X1352433Y-606167D01*
X1353133Y-605333D01*
X1353833Y-603833D01*
G01X1359017Y-608834D02*
X1359833Y-609667D01*
X1360767Y-610000D01*
X1361700Y-609667D01*
X1362517Y-608667D01*
X1363100Y-607167D01*
X1363333Y-605667D01*
Y-603833D01*
X1363100Y-602333D01*
X1362517Y-601000D01*
X1361817Y-600333D01*
X1361000Y-600000D01*
X1360067Y-600333D01*
X1359367Y-601000D01*
X1358900Y-602000D01*
X1358667Y-603334D01*
X1358900Y-604500D01*
X1359483Y-605667D01*
X1360183Y-606334D01*
X1361000Y-606500D01*
X1361933Y-606167D01*
X1362633Y-605333D01*
X1363333Y-603833D01*
G01X1216167Y-590000D02*
Y-580000D01*
X1219083D01*
X1220017Y-580500D01*
X1220600Y-581167D01*
X1220833Y-582500D01*
X1220600Y-583833D01*
X1219900Y-584667D01*
X1219083Y-585167D01*
X1216167D01*
G01X1219083D02*
X1220833Y-590000D01*
G01X1230333D02*
X1225667D01*
Y-580000D01*
X1230333D01*
G01X1228467Y-584833D02*
X1225667D01*
G01X1234933Y-590000D02*
Y-580000D01*
X1237267D01*
X1238200Y-580500D01*
X1238900Y-581167D01*
X1239483Y-582167D01*
X1239950Y-583334D01*
X1240067Y-585000D01*
X1239950Y-586667D01*
X1239483Y-587833D01*
X1238900Y-588834D01*
X1238200Y-589500D01*
X1237267Y-590000D01*
X1234933D01*
G01X1243967D02*
Y-580000D01*
X1247000Y-588333D01*
X1250033Y-580000D01*
Y-590000D01*
G01X1256500D02*
X1255567Y-589833D01*
X1254750Y-589167D01*
X1254050Y-588167D01*
X1253583Y-587000D01*
X1253350Y-585667D01*
Y-584333D01*
X1253583Y-583000D01*
X1254050Y-581833D01*
X1254750Y-580833D01*
X1255567Y-580167D01*
X1256500Y-580000D01*
X1257433Y-580167D01*
X1258250Y-580833D01*
X1258950Y-581833D01*
X1259417Y-583000D01*
X1259650Y-584333D01*
Y-585667D01*
X1259417Y-587000D01*
X1258950Y-588167D01*
X1258250Y-589167D01*
X1257433Y-589833D01*
X1256500Y-590000D01*
G01X1263317D02*
Y-580000D01*
X1268683Y-590000D01*
Y-580000D01*
G01X1272933Y-590000D02*
Y-580000D01*
X1275267D01*
X1276200Y-580500D01*
X1276900Y-581167D01*
X1277483Y-582167D01*
X1277950Y-583334D01*
X1278067Y-585000D01*
X1277950Y-586667D01*
X1277483Y-587833D01*
X1276900Y-588834D01*
X1276200Y-589500D01*
X1275267Y-590000D01*
X1272933D01*
G01X1218500Y-570000D02*
Y-560000D01*
X1217100Y-562000D01*
G01Y-570000D02*
X1219900D01*
G01X1234467D02*
Y-560000D01*
X1237500Y-568333D01*
X1240533Y-560000D01*
Y-570000D01*
G01X1245600Y-560000D02*
X1248400D01*
G01X1247000D02*
Y-570000D01*
G01X1245600D02*
X1248400D01*
G01X1259067Y-560833D02*
X1258367Y-560333D01*
X1257550Y-560000D01*
X1256617D01*
X1255567Y-560500D01*
X1254750Y-561333D01*
X1254167Y-562333D01*
X1253700Y-564000D01*
X1253583Y-565500D01*
X1253817Y-567000D01*
X1254167Y-568000D01*
X1254867Y-569000D01*
X1255683Y-569667D01*
X1256500Y-570000D01*
X1257317D01*
X1258133Y-569667D01*
X1258833Y-569167D01*
X1259417Y-568500D01*
G01X1263667Y-570000D02*
Y-560000D01*
X1266583D01*
X1267517Y-560500D01*
X1268100Y-561167D01*
X1268333Y-562500D01*
X1268100Y-563833D01*
X1267400Y-564667D01*
X1266583Y-565167D01*
X1263667D01*
G01X1266583D02*
X1268333Y-570000D01*
G01X1275500D02*
X1274567Y-569833D01*
X1273750Y-569167D01*
X1273050Y-568167D01*
X1272583Y-567000D01*
X1272350Y-565667D01*
Y-564333D01*
X1272583Y-563000D01*
X1273050Y-561833D01*
X1273750Y-560833D01*
X1274567Y-560167D01*
X1275500Y-560000D01*
X1276433Y-560167D01*
X1277250Y-560833D01*
X1277950Y-561833D01*
X1278417Y-563000D01*
X1278650Y-564333D01*
Y-565667D01*
X1278417Y-567000D01*
X1277950Y-568167D01*
X1277250Y-569167D01*
X1276433Y-569833D01*
X1275500Y-570000D01*
G01X1282550Y-568667D02*
X1283483Y-569500D01*
X1284533Y-570000D01*
X1285467D01*
X1286400Y-569500D01*
X1287100Y-568667D01*
X1287450Y-567500D01*
X1287217Y-566334D01*
X1286633Y-565333D01*
X1285583Y-564667D01*
X1284183Y-564333D01*
X1283367Y-563667D01*
X1283017Y-562500D01*
X1283250Y-561333D01*
X1283833Y-560500D01*
X1284650Y-560000D01*
X1285467D01*
X1286283Y-560333D01*
X1286983Y-561167D01*
G01X1294500Y-570000D02*
X1293567Y-569833D01*
X1292750Y-569167D01*
X1292050Y-568167D01*
X1291583Y-567000D01*
X1291350Y-565667D01*
Y-564333D01*
X1291583Y-563000D01*
X1292050Y-561833D01*
X1292750Y-560833D01*
X1293567Y-560167D01*
X1294500Y-560000D01*
X1295433Y-560167D01*
X1296250Y-560833D01*
X1296950Y-561833D01*
X1297417Y-563000D01*
X1297650Y-564333D01*
Y-565667D01*
X1297417Y-567000D01*
X1296950Y-568167D01*
X1296250Y-569167D01*
X1295433Y-569833D01*
X1294500Y-570000D01*
G01X1301783D02*
Y-560000D01*
X1306217D01*
G01X1304583Y-564833D02*
X1301783D01*
G01X1313500Y-560000D02*
Y-570000D01*
G01X1310817Y-560000D02*
X1316183D01*
G01X1329000D02*
X1330633Y-570000D01*
X1332500Y-560000D01*
X1334367Y-570000D01*
X1336000Y-560000D01*
G01X1339083Y-570000D02*
X1342000Y-560000D01*
X1344917Y-570000D01*
G01X1343867Y-566500D02*
X1340133D01*
G01X1351500Y-570000D02*
Y-565500D01*
X1349167Y-560000D01*
G01X1353833D02*
X1351500Y-565500D01*
G01X1233050Y-788667D02*
X1233983Y-789500D01*
X1235033Y-790000D01*
X1235967D01*
X1236900Y-789500D01*
X1237600Y-788667D01*
X1237950Y-787500D01*
X1237717Y-786334D01*
X1237133Y-785333D01*
X1236083Y-784667D01*
X1234683Y-784333D01*
X1233867Y-783667D01*
X1233517Y-782500D01*
X1233750Y-781333D01*
X1234333Y-780500D01*
X1235150Y-780000D01*
X1235967D01*
X1236783Y-780333D01*
X1237483Y-781167D01*
G01X1242550Y-790000D02*
Y-780000D01*
G01X1247450D02*
Y-790000D01*
G01Y-785000D02*
X1242550D01*
G01X1256833Y-790000D02*
X1252167D01*
Y-780000D01*
X1256833D01*
G01X1254967Y-784833D02*
X1252167D01*
G01X1266333Y-790000D02*
X1261667D01*
Y-780000D01*
X1266333D01*
G01X1264467Y-784833D02*
X1261667D01*
G01X1273500Y-780000D02*
Y-790000D01*
G01X1270817Y-780000D02*
X1276183D01*
G01X1253753Y1256640D02*
X1256670Y1266640D01*
X1259587Y1256640D01*
G01X1258537Y1260140D02*
X1254803D01*
G01X1263837Y1256640D02*
Y1266640D01*
X1266637D01*
X1267570Y1266140D01*
X1268270Y1264973D01*
X1268503Y1263640D01*
X1268270Y1262307D01*
X1267687Y1261307D01*
X1266637Y1260806D01*
X1263837D01*
G01X1272753Y1266640D02*
X1275670Y1256640D01*
X1278587Y1266640D01*
G01X1282603Y1256640D02*
Y1266640D01*
X1284937D01*
X1285870Y1266140D01*
X1286570Y1265473D01*
X1287153Y1264473D01*
X1287620Y1263306D01*
X1287737Y1261640D01*
X1287620Y1259973D01*
X1287153Y1258807D01*
X1286570Y1257806D01*
X1285870Y1257140D01*
X1284937Y1256640D01*
X1282603D01*
G01X1333500Y-790000D02*
X1332567Y-789833D01*
X1331750Y-789167D01*
X1331050Y-788167D01*
X1330583Y-787000D01*
X1330350Y-785667D01*
Y-784333D01*
X1330583Y-783000D01*
X1331050Y-781833D01*
X1331750Y-780833D01*
X1332567Y-780167D01*
X1333500Y-780000D01*
X1334433Y-780167D01*
X1335250Y-780833D01*
X1335950Y-781833D01*
X1336417Y-783000D01*
X1336650Y-784333D01*
Y-785667D01*
X1336417Y-787000D01*
X1335950Y-788167D01*
X1335250Y-789167D01*
X1334433Y-789833D01*
X1333500Y-790000D01*
G01X1340783D02*
Y-780000D01*
X1345217D01*
G01X1343583Y-784833D02*
X1340783D01*
G01X1342343Y1257090D02*
Y1267090D01*
X1344677D01*
X1345610Y1266590D01*
X1346310Y1265923D01*
X1346893Y1264923D01*
X1347360Y1263756D01*
X1347477Y1262090D01*
X1347360Y1260423D01*
X1346893Y1259257D01*
X1346310Y1258256D01*
X1345610Y1257590D01*
X1344677Y1257090D01*
X1342343D01*
G01X1351493D02*
X1354410Y1267090D01*
X1357327Y1257090D01*
G01X1356277Y1260590D02*
X1352543D01*
G01X1363910Y1267090D02*
Y1257090D01*
G01X1361227Y1267090D02*
X1366593D01*
G01X1375743Y1257090D02*
X1371077D01*
Y1267090D01*
X1375743D01*
G01X1373877Y1262257D02*
X1371077D01*
G01X1366167Y-735000D02*
Y-725000D01*
X1369083D01*
X1370017Y-725500D01*
X1370600Y-726167D01*
X1370833Y-727500D01*
X1370600Y-728833D01*
X1369900Y-729667D01*
X1369083Y-730167D01*
X1366167D01*
G01X1369083D02*
X1370833Y-735000D01*
G01X1380333D02*
X1375667D01*
Y-725000D01*
X1380333D01*
G01X1378467Y-729833D02*
X1375667D01*
G01X1384583Y-725000D02*
X1387500Y-735000D01*
X1390417Y-725000D01*
G54D20*
G01X-1701000Y-282500D02*
X-1671000D01*
Y-252500D01*
X-1701000D01*
Y-282500D01*
G01Y-97500D02*
X-1671000D01*
Y-67500D01*
X-1701000D01*
Y-97500D01*
G01Y502500D02*
X-1671000D01*
Y532500D01*
X-1701000D01*
Y502500D01*
G01X-1693500Y637500D02*
X-1663500D01*
Y667500D01*
X-1693500D01*
Y637500D01*
G01Y837500D02*
X-1663500D01*
Y867500D01*
X-1693500D01*
Y837500D01*
G01Y1007500D02*
X-1663500D01*
Y1037500D01*
X-1693500D01*
Y1007500D01*
G01X510000Y-775000D02*
X390000D01*
G01X510000Y-747480D02*
X390000D01*
G01X507520Y-715000D02*
X387520D01*
G01X510000Y-685000D02*
X390000D01*
G01X580000Y-625000D02*
X390000D01*
G54D11*
G01X911867Y-760000D02*
Y-740000D01*
X916533D01*
X918400Y-741000D01*
X919800Y-742333D01*
X920967Y-744333D01*
X921900Y-746667D01*
X922133Y-750000D01*
X921900Y-753334D01*
X920967Y-755667D01*
X919800Y-757667D01*
X918400Y-759000D01*
X916533Y-760000D01*
X911867D01*
G01X1166100Y-762000D02*
X1175900Y-742000D01*
G01X1166100D02*
X1175900Y-762000D01*
G01X1190000D02*
X1191633Y-761667D01*
X1193500Y-760667D01*
X1194667Y-759001D01*
X1195133Y-756667D01*
X1194667Y-754334D01*
X1193267Y-752334D01*
X1191167Y-751333D01*
X1188833D01*
X1187433Y-750667D01*
X1186266Y-749000D01*
X1185800Y-746667D01*
X1186500Y-744333D01*
X1188133Y-742667D01*
X1190000Y-742000D01*
X1191866Y-742667D01*
X1193500Y-744333D01*
X1194200Y-746667D01*
X1193733Y-749000D01*
X1192567Y-750667D01*
X1191167Y-751333D01*
X1188833D01*
X1186733Y-752334D01*
X1185333Y-754334D01*
X1184867Y-756667D01*
X1185333Y-759001D01*
X1186500Y-760667D01*
X1188367Y-761667D01*
X1190000Y-762000D01*
G01X1209000D02*
X1210633Y-761667D01*
X1212500Y-760667D01*
X1213667Y-759001D01*
X1214133Y-756667D01*
X1213667Y-754334D01*
X1212267Y-752334D01*
X1210167Y-751333D01*
X1207833D01*
X1206433Y-750667D01*
X1205266Y-749000D01*
X1204800Y-746667D01*
X1205500Y-744333D01*
X1207133Y-742667D01*
X1209000Y-742000D01*
X1210866Y-742667D01*
X1212500Y-744333D01*
X1213200Y-746667D01*
X1212733Y-749000D01*
X1211567Y-750667D01*
X1210167Y-751333D01*
X1207833D01*
X1205733Y-752334D01*
X1204333Y-754334D01*
X1203867Y-756667D01*
X1204333Y-759001D01*
X1205500Y-760667D01*
X1207367Y-761667D01*
X1209000Y-762000D01*
G01X1227533D02*
X1228000Y-757667D01*
X1228700Y-754000D01*
X1229633Y-750667D01*
X1230800Y-747000D01*
X1232667Y-742000D01*
X1223333D01*
G01X1241867Y-759001D02*
X1243266Y-760667D01*
X1244900Y-761667D01*
X1247000Y-762000D01*
X1249100Y-761333D01*
X1250733Y-760000D01*
X1251900Y-757667D01*
X1252133Y-755000D01*
X1251667Y-752334D01*
X1250500Y-750667D01*
X1248866Y-749334D01*
X1247234Y-749000D01*
X1245600Y-749334D01*
X1243500Y-750667D01*
X1244200Y-742000D01*
X1250500D01*
G01X1265533Y-762000D02*
X1266000Y-757667D01*
X1266700Y-754000D01*
X1267633Y-750667D01*
X1268800Y-747000D01*
X1270667Y-742000D01*
X1261333D01*
G01X1285000Y-762000D02*
Y-742000D01*
X1282200Y-746000D01*
G01Y-762000D02*
X1287800D01*
G01X1376866Y-749333D02*
X1377800Y-748333D01*
X1378500Y-746667D01*
X1378967Y-744333D01*
X1378500Y-742333D01*
X1377567Y-741000D01*
X1375933Y-740000D01*
X1369633D01*
Y-760000D01*
X1377333D01*
X1378967Y-758667D01*
X1379900Y-756667D01*
X1380367Y-754333D01*
X1379900Y-752000D01*
X1378500Y-750000D01*
X1376866Y-749333D01*
X1369633D01*
G54D12*
G01X1178490Y-581900D02*
G03I-3990J0D01*
G01X1173300Y-584000D02*
Y-579800D01*
X1175100D01*
G01X1174800D02*
G02X1175550Y-580550I0J-750D01*
G01Y-580850D01*
G02X1174650Y-581750I-900J0D01*
G01X1174050D01*
G01X1174950Y-581900D02*
X1175700Y-584000D01*
G54D13*
G01X1399400Y1189220D02*
X594400D01*
G01X595700Y1220440D02*
Y1190440D01*
G01Y1220440D02*
Y1190440D01*
G01X1400000Y1220000D02*
X595000D01*
G01Y1240000D02*
Y1220000D01*
G01Y1300000D02*
Y1240000D01*
G01X1400000Y1250000D02*
X595000D01*
G01Y1275000D02*
X1400000D01*
G01X650030Y1219710D02*
Y1189710D01*
G01X650000Y1250000D02*
Y1220000D01*
G01Y1275000D02*
Y1250000D01*
G01X889930Y1220380D02*
Y1190380D01*
G01X890000Y1250000D02*
Y1220000D01*
G01Y1275000D02*
Y1250000D01*
G01X990070Y1219230D02*
Y1189230D01*
G01X990000Y1250000D02*
Y1220000D01*
G01Y1275000D02*
Y1250000D01*
G01X1060200Y1219550D02*
Y1189550D01*
G01X1060000Y1250000D02*
Y1220000D01*
G01Y1275000D02*
Y1250000D01*
G01X1160050Y1219900D02*
Y1189900D01*
G01X1160000Y1250000D02*
Y1220000D01*
G01Y1275000D02*
Y1250000D01*
G01X1230050Y1219680D02*
Y1189680D01*
G01X1230000Y1250000D02*
Y1220000D01*
G01Y1275000D02*
Y1250000D01*
G01X1312340Y1219780D02*
Y1189780D01*
G01X1312270Y1249550D02*
Y1219550D01*
G01Y1274550D02*
Y1249550D01*
G54D14*
G01X-1900000Y250000D02*
X-1910000Y255000D01*
Y245000D01*
X-1900000Y250000D01*
G01Y-800000D02*
X1400000D01*
Y1300000D01*
X-1900000D01*
Y-800000D01*
G01X-1670000Y1300000D02*
Y1205000D01*
X-1900000D01*
G01X-200000Y-800000D02*
X-205000Y-810000D01*
X-195000D01*
X-200000Y-800000D01*
G01Y1300000D02*
X-195000Y1310000D01*
X-205000D01*
X-200000Y1300000D01*
G01X1400000Y250000D02*
X1410000Y245000D01*
Y255000D01*
X1400000Y250000D01*
G54D15*
G01X-1900000Y-300000D02*
X-1950000D01*
G01Y250000D02*
X-1900000D01*
G01Y800000D02*
X-1950000D01*
G01X-1770625Y-342500D02*
X-1772375Y-340000D01*
X-1773250Y-337500D01*
Y-327500D01*
X-1772375Y-325000D01*
X-1770625Y-322500D01*
G01X-1759575Y-337500D02*
Y-322500D01*
X-1751525Y-337500D01*
Y-322500D01*
G01X-1744500Y-338000D02*
X-1738200Y-322500D01*
G01X-1731525Y-337500D02*
X-1727150Y-322500D01*
X-1722775Y-337500D01*
G01X-1724350Y-332250D02*
X-1729950D01*
G01X-1712075Y-342500D02*
X-1710325Y-340000D01*
X-1709450Y-337500D01*
Y-327500D01*
X-1710325Y-325000D01*
X-1712075Y-322500D01*
G01X-1763625Y643000D02*
X-1765375Y645500D01*
X-1766250Y648000D01*
Y658000D01*
X-1765375Y660500D01*
X-1763625Y663000D01*
G01X-1752575Y648000D02*
Y663000D01*
X-1744525Y648000D01*
Y663000D01*
G01X-1737500Y647500D02*
X-1731200Y663000D01*
G01X-1724525Y648000D02*
X-1720150Y663000D01*
X-1715775Y648000D01*
G01X-1717350Y653250D02*
X-1722950D01*
G01X-1705075Y643000D02*
X-1703325Y645500D01*
X-1702450Y648000D01*
Y658000D01*
X-1703325Y660500D01*
X-1705075Y663000D01*
G01X-1640125Y-533000D02*
X-1638725Y-534250D01*
X-1637150Y-535000D01*
X-1635750D01*
X-1634350Y-534250D01*
X-1633300Y-533000D01*
X-1632775Y-531250D01*
X-1633125Y-529500D01*
X-1634000Y-528000D01*
X-1635575Y-527000D01*
X-1637675Y-526500D01*
X-1638900Y-525500D01*
X-1639425Y-523750D01*
X-1639075Y-522000D01*
X-1638200Y-520750D01*
X-1636975Y-520000D01*
X-1635750D01*
X-1634525Y-520500D01*
X-1633475Y-521750D01*
G01X-1622250Y-535000D02*
X-1623650Y-534750D01*
X-1624875Y-533750D01*
X-1625925Y-532250D01*
X-1626625Y-530500D01*
X-1626975Y-528500D01*
Y-526500D01*
X-1626625Y-524500D01*
X-1625925Y-522750D01*
X-1624875Y-521250D01*
X-1623650Y-520250D01*
X-1622250Y-520000D01*
X-1620850Y-520250D01*
X-1619625Y-521250D01*
X-1618575Y-522750D01*
X-1617875Y-524500D01*
X-1617525Y-526500D01*
Y-528500D01*
X-1617875Y-530500D01*
X-1618575Y-532250D01*
X-1619625Y-533750D01*
X-1620850Y-534750D01*
X-1622250Y-535000D01*
G01X-1611550Y-520000D02*
Y-535000D01*
X-1604550D01*
G01X-1597700D02*
Y-520000D01*
X-1594200D01*
X-1592800Y-520750D01*
X-1591750Y-521750D01*
X-1590875Y-523250D01*
X-1590175Y-525000D01*
X-1590000Y-527500D01*
X-1590175Y-530000D01*
X-1590875Y-531750D01*
X-1591750Y-533250D01*
X-1592800Y-534250D01*
X-1594200Y-535000D01*
X-1597700D01*
G01X-1576150D02*
X-1583150D01*
Y-520000D01*
X-1576150D01*
G01X-1578950Y-527250D02*
X-1583150D01*
G01X-1568950Y-535000D02*
Y-520000D01*
X-1564575D01*
X-1563175Y-520750D01*
X-1562300Y-521750D01*
X-1561950Y-523750D01*
X-1562300Y-525750D01*
X-1563350Y-527000D01*
X-1564575Y-527750D01*
X-1568950D01*
G01X-1564575D02*
X-1561950Y-535000D01*
G01X-1555800D02*
Y-520000D01*
X-1551250Y-532500D01*
X-1546700Y-520000D01*
Y-535000D01*
G01X-1541425D02*
X-1537050Y-520000D01*
X-1532675Y-535000D01*
G01X-1534250Y-529750D02*
X-1539850D01*
G01X-1526525Y-533000D02*
X-1525125Y-534250D01*
X-1523550Y-535000D01*
X-1522150D01*
X-1520750Y-534250D01*
X-1519700Y-533000D01*
X-1519175Y-531250D01*
X-1519525Y-529500D01*
X-1520400Y-528000D01*
X-1521975Y-527000D01*
X-1524075Y-526500D01*
X-1525300Y-525500D01*
X-1525825Y-523750D01*
X-1525475Y-522000D01*
X-1524600Y-520750D01*
X-1523375Y-520000D01*
X-1522150D01*
X-1520925Y-520500D01*
X-1519875Y-521750D01*
G01X-1512500Y-535000D02*
Y-520000D01*
G01X-1505850D02*
X-1512500Y-529250D01*
G01X-1504800Y-535000D02*
X-1509525Y-525000D01*
G01X-1480250Y-535000D02*
X-1481650Y-534750D01*
X-1482875Y-533750D01*
X-1483925Y-532250D01*
X-1484625Y-530500D01*
X-1484975Y-528500D01*
Y-526500D01*
X-1484625Y-524500D01*
X-1483925Y-522750D01*
X-1482875Y-521250D01*
X-1481650Y-520250D01*
X-1480250Y-520000D01*
X-1478850Y-520250D01*
X-1477625Y-521250D01*
X-1476575Y-522750D01*
X-1475875Y-524500D01*
X-1475525Y-526500D01*
Y-528500D01*
X-1475875Y-530500D01*
X-1476575Y-532250D01*
X-1477625Y-533750D01*
X-1478850Y-534750D01*
X-1480250Y-535000D01*
G01X-1469550D02*
Y-520000D01*
X-1465350D01*
X-1463950Y-520750D01*
X-1462900Y-522500D01*
X-1462550Y-524500D01*
X-1462900Y-526500D01*
X-1463775Y-528000D01*
X-1465350Y-528750D01*
X-1469550D01*
G01X-1448350Y-535000D02*
X-1455350D01*
Y-520000D01*
X-1448350D01*
G01X-1451150Y-527250D02*
X-1455350D01*
G01X-1441675Y-535000D02*
Y-520000D01*
X-1433625Y-535000D01*
Y-520000D01*
G01X-1425550D02*
X-1421350D01*
G01X-1423450D02*
Y-535000D01*
G01X-1425550D02*
X-1421350D01*
G01X-1413275D02*
Y-520000D01*
X-1405225Y-535000D01*
Y-520000D01*
G01X-1394000Y-527500D02*
X-1390500D01*
Y-532000D01*
X-1391550Y-533500D01*
X-1392775Y-534500D01*
X-1394525Y-535000D01*
X-1396275Y-534500D01*
X-1397500Y-533500D01*
X-1398550Y-532000D01*
X-1399250Y-530250D01*
X-1399600Y-528250D01*
Y-526500D01*
X-1399250Y-525000D01*
X-1398550Y-523250D01*
X-1397500Y-521750D01*
X-1396450Y-520750D01*
X-1395050Y-520000D01*
X-1393825D01*
X-1392425Y-520500D01*
X-1391375Y-521500D01*
G01X-1384525Y-533000D02*
X-1383125Y-534250D01*
X-1381550Y-535000D01*
X-1380150D01*
X-1378750Y-534250D01*
X-1377700Y-533000D01*
X-1377175Y-531250D01*
X-1377525Y-529500D01*
X-1378400Y-528000D01*
X-1379975Y-527000D01*
X-1382075Y-526500D01*
X-1383300Y-525500D01*
X-1383825Y-523750D01*
X-1383475Y-522000D01*
X-1382600Y-520750D01*
X-1381375Y-520000D01*
X-1380150D01*
X-1378925Y-520500D01*
X-1377875Y-521750D01*
G01X-1352450Y-535000D02*
X-1353850Y-534750D01*
X-1355075Y-533750D01*
X-1356125Y-532250D01*
X-1356825Y-530500D01*
X-1357175Y-528500D01*
Y-526500D01*
X-1356825Y-524500D01*
X-1356125Y-522750D01*
X-1355075Y-521250D01*
X-1353850Y-520250D01*
X-1352450Y-520000D01*
X-1351050Y-520250D01*
X-1349825Y-521250D01*
X-1348775Y-522750D01*
X-1348075Y-524500D01*
X-1347725Y-526500D01*
Y-528500D01*
X-1348075Y-530500D01*
X-1348775Y-532250D01*
X-1349825Y-533750D01*
X-1351050Y-534750D01*
X-1352450Y-535000D01*
G01X-1342275D02*
Y-520000D01*
X-1334225Y-535000D01*
Y-520000D01*
G01X-1309850D02*
Y-535000D01*
G01X-1313875Y-520000D02*
X-1305825D01*
G01X-1295650Y-535000D02*
X-1297050Y-534750D01*
X-1298275Y-533750D01*
X-1299325Y-532250D01*
X-1300025Y-530500D01*
X-1300375Y-528500D01*
Y-526500D01*
X-1300025Y-524500D01*
X-1299325Y-522750D01*
X-1298275Y-521250D01*
X-1297050Y-520250D01*
X-1295650Y-520000D01*
X-1294250Y-520250D01*
X-1293025Y-521250D01*
X-1291975Y-522750D01*
X-1291275Y-524500D01*
X-1290925Y-526500D01*
Y-528500D01*
X-1291275Y-530500D01*
X-1291975Y-532250D01*
X-1293025Y-533750D01*
X-1294250Y-534750D01*
X-1295650Y-535000D01*
G01X-1284950D02*
Y-520000D01*
X-1280750D01*
X-1279350Y-520750D01*
X-1278300Y-522500D01*
X-1277950Y-524500D01*
X-1278300Y-526500D01*
X-1279175Y-528000D01*
X-1280750Y-528750D01*
X-1284950D01*
G01X-1256725Y-533000D02*
X-1255325Y-534250D01*
X-1253750Y-535000D01*
X-1252350D01*
X-1250950Y-534250D01*
X-1249900Y-533000D01*
X-1249375Y-531250D01*
X-1249725Y-529500D01*
X-1250600Y-528000D01*
X-1252175Y-527000D01*
X-1254275Y-526500D01*
X-1255500Y-525500D01*
X-1256025Y-523750D01*
X-1255675Y-522000D01*
X-1254800Y-520750D01*
X-1253575Y-520000D01*
X-1252350D01*
X-1251125Y-520500D01*
X-1250075Y-521750D01*
G01X-1240950Y-520000D02*
X-1236750D01*
G01X-1238850D02*
Y-535000D01*
G01X-1240950D02*
X-1236750D01*
G01X-1228500D02*
Y-520000D01*
X-1225000D01*
X-1223600Y-520750D01*
X-1222550Y-521750D01*
X-1221675Y-523250D01*
X-1220975Y-525000D01*
X-1220800Y-527500D01*
X-1220975Y-530000D01*
X-1221675Y-531750D01*
X-1222550Y-533250D01*
X-1223600Y-534250D01*
X-1225000Y-535000D01*
X-1228500D01*
G01X-1206950D02*
X-1213950D01*
Y-520000D01*
X-1206950D01*
G01X-1209750Y-527250D02*
X-1213950D01*
G01X-1186425Y-535000D02*
X-1182050Y-520000D01*
X-1177675Y-535000D01*
G01X-1179250Y-529750D02*
X-1184850D01*
G01X-1171350Y-535000D02*
Y-520000D01*
X-1166975D01*
X-1165575Y-520750D01*
X-1164700Y-521750D01*
X-1164350Y-523750D01*
X-1164700Y-525750D01*
X-1165750Y-527000D01*
X-1166975Y-527750D01*
X-1171350D01*
G01X-1166975D02*
X-1164350Y-535000D01*
G01X-1150150D02*
X-1157150D01*
Y-520000D01*
X-1150150D01*
G01X-1152950Y-527250D02*
X-1157150D01*
G01X-1123850Y-527000D02*
X-1123150Y-526250D01*
X-1122625Y-525000D01*
X-1122275Y-523250D01*
X-1122625Y-521750D01*
X-1123325Y-520750D01*
X-1124550Y-520000D01*
X-1129275D01*
Y-535000D01*
X-1123500D01*
X-1122275Y-534000D01*
X-1121575Y-532500D01*
X-1121225Y-530750D01*
X-1121575Y-529000D01*
X-1122625Y-527500D01*
X-1123850Y-527000D01*
X-1129275D01*
G01X-1111050Y-535000D02*
Y-528250D01*
X-1114550Y-520000D01*
G01X-1107550D02*
X-1111050Y-528250D01*
G01X-1086500Y-535000D02*
Y-520000D01*
X-1083000D01*
X-1081600Y-520750D01*
X-1080550Y-521750D01*
X-1079675Y-523250D01*
X-1078975Y-525000D01*
X-1078800Y-527500D01*
X-1078975Y-530000D01*
X-1079675Y-531750D01*
X-1080550Y-533250D01*
X-1081600Y-534250D01*
X-1083000Y-535000D01*
X-1086500D01*
G01X-1064950D02*
X-1071950D01*
Y-520000D01*
X-1064950D01*
G01X-1067750Y-527250D02*
X-1071950D01*
G01X-1057925Y-533000D02*
X-1056525Y-534250D01*
X-1054950Y-535000D01*
X-1053550D01*
X-1052150Y-534250D01*
X-1051100Y-533000D01*
X-1050575Y-531250D01*
X-1050925Y-529500D01*
X-1051800Y-528000D01*
X-1053375Y-527000D01*
X-1055475Y-526500D01*
X-1056700Y-525500D01*
X-1057225Y-523750D01*
X-1056875Y-522000D01*
X-1056000Y-520750D01*
X-1054775Y-520000D01*
X-1053550D01*
X-1052325Y-520500D01*
X-1051275Y-521750D01*
G01X-1042150Y-520000D02*
X-1037950D01*
G01X-1040050D02*
Y-535000D01*
G01X-1042150D02*
X-1037950D01*
G01X-1024800Y-527500D02*
X-1021300D01*
Y-532000D01*
X-1022350Y-533500D01*
X-1023575Y-534500D01*
X-1025325Y-535000D01*
X-1027075Y-534500D01*
X-1028300Y-533500D01*
X-1029350Y-532000D01*
X-1030050Y-530250D01*
X-1030400Y-528250D01*
Y-526500D01*
X-1030050Y-525000D01*
X-1029350Y-523250D01*
X-1028300Y-521750D01*
X-1027250Y-520750D01*
X-1025850Y-520000D01*
X-1024625D01*
X-1023225Y-520500D01*
X-1022175Y-521500D01*
G01X-1015675Y-535000D02*
Y-520000D01*
X-1007625Y-535000D01*
Y-520000D01*
G01X-987625Y-535000D02*
X-983250Y-520000D01*
X-978875Y-535000D01*
G01X-980450Y-529750D02*
X-986050D01*
G01X-973075Y-535000D02*
Y-520000D01*
X-965025Y-535000D01*
Y-520000D01*
G01X-958700Y-535000D02*
Y-520000D01*
X-955200D01*
X-953800Y-520750D01*
X-952750Y-521750D01*
X-951875Y-523250D01*
X-951175Y-525000D01*
X-951000Y-527500D01*
X-951175Y-530000D01*
X-951875Y-531750D01*
X-952750Y-533250D01*
X-953800Y-534250D01*
X-955200Y-535000D01*
X-958700D01*
G01X-929950D02*
Y-520000D01*
X-925575D01*
X-924175Y-520750D01*
X-923300Y-521750D01*
X-922950Y-523750D01*
X-923300Y-525750D01*
X-924350Y-527000D01*
X-925575Y-527750D01*
X-929950D01*
G01X-925575D02*
X-922950Y-535000D01*
G01X-908750D02*
X-915750D01*
Y-520000D01*
X-908750D01*
G01X-911550Y-527250D02*
X-915750D01*
G01X-902600Y-535000D02*
Y-520000D01*
X-898050Y-532500D01*
X-893500Y-520000D01*
Y-535000D01*
G01X-888225D02*
X-883850Y-520000D01*
X-879475Y-535000D01*
G01X-881050Y-529750D02*
X-886650D01*
G01X-871750Y-520000D02*
X-867550D01*
G01X-869650D02*
Y-535000D01*
G01X-871750D02*
X-867550D01*
G01X-859475D02*
Y-520000D01*
X-851425Y-535000D01*
Y-520000D01*
G01X-827050Y-535000D02*
X-828450Y-534750D01*
X-829675Y-533750D01*
X-830725Y-532250D01*
X-831425Y-530500D01*
X-831775Y-528500D01*
Y-526500D01*
X-831425Y-524500D01*
X-830725Y-522750D01*
X-829675Y-521250D01*
X-828450Y-520250D01*
X-827050Y-520000D01*
X-825650Y-520250D01*
X-824425Y-521250D01*
X-823375Y-522750D01*
X-822675Y-524500D01*
X-822325Y-526500D01*
Y-528500D01*
X-822675Y-530500D01*
X-823375Y-532250D01*
X-824425Y-533750D01*
X-825650Y-534750D01*
X-827050Y-535000D01*
G01X-816350D02*
Y-520000D01*
X-812150D01*
X-810750Y-520750D01*
X-809700Y-522500D01*
X-809350Y-524500D01*
X-809700Y-526500D01*
X-810575Y-528000D01*
X-812150Y-528750D01*
X-816350D01*
G01X-795150Y-535000D02*
X-802150D01*
Y-520000D01*
X-795150D01*
G01X-797950Y-527250D02*
X-802150D01*
G01X-788475Y-535000D02*
Y-520000D01*
X-780425Y-535000D01*
Y-520000D01*
G01X-770250Y-535500D02*
X-770600Y-535250D01*
Y-534750D01*
X-770250Y-534500D01*
X-769900Y-534750D01*
Y-535250D01*
X-770250Y-535500D01*
G01X-1696575Y-492500D02*
X-1695525Y-491000D01*
X-1694300Y-490250D01*
X-1692900Y-490000D01*
X-1691150Y-490500D01*
X-1689925Y-491750D01*
X-1689575Y-493250D01*
X-1689750Y-494750D01*
X-1690450Y-496000D01*
X-1693950Y-498500D01*
X-1695525Y-500250D01*
X-1696575Y-502750D01*
X-1696925Y-505000D01*
X-1689575D01*
G01X-1682375Y-492500D02*
X-1681325Y-491000D01*
X-1680100Y-490250D01*
X-1678700Y-490000D01*
X-1676950Y-490500D01*
X-1675725Y-491750D01*
X-1675375Y-493250D01*
X-1675550Y-494750D01*
X-1676250Y-496000D01*
X-1679750Y-498500D01*
X-1681325Y-500250D01*
X-1682375Y-502750D01*
X-1682725Y-505000D01*
X-1675375D01*
G01X-1664850Y-505500D02*
X-1665200Y-505250D01*
Y-504750D01*
X-1664850Y-504500D01*
X-1664500Y-504750D01*
Y-505250D01*
X-1664850Y-505500D01*
G01X-1640825Y-490000D02*
X-1636450Y-505000D01*
X-1632075Y-490000D01*
G01X-1624350D02*
X-1620150D01*
G01X-1622250D02*
Y-505000D01*
G01X-1624350D02*
X-1620150D01*
G01X-1612425D02*
X-1608050Y-490000D01*
X-1603675Y-505000D01*
G01X-1605250Y-499750D02*
X-1610850D01*
G01X-1597525Y-503000D02*
X-1596125Y-504250D01*
X-1594550Y-505000D01*
X-1593150D01*
X-1591750Y-504250D01*
X-1590700Y-503000D01*
X-1590175Y-501250D01*
X-1590525Y-499500D01*
X-1591400Y-498000D01*
X-1592975Y-497000D01*
X-1595075Y-496500D01*
X-1596300Y-495500D01*
X-1596825Y-493750D01*
X-1596475Y-492000D01*
X-1595600Y-490750D01*
X-1594375Y-490000D01*
X-1593150D01*
X-1591925Y-490500D01*
X-1590875Y-491750D01*
G01X-1565450Y-490000D02*
Y-505000D01*
G01X-1569475Y-490000D02*
X-1561425D01*
G01X-1554925Y-505000D02*
Y-490000D01*
G01X-1547575D02*
Y-505000D01*
G01Y-497500D02*
X-1554925D01*
G01X-1541425Y-505000D02*
X-1537050Y-490000D01*
X-1532675Y-505000D01*
G01X-1534250Y-499750D02*
X-1539850D01*
G01X-1522850Y-490000D02*
Y-505000D01*
G01X-1526875Y-490000D02*
X-1518825D01*
G01X-1498825Y-505000D02*
X-1494450Y-490000D01*
X-1490075Y-505000D01*
G01X-1491650Y-499750D02*
X-1497250D01*
G01X-1483750Y-505000D02*
Y-490000D01*
X-1479375D01*
X-1477975Y-490750D01*
X-1477100Y-491750D01*
X-1476750Y-493750D01*
X-1477100Y-495750D01*
X-1478150Y-497000D01*
X-1479375Y-497750D01*
X-1483750D01*
G01X-1479375D02*
X-1476750Y-505000D01*
G01X-1462550D02*
X-1469550D01*
Y-490000D01*
X-1462550D01*
G01X-1465350Y-497250D02*
X-1469550D01*
G01X-1442200Y-505000D02*
Y-490000D01*
X-1437650Y-502500D01*
X-1433100Y-490000D01*
Y-505000D01*
G01X-1427825D02*
X-1423450Y-490000D01*
X-1419075Y-505000D01*
G01X-1420650Y-499750D02*
X-1426250D01*
G01X-1412925Y-503000D02*
X-1411525Y-504250D01*
X-1409950Y-505000D01*
X-1408550D01*
X-1407150Y-504250D01*
X-1406100Y-503000D01*
X-1405575Y-501250D01*
X-1405925Y-499500D01*
X-1406800Y-498000D01*
X-1408375Y-497000D01*
X-1410475Y-496500D01*
X-1411700Y-495500D01*
X-1412225Y-493750D01*
X-1411875Y-492000D01*
X-1411000Y-490750D01*
X-1409775Y-490000D01*
X-1408550D01*
X-1407325Y-490500D01*
X-1406275Y-491750D01*
G01X-1398900Y-505000D02*
Y-490000D01*
G01X-1392250D02*
X-1398900Y-499250D01*
G01X-1391200Y-505000D02*
X-1395925Y-495000D01*
G01X-1377350Y-505000D02*
X-1384350D01*
Y-490000D01*
X-1377350D01*
G01X-1380150Y-497250D02*
X-1384350D01*
G01X-1370500Y-505000D02*
Y-490000D01*
X-1367000D01*
X-1365600Y-490750D01*
X-1364550Y-491750D01*
X-1363675Y-493250D01*
X-1362975Y-495000D01*
X-1362800Y-497500D01*
X-1362975Y-500000D01*
X-1363675Y-501750D01*
X-1364550Y-503250D01*
X-1365600Y-504250D01*
X-1367000Y-505000D01*
X-1370500D01*
G01X-1338250D02*
X-1339650Y-504750D01*
X-1340875Y-503750D01*
X-1341925Y-502250D01*
X-1342625Y-500500D01*
X-1342975Y-498500D01*
Y-496500D01*
X-1342625Y-494500D01*
X-1341925Y-492750D01*
X-1340875Y-491250D01*
X-1339650Y-490250D01*
X-1338250Y-490000D01*
X-1336850Y-490250D01*
X-1335625Y-491250D01*
X-1334575Y-492750D01*
X-1333875Y-494500D01*
X-1333525Y-496500D01*
Y-498500D01*
X-1333875Y-500500D01*
X-1334575Y-502250D01*
X-1335625Y-503750D01*
X-1336850Y-504750D01*
X-1338250Y-505000D01*
G01X-1328425Y-490000D02*
X-1324050Y-505000D01*
X-1319675Y-490000D01*
G01X-1306350Y-505000D02*
X-1313350D01*
Y-490000D01*
X-1306350D01*
G01X-1309150Y-497250D02*
X-1313350D01*
G01X-1299150Y-505000D02*
Y-490000D01*
X-1294775D01*
X-1293375Y-490750D01*
X-1292500Y-491750D01*
X-1292150Y-493750D01*
X-1292500Y-495750D01*
X-1293550Y-497000D01*
X-1294775Y-497750D01*
X-1299150D01*
G01X-1294775D02*
X-1292150Y-505000D01*
G01X-1265850Y-497000D02*
X-1265150Y-496250D01*
X-1264625Y-495000D01*
X-1264275Y-493250D01*
X-1264625Y-491750D01*
X-1265325Y-490750D01*
X-1266550Y-490000D01*
X-1271275D01*
Y-505000D01*
X-1265500D01*
X-1264275Y-504000D01*
X-1263575Y-502500D01*
X-1263225Y-500750D01*
X-1263575Y-499000D01*
X-1264625Y-497500D01*
X-1265850Y-497000D01*
X-1271275D01*
G01X-1253050Y-505000D02*
Y-498250D01*
X-1256550Y-490000D01*
G01X-1249550D02*
X-1253050Y-498250D01*
G01X-1228500Y-505000D02*
Y-490000D01*
X-1225000D01*
X-1223600Y-490750D01*
X-1222550Y-491750D01*
X-1221675Y-493250D01*
X-1220975Y-495000D01*
X-1220800Y-497500D01*
X-1220975Y-500000D01*
X-1221675Y-501750D01*
X-1222550Y-503250D01*
X-1223600Y-504250D01*
X-1225000Y-505000D01*
X-1228500D01*
G01X-1206950D02*
X-1213950D01*
Y-490000D01*
X-1206950D01*
G01X-1209750Y-497250D02*
X-1213950D01*
G01X-1199925Y-503000D02*
X-1198525Y-504250D01*
X-1196950Y-505000D01*
X-1195550D01*
X-1194150Y-504250D01*
X-1193100Y-503000D01*
X-1192575Y-501250D01*
X-1192925Y-499500D01*
X-1193800Y-498000D01*
X-1195375Y-497000D01*
X-1197475Y-496500D01*
X-1198700Y-495500D01*
X-1199225Y-493750D01*
X-1198875Y-492000D01*
X-1198000Y-490750D01*
X-1196775Y-490000D01*
X-1195550D01*
X-1194325Y-490500D01*
X-1193275Y-491750D01*
G01X-1184150Y-490000D02*
X-1179950D01*
G01X-1182050D02*
Y-505000D01*
G01X-1184150D02*
X-1179950D01*
G01X-1166800Y-497500D02*
X-1163300D01*
Y-502000D01*
X-1164350Y-503500D01*
X-1165575Y-504500D01*
X-1167325Y-505000D01*
X-1169075Y-504500D01*
X-1170300Y-503500D01*
X-1171350Y-502000D01*
X-1172050Y-500250D01*
X-1172400Y-498250D01*
Y-496500D01*
X-1172050Y-495000D01*
X-1171350Y-493250D01*
X-1170300Y-491750D01*
X-1169250Y-490750D01*
X-1167850Y-490000D01*
X-1166625D01*
X-1165225Y-490500D01*
X-1164175Y-491500D01*
G01X-1157675Y-505000D02*
Y-490000D01*
X-1149625Y-505000D01*
Y-490000D01*
G01X-1129625Y-505000D02*
X-1125250Y-490000D01*
X-1120875Y-505000D01*
G01X-1122450Y-499750D02*
X-1128050D01*
G01X-1114550Y-505000D02*
Y-490000D01*
X-1110175D01*
X-1108775Y-490750D01*
X-1107900Y-491750D01*
X-1107550Y-493750D01*
X-1107900Y-495750D01*
X-1108950Y-497000D01*
X-1110175Y-497750D01*
X-1114550D01*
G01X-1110175D02*
X-1107550Y-505000D01*
G01X-1093350D02*
X-1100350D01*
Y-490000D01*
X-1093350D01*
G01X-1096150Y-497250D02*
X-1100350D01*
G01X-1071950Y-505000D02*
Y-490000D01*
X-1067750D01*
X-1066350Y-490750D01*
X-1065300Y-492500D01*
X-1064950Y-494500D01*
X-1065300Y-496500D01*
X-1066175Y-498000D01*
X-1067750Y-498750D01*
X-1071950D01*
G01X-1057750Y-490000D02*
Y-505000D01*
X-1050750D01*
G01X-1043900Y-490000D02*
Y-500750D01*
X-1043200Y-503000D01*
X-1041800Y-504500D01*
X-1040050Y-505000D01*
X-1038300Y-504500D01*
X-1036900Y-503000D01*
X-1036200Y-500750D01*
Y-490000D01*
G01X-1024800Y-497500D02*
X-1021300D01*
Y-502000D01*
X-1022350Y-503500D01*
X-1023575Y-504500D01*
X-1025325Y-505000D01*
X-1027075Y-504500D01*
X-1028300Y-503500D01*
X-1029350Y-502000D01*
X-1030050Y-500250D01*
X-1030400Y-498250D01*
Y-496500D01*
X-1030050Y-495000D01*
X-1029350Y-493250D01*
X-1028300Y-491750D01*
X-1027250Y-490750D01*
X-1025850Y-490000D01*
X-1024625D01*
X-1023225Y-490500D01*
X-1022175Y-491500D01*
G01X-1010600Y-497500D02*
X-1007100D01*
Y-502000D01*
X-1008150Y-503500D01*
X-1009375Y-504500D01*
X-1011125Y-505000D01*
X-1012875Y-504500D01*
X-1014100Y-503500D01*
X-1015150Y-502000D01*
X-1015850Y-500250D01*
X-1016200Y-498250D01*
Y-496500D01*
X-1015850Y-495000D01*
X-1015150Y-493250D01*
X-1014100Y-491750D01*
X-1013050Y-490750D01*
X-1011650Y-490000D01*
X-1010425D01*
X-1009025Y-490500D01*
X-1007975Y-491500D01*
G01X-993950Y-505000D02*
X-1000950D01*
Y-490000D01*
X-993950D01*
G01X-996750Y-497250D02*
X-1000950D01*
G01X-987100Y-505000D02*
Y-490000D01*
X-983600D01*
X-982200Y-490750D01*
X-981150Y-491750D01*
X-980275Y-493250D01*
X-979575Y-495000D01*
X-979400Y-497500D01*
X-979575Y-500000D01*
X-980275Y-501750D01*
X-981150Y-503250D01*
X-982200Y-504250D01*
X-983600Y-505000D01*
X-987100D01*
G01X-969400Y-507750D02*
X-968700Y-504500D01*
G01X-944500Y-502000D02*
X-943450Y-503750D01*
X-942050Y-504750D01*
X-940475Y-505000D01*
X-939075Y-504750D01*
X-937675Y-503500D01*
X-936800Y-502000D01*
X-936625Y-500500D01*
X-936975Y-498750D01*
X-938200Y-497500D01*
X-939425Y-497000D01*
X-941000D01*
G01X-939425D02*
X-938375Y-496250D01*
X-937500Y-495000D01*
X-937150Y-493500D01*
X-937500Y-492000D01*
X-938375Y-490750D01*
X-939950Y-490000D01*
X-941525Y-490250D01*
X-943100Y-491250D01*
G01X-926450Y-490000D02*
X-927850Y-490500D01*
X-928900Y-491750D01*
X-929600Y-493250D01*
X-930125Y-495250D01*
X-930300Y-497500D01*
X-930125Y-499750D01*
X-929600Y-501750D01*
X-928900Y-503250D01*
X-927850Y-504500D01*
X-926450Y-505000D01*
X-925050Y-504500D01*
X-924000Y-503250D01*
X-923300Y-501750D01*
X-922775Y-499750D01*
X-922600Y-497500D01*
X-922775Y-495250D01*
X-923300Y-493250D01*
X-924000Y-491750D01*
X-925050Y-490500D01*
X-926450Y-490000D01*
G01X-915400Y-505500D02*
X-909100Y-490000D01*
G01X-915400D02*
X-916450Y-490500D01*
X-916975Y-491250D01*
X-917325Y-492750D01*
X-916975Y-494250D01*
X-916450Y-495000D01*
X-915400Y-495500D01*
X-914350Y-495000D01*
X-913825Y-494250D01*
X-913475Y-492750D01*
X-913825Y-491250D01*
X-914350Y-490500D01*
X-915400Y-490000D01*
G01X-909100Y-500000D02*
X-910150Y-500500D01*
X-910675Y-501250D01*
X-911025Y-502750D01*
X-910675Y-504250D01*
X-910150Y-505000D01*
X-909100Y-505500D01*
X-908050Y-505000D01*
X-907525Y-504250D01*
X-907175Y-502750D01*
X-907525Y-501250D01*
X-908050Y-500500D01*
X-909100Y-500000D01*
G01X-883850Y-490000D02*
Y-505000D01*
G01X-887875Y-490000D02*
X-879825D01*
G01X-869650Y-505000D02*
X-871050Y-504750D01*
X-872275Y-503750D01*
X-873325Y-502250D01*
X-874025Y-500500D01*
X-874375Y-498500D01*
Y-496500D01*
X-874025Y-494500D01*
X-873325Y-492750D01*
X-872275Y-491250D01*
X-871050Y-490250D01*
X-869650Y-490000D01*
X-868250Y-490250D01*
X-867025Y-491250D01*
X-865975Y-492750D01*
X-865275Y-494500D01*
X-864925Y-496500D01*
Y-498500D01*
X-865275Y-500500D01*
X-865975Y-502250D01*
X-867025Y-503750D01*
X-868250Y-504750D01*
X-869650Y-505000D01*
G01X-844225Y-503250D02*
X-843000Y-504500D01*
X-841600Y-505000D01*
X-840200Y-504500D01*
X-838975Y-503000D01*
X-838100Y-500750D01*
X-837750Y-498500D01*
Y-495750D01*
X-838100Y-493500D01*
X-838975Y-491500D01*
X-840025Y-490500D01*
X-841250Y-490000D01*
X-842650Y-490500D01*
X-843700Y-491500D01*
X-844400Y-493000D01*
X-844750Y-495000D01*
X-844400Y-496750D01*
X-843525Y-498500D01*
X-842475Y-499500D01*
X-841250Y-499750D01*
X-839850Y-499250D01*
X-838800Y-498000D01*
X-837750Y-495750D01*
G01X-827050Y-490000D02*
X-828450Y-490500D01*
X-829500Y-491750D01*
X-830200Y-493250D01*
X-830725Y-495250D01*
X-830900Y-497500D01*
X-830725Y-499750D01*
X-830200Y-501750D01*
X-829500Y-503250D01*
X-828450Y-504500D01*
X-827050Y-505000D01*
X-825650Y-504500D01*
X-824600Y-503250D01*
X-823900Y-501750D01*
X-823375Y-499750D01*
X-823200Y-497500D01*
X-823375Y-495250D01*
X-823900Y-493250D01*
X-824600Y-491750D01*
X-825650Y-490500D01*
X-827050Y-490000D01*
G01X-816000Y-505500D02*
X-809700Y-490000D01*
G01X-816000D02*
X-817050Y-490500D01*
X-817575Y-491250D01*
X-817925Y-492750D01*
X-817575Y-494250D01*
X-817050Y-495000D01*
X-816000Y-495500D01*
X-814950Y-495000D01*
X-814425Y-494250D01*
X-814075Y-492750D01*
X-814425Y-491250D01*
X-814950Y-490500D01*
X-816000Y-490000D01*
G01X-809700Y-500000D02*
X-810750Y-500500D01*
X-811275Y-501250D01*
X-811625Y-502750D01*
X-811275Y-504250D01*
X-810750Y-505000D01*
X-809700Y-505500D01*
X-808650Y-505000D01*
X-808125Y-504250D01*
X-807775Y-502750D01*
X-808125Y-501250D01*
X-808650Y-500500D01*
X-809700Y-500000D01*
G01X-798650Y-505500D02*
X-799000Y-505250D01*
Y-504750D01*
X-798650Y-504500D01*
X-798300Y-504750D01*
Y-505250D01*
X-798650Y-505500D01*
G01X-774625Y-490000D02*
X-770250Y-505000D01*
X-765875Y-490000D01*
G01X-758150D02*
X-753950D01*
G01X-756050D02*
Y-505000D01*
G01X-758150D02*
X-753950D01*
G01X-746225D02*
X-741850Y-490000D01*
X-737475Y-505000D01*
G01X-739050Y-499750D02*
X-744650D01*
G01X-731325Y-503000D02*
X-729925Y-504250D01*
X-728350Y-505000D01*
X-726950D01*
X-725550Y-504250D01*
X-724500Y-503000D01*
X-723975Y-501250D01*
X-724325Y-499500D01*
X-725200Y-498000D01*
X-726775Y-497000D01*
X-728875Y-496500D01*
X-730100Y-495500D01*
X-730625Y-493750D01*
X-730275Y-492000D01*
X-729400Y-490750D01*
X-728175Y-490000D01*
X-726950D01*
X-725725Y-490500D01*
X-724675Y-491750D01*
G01X-704500Y-490000D02*
X-702050Y-505000D01*
X-699250Y-490000D01*
X-696450Y-505000D01*
X-694000Y-490000D01*
G01X-687150D02*
X-682950D01*
G01X-685050D02*
Y-505000D01*
G01X-687150D02*
X-682950D01*
G01X-670850Y-490000D02*
Y-505000D01*
G01X-674875Y-490000D02*
X-666825D01*
G01X-660325Y-505000D02*
Y-490000D01*
G01X-652975D02*
Y-505000D01*
G01Y-497500D02*
X-660325D01*
G01X-1636450Y-455000D02*
Y-470000D01*
G01X-1640475Y-455000D02*
X-1632425D01*
G01X-1625925Y-470000D02*
Y-455000D01*
G01X-1618575D02*
Y-470000D01*
G01Y-462500D02*
X-1625925D01*
G01X-1610150Y-455000D02*
X-1605950D01*
G01X-1608050D02*
Y-470000D01*
G01X-1610150D02*
X-1605950D01*
G01X-1590000Y-456250D02*
X-1591050Y-455500D01*
X-1592275Y-455000D01*
X-1593675D01*
X-1595250Y-455750D01*
X-1596475Y-457000D01*
X-1597350Y-458500D01*
X-1598050Y-461000D01*
X-1598225Y-463250D01*
X-1597875Y-465500D01*
X-1597350Y-467000D01*
X-1596300Y-468500D01*
X-1595075Y-469500D01*
X-1593850Y-470000D01*
X-1592625D01*
X-1591400Y-469500D01*
X-1590350Y-468750D01*
X-1589475Y-467750D01*
G01X-1583500Y-470000D02*
Y-455000D01*
G01X-1576850D02*
X-1583500Y-464250D01*
G01X-1575800Y-470000D02*
X-1580525Y-460000D01*
G01X-1569475Y-470000D02*
Y-455000D01*
X-1561425Y-470000D01*
Y-455000D01*
G01X-1547750Y-470000D02*
X-1554750D01*
Y-455000D01*
X-1547750D01*
G01X-1550550Y-462250D02*
X-1554750D01*
G01X-1540725Y-468000D02*
X-1539325Y-469250D01*
X-1537750Y-470000D01*
X-1536350D01*
X-1534950Y-469250D01*
X-1533900Y-468000D01*
X-1533375Y-466250D01*
X-1533725Y-464500D01*
X-1534600Y-463000D01*
X-1536175Y-462000D01*
X-1538275Y-461500D01*
X-1539500Y-460500D01*
X-1540025Y-458750D01*
X-1539675Y-457000D01*
X-1538800Y-455750D01*
X-1537575Y-455000D01*
X-1536350D01*
X-1535125Y-455500D01*
X-1534075Y-456750D01*
G01X-1526525Y-468000D02*
X-1525125Y-469250D01*
X-1523550Y-470000D01*
X-1522150D01*
X-1520750Y-469250D01*
X-1519700Y-468000D01*
X-1519175Y-466250D01*
X-1519525Y-464500D01*
X-1520400Y-463000D01*
X-1521975Y-462000D01*
X-1524075Y-461500D01*
X-1525300Y-460500D01*
X-1525825Y-458750D01*
X-1525475Y-457000D01*
X-1524600Y-455750D01*
X-1523375Y-455000D01*
X-1522150D01*
X-1520925Y-455500D01*
X-1519875Y-456750D01*
G01X-1498125Y-468000D02*
X-1496725Y-469250D01*
X-1495150Y-470000D01*
X-1493750D01*
X-1492350Y-469250D01*
X-1491300Y-468000D01*
X-1490775Y-466250D01*
X-1491125Y-464500D01*
X-1492000Y-463000D01*
X-1493575Y-462000D01*
X-1495675Y-461500D01*
X-1496900Y-460500D01*
X-1497425Y-458750D01*
X-1497075Y-457000D01*
X-1496200Y-455750D01*
X-1494975Y-455000D01*
X-1493750D01*
X-1492525Y-455500D01*
X-1491475Y-456750D01*
G01X-1483925Y-470000D02*
Y-455000D01*
G01X-1476575D02*
Y-470000D01*
G01Y-462500D02*
X-1483925D01*
G01X-1470425Y-470000D02*
X-1466050Y-455000D01*
X-1461675Y-470000D01*
G01X-1463250Y-464750D02*
X-1468850D01*
G01X-1455350Y-455000D02*
Y-470000D01*
X-1448350D01*
G01X-1441150Y-455000D02*
Y-470000D01*
X-1434150D01*
G01X-1407850Y-462000D02*
X-1407150Y-461250D01*
X-1406625Y-460000D01*
X-1406275Y-458250D01*
X-1406625Y-456750D01*
X-1407325Y-455750D01*
X-1408550Y-455000D01*
X-1413275D01*
Y-470000D01*
X-1407500D01*
X-1406275Y-469000D01*
X-1405575Y-467500D01*
X-1405225Y-465750D01*
X-1405575Y-464000D01*
X-1406625Y-462500D01*
X-1407850Y-462000D01*
X-1413275D01*
G01X-1391550Y-470000D02*
X-1398550D01*
Y-455000D01*
X-1391550D01*
G01X-1394350Y-462250D02*
X-1398550D01*
G01X-1366650Y-455000D02*
X-1368050Y-455500D01*
X-1369100Y-456750D01*
X-1369800Y-458250D01*
X-1370325Y-460250D01*
X-1370500Y-462500D01*
X-1370325Y-464750D01*
X-1369800Y-466750D01*
X-1369100Y-468250D01*
X-1368050Y-469500D01*
X-1366650Y-470000D01*
X-1365250Y-469500D01*
X-1364200Y-468250D01*
X-1363500Y-466750D01*
X-1362975Y-464750D01*
X-1362800Y-462500D01*
X-1362975Y-460250D01*
X-1363500Y-458250D01*
X-1364200Y-456750D01*
X-1365250Y-455500D01*
X-1366650Y-455000D01*
G01X-1352450Y-470500D02*
X-1352800Y-470250D01*
Y-469750D01*
X-1352450Y-469500D01*
X-1352100Y-469750D01*
Y-470250D01*
X-1352450Y-470500D01*
G01X-1341575Y-457500D02*
X-1340525Y-456000D01*
X-1339300Y-455250D01*
X-1337900Y-455000D01*
X-1336150Y-455500D01*
X-1334925Y-456750D01*
X-1334575Y-458250D01*
X-1334750Y-459750D01*
X-1335450Y-461000D01*
X-1338950Y-463500D01*
X-1340525Y-465250D01*
X-1341575Y-467750D01*
X-1341925Y-470000D01*
X-1334575D01*
G01X-1327900Y-467750D02*
X-1326850Y-469000D01*
X-1325625Y-469750D01*
X-1324050Y-470000D01*
X-1322475Y-469500D01*
X-1321250Y-468500D01*
X-1320375Y-466750D01*
X-1320200Y-464750D01*
X-1320550Y-462750D01*
X-1321425Y-461500D01*
X-1322650Y-460500D01*
X-1323875Y-460250D01*
X-1325100Y-460500D01*
X-1326675Y-461500D01*
X-1326150Y-455000D01*
X-1321425D01*
G01X-1295650D02*
Y-470000D01*
G01X-1299675Y-455000D02*
X-1291625D01*
G01X-1281450Y-470000D02*
X-1282850Y-469750D01*
X-1284075Y-468750D01*
X-1285125Y-467250D01*
X-1285825Y-465500D01*
X-1286175Y-463500D01*
Y-461500D01*
X-1285825Y-459500D01*
X-1285125Y-457750D01*
X-1284075Y-456250D01*
X-1282850Y-455250D01*
X-1281450Y-455000D01*
X-1280050Y-455250D01*
X-1278825Y-456250D01*
X-1277775Y-457750D01*
X-1277075Y-459500D01*
X-1276725Y-461500D01*
Y-463500D01*
X-1277075Y-465500D01*
X-1277775Y-467250D01*
X-1278825Y-468750D01*
X-1280050Y-469750D01*
X-1281450Y-470000D01*
G01X-1253050Y-455000D02*
X-1254450Y-455500D01*
X-1255500Y-456750D01*
X-1256200Y-458250D01*
X-1256725Y-460250D01*
X-1256900Y-462500D01*
X-1256725Y-464750D01*
X-1256200Y-466750D01*
X-1255500Y-468250D01*
X-1254450Y-469500D01*
X-1253050Y-470000D01*
X-1251650Y-469500D01*
X-1250600Y-468250D01*
X-1249900Y-466750D01*
X-1249375Y-464750D01*
X-1249200Y-462500D01*
X-1249375Y-460250D01*
X-1249900Y-458250D01*
X-1250600Y-456750D01*
X-1251650Y-455500D01*
X-1253050Y-455000D01*
G01X-1238850Y-470500D02*
X-1239200Y-470250D01*
Y-469750D01*
X-1238850Y-469500D01*
X-1238500Y-469750D01*
Y-470250D01*
X-1238850Y-470500D01*
G01X-1228500Y-467750D02*
X-1227450Y-469000D01*
X-1226225Y-469750D01*
X-1224650Y-470000D01*
X-1223075Y-469500D01*
X-1221850Y-468500D01*
X-1220975Y-466750D01*
X-1220800Y-464750D01*
X-1221150Y-462750D01*
X-1222025Y-461500D01*
X-1223250Y-460500D01*
X-1224475Y-460250D01*
X-1225700Y-460500D01*
X-1227275Y-461500D01*
X-1226750Y-455000D01*
X-1222025D01*
G01X-1210450D02*
X-1211850Y-455500D01*
X-1212900Y-456750D01*
X-1213600Y-458250D01*
X-1214125Y-460250D01*
X-1214300Y-462500D01*
X-1214125Y-464750D01*
X-1213600Y-466750D01*
X-1212900Y-468250D01*
X-1211850Y-469500D01*
X-1210450Y-470000D01*
X-1209050Y-469500D01*
X-1208000Y-468250D01*
X-1207300Y-466750D01*
X-1206775Y-464750D01*
X-1206600Y-462500D01*
X-1206775Y-460250D01*
X-1207300Y-458250D01*
X-1208000Y-456750D01*
X-1209050Y-455500D01*
X-1210450Y-455000D01*
G01X-1186600Y-470000D02*
Y-455000D01*
X-1182050Y-467500D01*
X-1177500Y-455000D01*
Y-470000D01*
G01X-1169950Y-455000D02*
X-1165750D01*
G01X-1167850D02*
Y-470000D01*
G01X-1169950D02*
X-1165750D01*
G01X-1149800Y-456250D02*
X-1150850Y-455500D01*
X-1152075Y-455000D01*
X-1153475D01*
X-1155050Y-455750D01*
X-1156275Y-457000D01*
X-1157150Y-458500D01*
X-1157850Y-461000D01*
X-1158025Y-463250D01*
X-1157675Y-465500D01*
X-1157150Y-467000D01*
X-1156100Y-468500D01*
X-1154875Y-469500D01*
X-1153650Y-470000D01*
X-1152425D01*
X-1151200Y-469500D01*
X-1150150Y-468750D01*
X-1149275Y-467750D01*
G01X-1142950Y-470000D02*
Y-455000D01*
X-1138575D01*
X-1137175Y-455750D01*
X-1136300Y-456750D01*
X-1135950Y-458750D01*
X-1136300Y-460750D01*
X-1137350Y-462000D01*
X-1138575Y-462750D01*
X-1142950D01*
G01X-1138575D02*
X-1135950Y-470000D01*
G01X-1125250D02*
X-1126650Y-469750D01*
X-1127875Y-468750D01*
X-1128925Y-467250D01*
X-1129625Y-465500D01*
X-1129975Y-463500D01*
Y-461500D01*
X-1129625Y-459500D01*
X-1128925Y-457750D01*
X-1127875Y-456250D01*
X-1126650Y-455250D01*
X-1125250Y-455000D01*
X-1123850Y-455250D01*
X-1122625Y-456250D01*
X-1121575Y-457750D01*
X-1120875Y-459500D01*
X-1120525Y-461500D01*
Y-463500D01*
X-1120875Y-465500D01*
X-1121575Y-467250D01*
X-1122625Y-468750D01*
X-1123850Y-469750D01*
X-1125250Y-470000D01*
G01X-1115075D02*
Y-455000D01*
X-1107025Y-470000D01*
Y-455000D01*
G01X-1095975Y-475000D02*
X-1094225Y-472500D01*
X-1093350Y-470000D01*
Y-460000D01*
X-1094225Y-457500D01*
X-1095975Y-455000D01*
G01X-1082650Y-470500D02*
X-1083000Y-470250D01*
Y-469750D01*
X-1082650Y-469500D01*
X-1082300Y-469750D01*
Y-470250D01*
X-1082650Y-470500D01*
G01X-1696575Y-427500D02*
X-1695525Y-426000D01*
X-1694300Y-425250D01*
X-1692900Y-425000D01*
X-1691150Y-425500D01*
X-1689925Y-426750D01*
X-1689575Y-428250D01*
X-1689750Y-429750D01*
X-1690450Y-431000D01*
X-1693950Y-433500D01*
X-1695525Y-435250D01*
X-1696575Y-437750D01*
X-1696925Y-440000D01*
X-1689575D01*
G01X-1679050D02*
Y-425000D01*
X-1681150Y-428000D01*
G01Y-440000D02*
X-1676950D01*
G01X-1664850Y-440500D02*
X-1665200Y-440250D01*
Y-439750D01*
X-1664850Y-439500D01*
X-1664500Y-439750D01*
Y-440250D01*
X-1664850Y-440500D01*
G01X-1640125Y-438000D02*
X-1638725Y-439250D01*
X-1637150Y-440000D01*
X-1635750D01*
X-1634350Y-439250D01*
X-1633300Y-438000D01*
X-1632775Y-436250D01*
X-1633125Y-434500D01*
X-1634000Y-433000D01*
X-1635575Y-432000D01*
X-1637675Y-431500D01*
X-1638900Y-430500D01*
X-1639425Y-428750D01*
X-1639075Y-427000D01*
X-1638200Y-425750D01*
X-1636975Y-425000D01*
X-1635750D01*
X-1634525Y-425500D01*
X-1633475Y-426750D01*
G01X-1626100Y-425000D02*
Y-435750D01*
X-1625400Y-438000D01*
X-1624000Y-439500D01*
X-1622250Y-440000D01*
X-1620500Y-439500D01*
X-1619100Y-438000D01*
X-1618400Y-435750D01*
Y-425000D01*
G01X-1611550Y-440000D02*
Y-425000D01*
X-1607175D01*
X-1605775Y-425750D01*
X-1604900Y-426750D01*
X-1604550Y-428750D01*
X-1604900Y-430750D01*
X-1605950Y-432000D01*
X-1607175Y-432750D01*
X-1611550D01*
G01X-1607175D02*
X-1604550Y-440000D01*
G01X-1597175D02*
Y-425000D01*
X-1590525D01*
G01X-1592975Y-432250D02*
X-1597175D01*
G01X-1584025Y-440000D02*
X-1579650Y-425000D01*
X-1575275Y-440000D01*
G01X-1576850Y-434750D02*
X-1582450D01*
G01X-1561600Y-426250D02*
X-1562650Y-425500D01*
X-1563875Y-425000D01*
X-1565275D01*
X-1566850Y-425750D01*
X-1568075Y-427000D01*
X-1568950Y-428500D01*
X-1569650Y-431000D01*
X-1569825Y-433250D01*
X-1569475Y-435500D01*
X-1568950Y-437000D01*
X-1567900Y-438500D01*
X-1566675Y-439500D01*
X-1565450Y-440000D01*
X-1564225D01*
X-1563000Y-439500D01*
X-1561950Y-438750D01*
X-1561075Y-437750D01*
G01X-1547750Y-440000D02*
X-1554750D01*
Y-425000D01*
X-1547750D01*
G01X-1550550Y-432250D02*
X-1554750D01*
G01X-1526175Y-440000D02*
Y-425000D01*
X-1519525D01*
G01X-1521975Y-432250D02*
X-1526175D01*
G01X-1510750Y-425000D02*
X-1506550D01*
G01X-1508650D02*
Y-440000D01*
G01X-1510750D02*
X-1506550D01*
G01X-1498475D02*
Y-425000D01*
X-1490425Y-440000D01*
Y-425000D01*
G01X-1482350D02*
X-1478150D01*
G01X-1480250D02*
Y-440000D01*
G01X-1482350D02*
X-1478150D01*
G01X-1469725Y-438000D02*
X-1468325Y-439250D01*
X-1466750Y-440000D01*
X-1465350D01*
X-1463950Y-439250D01*
X-1462900Y-438000D01*
X-1462375Y-436250D01*
X-1462725Y-434500D01*
X-1463600Y-433000D01*
X-1465175Y-432000D01*
X-1467275Y-431500D01*
X-1468500Y-430500D01*
X-1469025Y-428750D01*
X-1468675Y-427000D01*
X-1467800Y-425750D01*
X-1466575Y-425000D01*
X-1465350D01*
X-1464125Y-425500D01*
X-1463075Y-426750D01*
G01X-1455525Y-440000D02*
Y-425000D01*
G01X-1448175D02*
Y-440000D01*
G01Y-432500D02*
X-1455525D01*
G01X-1437650Y-440500D02*
X-1438000Y-440250D01*
Y-439750D01*
X-1437650Y-439500D01*
X-1437300Y-439750D01*
Y-440250D01*
X-1437650Y-440500D01*
G01Y-433750D02*
X-1438000Y-433500D01*
Y-433000D01*
X-1437650Y-432750D01*
X-1437300Y-433000D01*
Y-433500D01*
X-1437650Y-433750D01*
G01X-1409250Y-440000D02*
X-1410650Y-439750D01*
X-1411875Y-438750D01*
X-1412925Y-437250D01*
X-1413625Y-435500D01*
X-1413975Y-433500D01*
Y-431500D01*
X-1413625Y-429500D01*
X-1412925Y-427750D01*
X-1411875Y-426250D01*
X-1410650Y-425250D01*
X-1409250Y-425000D01*
X-1407850Y-425250D01*
X-1406625Y-426250D01*
X-1405575Y-427750D01*
X-1404875Y-429500D01*
X-1404525Y-431500D01*
Y-433500D01*
X-1404875Y-435500D01*
X-1405575Y-437250D01*
X-1406625Y-438750D01*
X-1407850Y-439750D01*
X-1409250Y-440000D01*
G01X-1398725Y-438000D02*
X-1397325Y-439250D01*
X-1395750Y-440000D01*
X-1394350D01*
X-1392950Y-439250D01*
X-1391900Y-438000D01*
X-1391375Y-436250D01*
X-1391725Y-434500D01*
X-1392600Y-433000D01*
X-1394175Y-432000D01*
X-1396275Y-431500D01*
X-1397500Y-430500D01*
X-1398025Y-428750D01*
X-1397675Y-427000D01*
X-1396800Y-425750D01*
X-1395575Y-425000D01*
X-1394350D01*
X-1393125Y-425500D01*
X-1392075Y-426750D01*
G01X-1384350Y-440000D02*
Y-425000D01*
X-1380150D01*
X-1378750Y-425750D01*
X-1377700Y-427500D01*
X-1377350Y-429500D01*
X-1377700Y-431500D01*
X-1378575Y-433000D01*
X-1380150Y-433750D01*
X-1384350D01*
G01X-1353325Y-445000D02*
X-1355075Y-442500D01*
X-1355950Y-440000D01*
Y-430000D01*
X-1355075Y-427500D01*
X-1353325Y-425000D01*
G01X-1334750Y-440000D02*
X-1341750D01*
Y-425000D01*
X-1334750D01*
G01X-1337550Y-432250D02*
X-1341750D01*
G01X-1328075Y-440000D02*
Y-425000D01*
X-1320025Y-440000D01*
Y-425000D01*
G01X-1309850D02*
Y-440000D01*
G01X-1313875Y-425000D02*
X-1305825D01*
G01X-1299325Y-440000D02*
Y-425000D01*
G01X-1291975D02*
Y-440000D01*
G01Y-432500D02*
X-1299325D01*
G01X-1281450Y-440000D02*
X-1282850Y-439750D01*
X-1284075Y-438750D01*
X-1285125Y-437250D01*
X-1285825Y-435500D01*
X-1286175Y-433500D01*
Y-431500D01*
X-1285825Y-429500D01*
X-1285125Y-427750D01*
X-1284075Y-426250D01*
X-1282850Y-425250D01*
X-1281450Y-425000D01*
X-1280050Y-425250D01*
X-1278825Y-426250D01*
X-1277775Y-427750D01*
X-1277075Y-429500D01*
X-1276725Y-431500D01*
Y-433500D01*
X-1277075Y-435500D01*
X-1277775Y-437250D01*
X-1278825Y-438750D01*
X-1280050Y-439750D01*
X-1281450Y-440000D01*
G01X-1271275D02*
Y-425000D01*
X-1263225Y-440000D01*
Y-425000D01*
G01X-1249550Y-440000D02*
X-1256550D01*
Y-425000D01*
X-1249550D01*
G01X-1252350Y-432250D02*
X-1256550D01*
G01X-1228325Y-440000D02*
Y-425000D01*
G01X-1220975D02*
Y-440000D01*
G01Y-432500D02*
X-1228325D01*
G01X-1210450Y-425000D02*
Y-440000D01*
G01X-1214475Y-425000D02*
X-1206425D01*
G01X-1185550Y-440000D02*
Y-425000D01*
X-1181350D01*
X-1179950Y-425750D01*
X-1178900Y-427500D01*
X-1178550Y-429500D01*
X-1178900Y-431500D01*
X-1179775Y-433000D01*
X-1181350Y-433750D01*
X-1185550D01*
G01X-1171350Y-425000D02*
Y-440000D01*
X-1164350D01*
G01X-1157500Y-425000D02*
Y-435750D01*
X-1156800Y-438000D01*
X-1155400Y-439500D01*
X-1153650Y-440000D01*
X-1151900Y-439500D01*
X-1150500Y-438000D01*
X-1149800Y-435750D01*
Y-425000D01*
G01X-1143125Y-438000D02*
X-1141725Y-439250D01*
X-1140150Y-440000D01*
X-1138750D01*
X-1137350Y-439250D01*
X-1136300Y-438000D01*
X-1135775Y-436250D01*
X-1136125Y-434500D01*
X-1137000Y-433000D01*
X-1138575Y-432000D01*
X-1140675Y-431500D01*
X-1141900Y-430500D01*
X-1142425Y-428750D01*
X-1142075Y-427000D01*
X-1141200Y-425750D01*
X-1139975Y-425000D01*
X-1138750D01*
X-1137525Y-425500D01*
X-1136475Y-426750D01*
G01X-1125600Y-442750D02*
X-1124900Y-439500D01*
G01X-1114375Y-440000D02*
Y-425000D01*
X-1107725D01*
G01X-1110175Y-432250D02*
X-1114375D01*
G01X-1096850Y-440000D02*
X-1098250Y-439750D01*
X-1099475Y-438750D01*
X-1100525Y-437250D01*
X-1101225Y-435500D01*
X-1101575Y-433500D01*
Y-431500D01*
X-1101225Y-429500D01*
X-1100525Y-427750D01*
X-1099475Y-426250D01*
X-1098250Y-425250D01*
X-1096850Y-425000D01*
X-1095450Y-425250D01*
X-1094225Y-426250D01*
X-1093175Y-427750D01*
X-1092475Y-429500D01*
X-1092125Y-431500D01*
Y-433500D01*
X-1092475Y-435500D01*
X-1093175Y-437250D01*
X-1094225Y-438750D01*
X-1095450Y-439750D01*
X-1096850Y-440000D01*
G01X-1086150D02*
Y-425000D01*
X-1081775D01*
X-1080375Y-425750D01*
X-1079500Y-426750D01*
X-1079150Y-428750D01*
X-1079500Y-430750D01*
X-1080550Y-432000D01*
X-1081775Y-432750D01*
X-1086150D01*
G01X-1081775D02*
X-1079150Y-440000D01*
G01X-1073000D02*
Y-425000D01*
X-1068450Y-437500D01*
X-1063900Y-425000D01*
Y-440000D01*
G01X-1054250D02*
X-1055650Y-439750D01*
X-1056875Y-438750D01*
X-1057925Y-437250D01*
X-1058625Y-435500D01*
X-1058975Y-433500D01*
Y-431500D01*
X-1058625Y-429500D01*
X-1057925Y-427750D01*
X-1056875Y-426250D01*
X-1055650Y-425250D01*
X-1054250Y-425000D01*
X-1052850Y-425250D01*
X-1051625Y-426250D01*
X-1050575Y-427750D01*
X-1049875Y-429500D01*
X-1049525Y-431500D01*
Y-433500D01*
X-1049875Y-435500D01*
X-1050575Y-437250D01*
X-1051625Y-438750D01*
X-1052850Y-439750D01*
X-1054250Y-440000D01*
G01X-1036200Y-426250D02*
X-1037250Y-425500D01*
X-1038475Y-425000D01*
X-1039875D01*
X-1041450Y-425750D01*
X-1042675Y-427000D01*
X-1043550Y-428500D01*
X-1044250Y-431000D01*
X-1044425Y-433250D01*
X-1044075Y-435500D01*
X-1043550Y-437000D01*
X-1042500Y-438500D01*
X-1041275Y-439500D01*
X-1040050Y-440000D01*
X-1038825D01*
X-1037600Y-439500D01*
X-1036550Y-438750D01*
X-1035675Y-437750D01*
G01X-1029525Y-440000D02*
Y-425000D01*
G01X-1022175D02*
Y-440000D01*
G01Y-432500D02*
X-1029525D01*
G01X-1008150Y-440000D02*
X-1015150D01*
Y-425000D01*
X-1008150D01*
G01X-1010950Y-432250D02*
X-1015150D01*
G01X-1002000Y-440000D02*
Y-425000D01*
X-997450Y-437500D01*
X-992900Y-425000D01*
Y-440000D01*
G01X-972375D02*
Y-425000D01*
X-965725D01*
G01X-968175Y-432250D02*
X-972375D01*
G01X-958700Y-437000D02*
X-957650Y-438750D01*
X-956250Y-439750D01*
X-954675Y-440000D01*
X-953275Y-439750D01*
X-951875Y-438500D01*
X-951000Y-437000D01*
X-950825Y-435500D01*
X-951175Y-433750D01*
X-952400Y-432500D01*
X-953625Y-432000D01*
X-955200D01*
G01X-953625D02*
X-952575Y-431250D01*
X-951700Y-430000D01*
X-951350Y-428500D01*
X-951700Y-427000D01*
X-952575Y-425750D01*
X-954150Y-425000D01*
X-955725Y-425250D01*
X-957300Y-426250D01*
G01X-944500Y-437750D02*
X-943450Y-439000D01*
X-942225Y-439750D01*
X-940650Y-440000D01*
X-939075Y-439500D01*
X-937850Y-438500D01*
X-936975Y-436750D01*
X-936800Y-434750D01*
X-937150Y-432750D01*
X-938025Y-431500D01*
X-939250Y-430500D01*
X-940475Y-430250D01*
X-941700Y-430500D01*
X-943275Y-431500D01*
X-942750Y-425000D01*
X-938025D01*
G01X-926800Y-442750D02*
X-926100Y-439500D01*
G01X-915925Y-438000D02*
X-914525Y-439250D01*
X-912950Y-440000D01*
X-911550D01*
X-910150Y-439250D01*
X-909100Y-438000D01*
X-908575Y-436250D01*
X-908925Y-434500D01*
X-909800Y-433000D01*
X-911375Y-432000D01*
X-913475Y-431500D01*
X-914700Y-430500D01*
X-915225Y-428750D01*
X-914875Y-427000D01*
X-914000Y-425750D01*
X-912775Y-425000D01*
X-911550D01*
X-910325Y-425500D01*
X-909275Y-426750D01*
G01X-901725Y-440000D02*
Y-425000D01*
G01X-894375D02*
Y-440000D01*
G01Y-432500D02*
X-901725D01*
G01X-885950Y-425000D02*
X-881750D01*
G01X-883850D02*
Y-440000D01*
G01X-885950D02*
X-881750D01*
G01X-873500D02*
Y-425000D01*
G01X-866850D02*
X-873500Y-434250D01*
G01X-865800Y-440000D02*
X-870525Y-430000D01*
G01X-855450Y-440000D02*
X-856850Y-439750D01*
X-858075Y-438750D01*
X-859125Y-437250D01*
X-859825Y-435500D01*
X-860175Y-433500D01*
Y-431500D01*
X-859825Y-429500D01*
X-859125Y-427750D01*
X-858075Y-426250D01*
X-856850Y-425250D01*
X-855450Y-425000D01*
X-854050Y-425250D01*
X-852825Y-426250D01*
X-851775Y-427750D01*
X-851075Y-429500D01*
X-850725Y-431500D01*
Y-433500D01*
X-851075Y-435500D01*
X-851775Y-437250D01*
X-852825Y-438750D01*
X-854050Y-439750D01*
X-855450Y-440000D01*
G01X-845100D02*
Y-425000D01*
G01X-838450D02*
X-845100Y-434250D01*
G01X-837400Y-440000D02*
X-842125Y-430000D01*
G01X-830900Y-425000D02*
Y-435750D01*
X-830200Y-438000D01*
X-828800Y-439500D01*
X-827050Y-440000D01*
X-825300Y-439500D01*
X-823900Y-438000D01*
X-823200Y-435750D01*
Y-425000D01*
G01X-801975Y-440000D02*
Y-425000D01*
X-795325D01*
G01X-797775Y-432250D02*
X-801975D01*
G01X-787775Y-427500D02*
X-786725Y-426000D01*
X-785500Y-425250D01*
X-784100Y-425000D01*
X-782350Y-425500D01*
X-781125Y-426750D01*
X-780775Y-428250D01*
X-780950Y-429750D01*
X-781650Y-431000D01*
X-785150Y-433500D01*
X-786725Y-435250D01*
X-787775Y-437750D01*
X-788125Y-440000D01*
X-780775D01*
G01X-756925Y-445000D02*
X-758675Y-442500D01*
X-759550Y-440000D01*
Y-430000D01*
X-758675Y-427500D01*
X-756925Y-425000D01*
G01X-745350D02*
Y-440000D01*
X-738350D01*
G01X-731325D02*
X-723975Y-425000D01*
G01X-731325D02*
X-723975Y-440000D01*
G01X-712575Y-445000D02*
X-710825Y-442500D01*
X-709950Y-440000D01*
Y-430000D01*
X-710825Y-427500D01*
X-712575Y-425000D01*
G01X-688550Y-440000D02*
Y-425000D01*
X-684350D01*
X-682950Y-425750D01*
X-681900Y-427500D01*
X-681550Y-429500D01*
X-681900Y-431500D01*
X-682775Y-433000D01*
X-684350Y-433750D01*
X-688550D01*
G01X-674350Y-425000D02*
Y-440000D01*
X-667350D01*
G01X-660500Y-425000D02*
Y-435750D01*
X-659800Y-438000D01*
X-658400Y-439500D01*
X-656650Y-440000D01*
X-654900Y-439500D01*
X-653500Y-438000D01*
X-652800Y-435750D01*
Y-425000D01*
G01X-646125Y-440000D02*
X-638775Y-425000D01*
G01X-646125D02*
X-638775Y-440000D01*
G01X-1696575Y-327500D02*
X-1695525Y-326000D01*
X-1694300Y-325250D01*
X-1692900Y-325000D01*
X-1691150Y-325500D01*
X-1689925Y-326750D01*
X-1689575Y-328250D01*
X-1689750Y-329750D01*
X-1690450Y-331000D01*
X-1693950Y-333500D01*
X-1695525Y-335250D01*
X-1696575Y-337750D01*
X-1696925Y-340000D01*
X-1689575D01*
G01X-1679050Y-325000D02*
X-1680450Y-325500D01*
X-1681500Y-326750D01*
X-1682200Y-328250D01*
X-1682725Y-330250D01*
X-1682900Y-332500D01*
X-1682725Y-334750D01*
X-1682200Y-336750D01*
X-1681500Y-338250D01*
X-1680450Y-339500D01*
X-1679050Y-340000D01*
X-1677650Y-339500D01*
X-1676600Y-338250D01*
X-1675900Y-336750D01*
X-1675375Y-334750D01*
X-1675200Y-332500D01*
X-1675375Y-330250D01*
X-1675900Y-328250D01*
X-1676600Y-326750D01*
X-1677650Y-325500D01*
X-1679050Y-325000D01*
G01X-1664850Y-340500D02*
X-1665200Y-340250D01*
Y-339750D01*
X-1664850Y-339500D01*
X-1664500Y-339750D01*
Y-340250D01*
X-1664850Y-340500D01*
G01X-1639950Y-340000D02*
Y-325000D01*
X-1635750D01*
X-1634350Y-325750D01*
X-1633300Y-327500D01*
X-1632950Y-329500D01*
X-1633300Y-331500D01*
X-1634175Y-333000D01*
X-1635750Y-333750D01*
X-1639950D01*
G01X-1625750Y-325000D02*
Y-340000D01*
X-1618750D01*
G01X-1612425D02*
X-1608050Y-325000D01*
X-1603675Y-340000D01*
G01X-1605250Y-334750D02*
X-1610850D01*
G01X-1590000Y-326250D02*
X-1591050Y-325500D01*
X-1592275Y-325000D01*
X-1593675D01*
X-1595250Y-325750D01*
X-1596475Y-327000D01*
X-1597350Y-328500D01*
X-1598050Y-331000D01*
X-1598225Y-333250D01*
X-1597875Y-335500D01*
X-1597350Y-337000D01*
X-1596300Y-338500D01*
X-1595075Y-339500D01*
X-1593850Y-340000D01*
X-1592625D01*
X-1591400Y-339500D01*
X-1590350Y-338750D01*
X-1589475Y-337750D01*
G01X-1576150Y-340000D02*
X-1583150D01*
Y-325000D01*
X-1576150D01*
G01X-1578950Y-332250D02*
X-1583150D01*
G01X-1554750Y-340000D02*
Y-325000D01*
X-1550550D01*
X-1549150Y-325750D01*
X-1548100Y-327500D01*
X-1547750Y-329500D01*
X-1548100Y-331500D01*
X-1548975Y-333000D01*
X-1550550Y-333750D01*
X-1554750D01*
G01X-1533200Y-326250D02*
X-1534250Y-325500D01*
X-1535475Y-325000D01*
X-1536875D01*
X-1538450Y-325750D01*
X-1539675Y-327000D01*
X-1540550Y-328500D01*
X-1541250Y-331000D01*
X-1541425Y-333250D01*
X-1541075Y-335500D01*
X-1540550Y-337000D01*
X-1539500Y-338500D01*
X-1538275Y-339500D01*
X-1537050Y-340000D01*
X-1535825D01*
X-1534600Y-339500D01*
X-1533550Y-338750D01*
X-1532675Y-337750D01*
G01X-1521450Y-332000D02*
X-1520750Y-331250D01*
X-1520225Y-330000D01*
X-1519875Y-328250D01*
X-1520225Y-326750D01*
X-1520925Y-325750D01*
X-1522150Y-325000D01*
X-1526875D01*
Y-340000D01*
X-1521100D01*
X-1519875Y-339000D01*
X-1519175Y-337500D01*
X-1518825Y-335750D01*
X-1519175Y-334000D01*
X-1520225Y-332500D01*
X-1521450Y-332000D01*
X-1526875D01*
G01X-1497950Y-325000D02*
Y-340000D01*
X-1490950D01*
G01X-1480250D02*
X-1481650Y-339750D01*
X-1482875Y-338750D01*
X-1483925Y-337250D01*
X-1484625Y-335500D01*
X-1484975Y-333500D01*
Y-331500D01*
X-1484625Y-329500D01*
X-1483925Y-327750D01*
X-1482875Y-326250D01*
X-1481650Y-325250D01*
X-1480250Y-325000D01*
X-1478850Y-325250D01*
X-1477625Y-326250D01*
X-1476575Y-327750D01*
X-1475875Y-329500D01*
X-1475525Y-331500D01*
Y-333500D01*
X-1475875Y-335500D01*
X-1476575Y-337250D01*
X-1477625Y-338750D01*
X-1478850Y-339750D01*
X-1480250Y-340000D01*
G01X-1466050Y-325000D02*
Y-340000D01*
G01X-1470075Y-325000D02*
X-1462025D01*
G01X-1433800Y-326250D02*
X-1434850Y-325500D01*
X-1436075Y-325000D01*
X-1437475D01*
X-1439050Y-325750D01*
X-1440275Y-327000D01*
X-1441150Y-328500D01*
X-1441850Y-331000D01*
X-1442025Y-333250D01*
X-1441675Y-335500D01*
X-1441150Y-337000D01*
X-1440100Y-338500D01*
X-1438875Y-339500D01*
X-1437650Y-340000D01*
X-1436425D01*
X-1435200Y-339500D01*
X-1434150Y-338750D01*
X-1433275Y-337750D01*
G01X-1423450Y-340000D02*
X-1424850Y-339750D01*
X-1426075Y-338750D01*
X-1427125Y-337250D01*
X-1427825Y-335500D01*
X-1428175Y-333500D01*
Y-331500D01*
X-1427825Y-329500D01*
X-1427125Y-327750D01*
X-1426075Y-326250D01*
X-1424850Y-325250D01*
X-1423450Y-325000D01*
X-1422050Y-325250D01*
X-1420825Y-326250D01*
X-1419775Y-327750D01*
X-1419075Y-329500D01*
X-1418725Y-331500D01*
Y-333500D01*
X-1419075Y-335500D01*
X-1419775Y-337250D01*
X-1420825Y-338750D01*
X-1422050Y-339750D01*
X-1423450Y-340000D01*
G01X-1413100D02*
Y-325000D01*
X-1409600D01*
X-1408200Y-325750D01*
X-1407150Y-326750D01*
X-1406275Y-328250D01*
X-1405575Y-330000D01*
X-1405400Y-332500D01*
X-1405575Y-335000D01*
X-1406275Y-336750D01*
X-1407150Y-338250D01*
X-1408200Y-339250D01*
X-1409600Y-340000D01*
X-1413100D01*
G01X-1391550D02*
X-1398550D01*
Y-325000D01*
X-1391550D01*
G01X-1394350Y-332250D02*
X-1398550D01*
G01X-1370675Y-340000D02*
Y-325000D01*
X-1362625Y-340000D01*
Y-325000D01*
G01X-1356300D02*
Y-335750D01*
X-1355600Y-338000D01*
X-1354200Y-339500D01*
X-1352450Y-340000D01*
X-1350700Y-339500D01*
X-1349300Y-338000D01*
X-1348600Y-335750D01*
Y-325000D01*
G01X-1342800Y-340000D02*
Y-325000D01*
X-1338250Y-337500D01*
X-1333700Y-325000D01*
Y-340000D01*
G01X-1322650Y-332000D02*
X-1321950Y-331250D01*
X-1321425Y-330000D01*
X-1321075Y-328250D01*
X-1321425Y-326750D01*
X-1322125Y-325750D01*
X-1323350Y-325000D01*
X-1328075D01*
Y-340000D01*
X-1322300D01*
X-1321075Y-339000D01*
X-1320375Y-337500D01*
X-1320025Y-335750D01*
X-1320375Y-334000D01*
X-1321425Y-332500D01*
X-1322650Y-332000D01*
X-1328075D01*
G01X-1306350Y-340000D02*
X-1313350D01*
Y-325000D01*
X-1306350D01*
G01X-1309150Y-332250D02*
X-1313350D01*
G01X-1299150Y-340000D02*
Y-325000D01*
X-1294775D01*
X-1293375Y-325750D01*
X-1292500Y-326750D01*
X-1292150Y-328750D01*
X-1292500Y-330750D01*
X-1293550Y-332000D01*
X-1294775Y-332750D01*
X-1299150D01*
G01X-1294775D02*
X-1292150Y-340000D01*
G01X-1270750D02*
Y-325000D01*
X-1266550D01*
X-1265150Y-325750D01*
X-1264100Y-327500D01*
X-1263750Y-329500D01*
X-1264100Y-331500D01*
X-1264975Y-333000D01*
X-1266550Y-333750D01*
X-1270750D01*
G01X-1249550Y-340000D02*
X-1256550D01*
Y-325000D01*
X-1249550D01*
G01X-1252350Y-332250D02*
X-1256550D01*
G01X-1242350Y-340000D02*
Y-325000D01*
X-1237975D01*
X-1236575Y-325750D01*
X-1235700Y-326750D01*
X-1235350Y-328750D01*
X-1235700Y-330750D01*
X-1236750Y-332000D01*
X-1237975Y-332750D01*
X-1242350D01*
G01X-1237975D02*
X-1235350Y-340000D01*
G01X-1215000D02*
Y-325000D01*
X-1210450Y-337500D01*
X-1205900Y-325000D01*
Y-340000D01*
G01X-1198350Y-325000D02*
X-1194150D01*
G01X-1196250D02*
Y-340000D01*
G01X-1198350D02*
X-1194150D01*
G01X-1178200Y-326250D02*
X-1179250Y-325500D01*
X-1180475Y-325000D01*
X-1181875D01*
X-1183450Y-325750D01*
X-1184675Y-327000D01*
X-1185550Y-328500D01*
X-1186250Y-331000D01*
X-1186425Y-333250D01*
X-1186075Y-335500D01*
X-1185550Y-337000D01*
X-1184500Y-338500D01*
X-1183275Y-339500D01*
X-1182050Y-340000D01*
X-1180825D01*
X-1179600Y-339500D01*
X-1178550Y-338750D01*
X-1177675Y-337750D01*
G01X-1171350Y-340000D02*
Y-325000D01*
X-1166975D01*
X-1165575Y-325750D01*
X-1164700Y-326750D01*
X-1164350Y-328750D01*
X-1164700Y-330750D01*
X-1165750Y-332000D01*
X-1166975Y-332750D01*
X-1171350D01*
G01X-1166975D02*
X-1164350Y-340000D01*
G01X-1153650D02*
X-1155050Y-339750D01*
X-1156275Y-338750D01*
X-1157325Y-337250D01*
X-1158025Y-335500D01*
X-1158375Y-333500D01*
Y-331500D01*
X-1158025Y-329500D01*
X-1157325Y-327750D01*
X-1156275Y-326250D01*
X-1155050Y-325250D01*
X-1153650Y-325000D01*
X-1152250Y-325250D01*
X-1151025Y-326250D01*
X-1149975Y-327750D01*
X-1149275Y-329500D01*
X-1148925Y-331500D01*
Y-333500D01*
X-1149275Y-335500D01*
X-1149975Y-337250D01*
X-1151025Y-338750D01*
X-1152250Y-339750D01*
X-1153650Y-340000D01*
G01X-1143125Y-338000D02*
X-1141725Y-339250D01*
X-1140150Y-340000D01*
X-1138750D01*
X-1137350Y-339250D01*
X-1136300Y-338000D01*
X-1135775Y-336250D01*
X-1136125Y-334500D01*
X-1137000Y-333000D01*
X-1138575Y-332000D01*
X-1140675Y-331500D01*
X-1141900Y-330500D01*
X-1142425Y-328750D01*
X-1142075Y-327000D01*
X-1141200Y-325750D01*
X-1139975Y-325000D01*
X-1138750D01*
X-1137525Y-325500D01*
X-1136475Y-326750D01*
G01X-1125250Y-340000D02*
X-1126650Y-339750D01*
X-1127875Y-338750D01*
X-1128925Y-337250D01*
X-1129625Y-335500D01*
X-1129975Y-333500D01*
Y-331500D01*
X-1129625Y-329500D01*
X-1128925Y-327750D01*
X-1127875Y-326250D01*
X-1126650Y-325250D01*
X-1125250Y-325000D01*
X-1123850Y-325250D01*
X-1122625Y-326250D01*
X-1121575Y-327750D01*
X-1120875Y-329500D01*
X-1120525Y-331500D01*
Y-333500D01*
X-1120875Y-335500D01*
X-1121575Y-337250D01*
X-1122625Y-338750D01*
X-1123850Y-339750D01*
X-1125250Y-340000D01*
G01X-1114375D02*
Y-325000D01*
X-1107725D01*
G01X-1110175Y-332250D02*
X-1114375D01*
G01X-1096850Y-325000D02*
Y-340000D01*
G01X-1100875Y-325000D02*
X-1092825D01*
G01X-1072125Y-338000D02*
X-1070725Y-339250D01*
X-1069150Y-340000D01*
X-1067750D01*
X-1066350Y-339250D01*
X-1065300Y-338000D01*
X-1064775Y-336250D01*
X-1065125Y-334500D01*
X-1066000Y-333000D01*
X-1067575Y-332000D01*
X-1069675Y-331500D01*
X-1070900Y-330500D01*
X-1071425Y-328750D01*
X-1071075Y-327000D01*
X-1070200Y-325750D01*
X-1068975Y-325000D01*
X-1067750D01*
X-1066525Y-325500D01*
X-1065475Y-326750D01*
G01X-1057750Y-340000D02*
Y-325000D01*
X-1053550D01*
X-1052150Y-325750D01*
X-1051100Y-327500D01*
X-1050750Y-329500D01*
X-1051100Y-331500D01*
X-1051975Y-333000D01*
X-1053550Y-333750D01*
X-1057750D01*
G01X-1036550Y-340000D02*
X-1043550D01*
Y-325000D01*
X-1036550D01*
G01X-1039350Y-332250D02*
X-1043550D01*
G01X-1022000Y-326250D02*
X-1023050Y-325500D01*
X-1024275Y-325000D01*
X-1025675D01*
X-1027250Y-325750D01*
X-1028475Y-327000D01*
X-1029350Y-328500D01*
X-1030050Y-331000D01*
X-1030225Y-333250D01*
X-1029875Y-335500D01*
X-1029350Y-337000D01*
X-1028300Y-338500D01*
X-1027075Y-339500D01*
X-1025850Y-340000D01*
X-1024625D01*
X-1023400Y-339500D01*
X-1022350Y-338750D01*
X-1021475Y-337750D01*
G01X-1011650Y-340500D02*
X-1012000Y-340250D01*
Y-339750D01*
X-1011650Y-339500D01*
X-1011300Y-339750D01*
Y-340250D01*
X-1011650Y-340500D01*
G01X-998325Y-345000D02*
X-1000075Y-342500D01*
X-1000950Y-340000D01*
Y-330000D01*
X-1000075Y-327500D01*
X-998325Y-325000D01*
G01X-986925Y-340000D02*
Y-325000D01*
G01X-979575D02*
Y-340000D01*
G01Y-332500D02*
X-986925D01*
G01X-969050Y-325000D02*
X-970450Y-325500D01*
X-971500Y-326750D01*
X-972200Y-328250D01*
X-972725Y-330250D01*
X-972900Y-332500D01*
X-972725Y-334750D01*
X-972200Y-336750D01*
X-971500Y-338250D01*
X-970450Y-339500D01*
X-969050Y-340000D01*
X-967650Y-339500D01*
X-966600Y-338250D01*
X-965900Y-336750D01*
X-965375Y-334750D01*
X-965200Y-332500D01*
X-965375Y-330250D01*
X-965900Y-328250D01*
X-966600Y-326750D01*
X-967650Y-325500D01*
X-969050Y-325000D01*
G01X-958700Y-337750D02*
X-957650Y-339000D01*
X-956425Y-339750D01*
X-954850Y-340000D01*
X-953275Y-339500D01*
X-952050Y-338500D01*
X-951175Y-336750D01*
X-951000Y-334750D01*
X-951350Y-332750D01*
X-952225Y-331500D01*
X-953450Y-330500D01*
X-954675Y-330250D01*
X-955900Y-330500D01*
X-957475Y-331500D01*
X-956950Y-325000D01*
X-952225D01*
G01X-944500Y-337750D02*
X-943450Y-339000D01*
X-942225Y-339750D01*
X-940650Y-340000D01*
X-939075Y-339500D01*
X-937850Y-338500D01*
X-936975Y-336750D01*
X-936800Y-334750D01*
X-937150Y-332750D01*
X-938025Y-331500D01*
X-939250Y-330500D01*
X-940475Y-330250D01*
X-941700Y-330500D01*
X-943275Y-331500D01*
X-942750Y-325000D01*
X-938025D01*
G01X-930300Y-337000D02*
X-929250Y-338750D01*
X-927850Y-339750D01*
X-926275Y-340000D01*
X-924875Y-339750D01*
X-923475Y-338500D01*
X-922600Y-337000D01*
X-922425Y-335500D01*
X-922775Y-333750D01*
X-924000Y-332500D01*
X-925225Y-332000D01*
X-926800D01*
G01X-925225D02*
X-924175Y-331250D01*
X-923300Y-330000D01*
X-922950Y-328500D01*
X-923300Y-327000D01*
X-924175Y-325750D01*
X-925750Y-325000D01*
X-927325Y-325250D01*
X-928900Y-326250D01*
G01X-910150Y-340000D02*
Y-325000D01*
X-916625Y-335750D01*
X-907875D01*
G01X-900325Y-335000D02*
X-895775D01*
G01X-880350Y-340000D02*
X-887350D01*
Y-325000D01*
X-880350D01*
G01X-883150Y-332250D02*
X-887350D01*
G01X-868775Y-345000D02*
X-867025Y-342500D01*
X-866150Y-340000D01*
Y-330000D01*
X-867025Y-327500D01*
X-868775Y-325000D01*
G01X-855450Y-340500D02*
X-855800Y-340250D01*
Y-339750D01*
X-855450Y-339500D01*
X-855100Y-339750D01*
Y-340250D01*
X-855450Y-340500D01*
G01X-1640300Y-290000D02*
Y-300750D01*
X-1639600Y-303000D01*
X-1638200Y-304500D01*
X-1636450Y-305000D01*
X-1634700Y-304500D01*
X-1633300Y-303000D01*
X-1632600Y-300750D01*
Y-290000D01*
G01X-1625750Y-305000D02*
Y-290000D01*
X-1621550D01*
X-1620150Y-290750D01*
X-1619100Y-292500D01*
X-1618750Y-294500D01*
X-1619100Y-296500D01*
X-1619975Y-298000D01*
X-1621550Y-298750D01*
X-1625750D01*
G01X-1597525Y-303000D02*
X-1596125Y-304250D01*
X-1594550Y-305000D01*
X-1593150D01*
X-1591750Y-304250D01*
X-1590700Y-303000D01*
X-1590175Y-301250D01*
X-1590525Y-299500D01*
X-1591400Y-298000D01*
X-1592975Y-297000D01*
X-1595075Y-296500D01*
X-1596300Y-295500D01*
X-1596825Y-293750D01*
X-1596475Y-292000D01*
X-1595600Y-290750D01*
X-1594375Y-290000D01*
X-1593150D01*
X-1591925Y-290500D01*
X-1590875Y-291750D01*
G01X-1576150Y-305000D02*
X-1583150D01*
Y-290000D01*
X-1576150D01*
G01X-1578950Y-297250D02*
X-1583150D01*
G01X-1565450Y-305000D02*
X-1566850Y-304750D01*
X-1568075Y-303750D01*
X-1569125Y-302250D01*
X-1569825Y-300500D01*
X-1570175Y-298500D01*
Y-296500D01*
X-1569825Y-294500D01*
X-1569125Y-292750D01*
X-1568075Y-291250D01*
X-1566850Y-290250D01*
X-1565450Y-290000D01*
X-1564050Y-290250D01*
X-1562825Y-291250D01*
X-1561775Y-292750D01*
X-1561075Y-294500D01*
X-1560725Y-296500D01*
Y-298500D01*
X-1561075Y-300500D01*
X-1561775Y-302250D01*
X-1562825Y-303750D01*
X-1564050Y-304750D01*
X-1565450Y-305000D01*
G01X-1564050Y-301000D02*
X-1561950Y-305000D01*
G01X-1555100Y-290000D02*
Y-300750D01*
X-1554400Y-303000D01*
X-1553000Y-304500D01*
X-1551250Y-305000D01*
X-1549500Y-304500D01*
X-1548100Y-303000D01*
X-1547400Y-300750D01*
Y-290000D01*
G01X-1533550Y-305000D02*
X-1540550D01*
Y-290000D01*
X-1533550D01*
G01X-1536350Y-297250D02*
X-1540550D01*
G01X-1526875Y-305000D02*
Y-290000D01*
X-1518825Y-305000D01*
Y-290000D01*
G01X-1504800Y-291250D02*
X-1505850Y-290500D01*
X-1507075Y-290000D01*
X-1508475D01*
X-1510050Y-290750D01*
X-1511275Y-292000D01*
X-1512150Y-293500D01*
X-1512850Y-296000D01*
X-1513025Y-298250D01*
X-1512675Y-300500D01*
X-1512150Y-302000D01*
X-1511100Y-303500D01*
X-1509875Y-304500D01*
X-1508650Y-305000D01*
X-1507425D01*
X-1506200Y-304500D01*
X-1505150Y-303750D01*
X-1504275Y-302750D01*
G01X-1490950Y-305000D02*
X-1497950D01*
Y-290000D01*
X-1490950D01*
G01X-1493750Y-297250D02*
X-1497950D01*
G01X-1480250Y-305500D02*
X-1480600Y-305250D01*
Y-304750D01*
X-1480250Y-304500D01*
X-1479900Y-304750D01*
Y-305250D01*
X-1480250Y-305500D01*
G01X-1693250Y-275000D02*
Y-260000D01*
X-1695350Y-263000D01*
G01Y-275000D02*
X-1691150D01*
G01X-1682025Y-273250D02*
X-1680800Y-274500D01*
X-1679400Y-275000D01*
X-1678000Y-274500D01*
X-1676775Y-273000D01*
X-1675900Y-270750D01*
X-1675550Y-268500D01*
Y-265750D01*
X-1675900Y-263500D01*
X-1676775Y-261500D01*
X-1677825Y-260500D01*
X-1679050Y-260000D01*
X-1680450Y-260500D01*
X-1681500Y-261500D01*
X-1682200Y-263000D01*
X-1682550Y-265000D01*
X-1682200Y-266750D01*
X-1681325Y-268500D01*
X-1680275Y-269500D01*
X-1679050Y-269750D01*
X-1677650Y-269250D01*
X-1676600Y-268000D01*
X-1675550Y-265750D01*
G01X-1636450Y-260000D02*
Y-275000D01*
G01X-1640475Y-260000D02*
X-1632425D01*
G01X-1625925Y-275000D02*
Y-260000D01*
G01X-1618575D02*
Y-275000D01*
G01Y-267500D02*
X-1625925D01*
G01X-1610150Y-260000D02*
X-1605950D01*
G01X-1608050D02*
Y-275000D01*
G01X-1610150D02*
X-1605950D01*
G01X-1597525Y-273000D02*
X-1596125Y-274250D01*
X-1594550Y-275000D01*
X-1593150D01*
X-1591750Y-274250D01*
X-1590700Y-273000D01*
X-1590175Y-271250D01*
X-1590525Y-269500D01*
X-1591400Y-268000D01*
X-1592975Y-267000D01*
X-1595075Y-266500D01*
X-1596300Y-265500D01*
X-1596825Y-263750D01*
X-1596475Y-262000D01*
X-1595600Y-260750D01*
X-1594375Y-260000D01*
X-1593150D01*
X-1591925Y-260500D01*
X-1590875Y-261750D01*
G01X-1569825Y-275000D02*
X-1565450Y-260000D01*
X-1561075Y-275000D01*
G01X-1562650Y-269750D02*
X-1568250D01*
G01X-1554750Y-275000D02*
Y-260000D01*
X-1550375D01*
X-1548975Y-260750D01*
X-1548100Y-261750D01*
X-1547750Y-263750D01*
X-1548100Y-265750D01*
X-1549150Y-267000D01*
X-1550375Y-267750D01*
X-1554750D01*
G01X-1550375D02*
X-1547750Y-275000D01*
G01X-1533550D02*
X-1540550D01*
Y-260000D01*
X-1533550D01*
G01X-1536350Y-267250D02*
X-1540550D01*
G01X-1527225Y-275000D02*
X-1522850Y-260000D01*
X-1518475Y-275000D01*
G01X-1520050Y-269750D02*
X-1525650D01*
G01X-1498125Y-273000D02*
X-1496725Y-274250D01*
X-1495150Y-275000D01*
X-1493750D01*
X-1492350Y-274250D01*
X-1491300Y-273000D01*
X-1490775Y-271250D01*
X-1491125Y-269500D01*
X-1492000Y-268000D01*
X-1493575Y-267000D01*
X-1495675Y-266500D01*
X-1496900Y-265500D01*
X-1497425Y-263750D01*
X-1497075Y-262000D01*
X-1496200Y-260750D01*
X-1494975Y-260000D01*
X-1493750D01*
X-1492525Y-260500D01*
X-1491475Y-261750D01*
G01X-1483925Y-275000D02*
Y-260000D01*
G01X-1476575D02*
Y-275000D01*
G01Y-267500D02*
X-1483925D01*
G01X-1466050Y-275000D02*
X-1467450Y-274750D01*
X-1468675Y-273750D01*
X-1469725Y-272250D01*
X-1470425Y-270500D01*
X-1470775Y-268500D01*
Y-266500D01*
X-1470425Y-264500D01*
X-1469725Y-262750D01*
X-1468675Y-261250D01*
X-1467450Y-260250D01*
X-1466050Y-260000D01*
X-1464650Y-260250D01*
X-1463425Y-261250D01*
X-1462375Y-262750D01*
X-1461675Y-264500D01*
X-1461325Y-266500D01*
Y-268500D01*
X-1461675Y-270500D01*
X-1462375Y-272250D01*
X-1463425Y-273750D01*
X-1464650Y-274750D01*
X-1466050Y-275000D01*
G01X-1457100Y-260000D02*
X-1454650Y-275000D01*
X-1451850Y-260000D01*
X-1449050Y-275000D01*
X-1446600Y-260000D01*
G01X-1441675Y-275000D02*
Y-260000D01*
X-1433625Y-275000D01*
Y-260000D01*
G01X-1411350D02*
X-1407150D01*
G01X-1409250D02*
Y-275000D01*
G01X-1411350D02*
X-1407150D01*
G01X-1398725Y-273000D02*
X-1397325Y-274250D01*
X-1395750Y-275000D01*
X-1394350D01*
X-1392950Y-274250D01*
X-1391900Y-273000D01*
X-1391375Y-271250D01*
X-1391725Y-269500D01*
X-1392600Y-268000D01*
X-1394175Y-267000D01*
X-1396275Y-266500D01*
X-1397500Y-265500D01*
X-1398025Y-263750D01*
X-1397675Y-262000D01*
X-1396800Y-260750D01*
X-1395575Y-260000D01*
X-1394350D01*
X-1393125Y-260500D01*
X-1392075Y-261750D01*
G01X-1366650Y-260000D02*
Y-275000D01*
G01X-1370675Y-260000D02*
X-1362625D01*
G01X-1352450Y-275000D02*
X-1353850Y-274750D01*
X-1355075Y-273750D01*
X-1356125Y-272250D01*
X-1356825Y-270500D01*
X-1357175Y-268500D01*
Y-266500D01*
X-1356825Y-264500D01*
X-1356125Y-262750D01*
X-1355075Y-261250D01*
X-1353850Y-260250D01*
X-1352450Y-260000D01*
X-1351050Y-260250D01*
X-1349825Y-261250D01*
X-1348775Y-262750D01*
X-1348075Y-264500D01*
X-1347725Y-266500D01*
Y-268500D01*
X-1348075Y-270500D01*
X-1348775Y-272250D01*
X-1349825Y-273750D01*
X-1351050Y-274750D01*
X-1352450Y-275000D01*
G01X-1322650Y-267000D02*
X-1321950Y-266250D01*
X-1321425Y-265000D01*
X-1321075Y-263250D01*
X-1321425Y-261750D01*
X-1322125Y-260750D01*
X-1323350Y-260000D01*
X-1328075D01*
Y-275000D01*
X-1322300D01*
X-1321075Y-274000D01*
X-1320375Y-272500D01*
X-1320025Y-270750D01*
X-1320375Y-269000D01*
X-1321425Y-267500D01*
X-1322650Y-267000D01*
X-1328075D01*
G01X-1306350Y-275000D02*
X-1313350D01*
Y-260000D01*
X-1306350D01*
G01X-1309150Y-267250D02*
X-1313350D01*
G01X-1285300Y-260000D02*
Y-270750D01*
X-1284600Y-273000D01*
X-1283200Y-274500D01*
X-1281450Y-275000D01*
X-1279700Y-274500D01*
X-1278300Y-273000D01*
X-1277600Y-270750D01*
Y-260000D01*
G01X-1270925Y-273000D02*
X-1269525Y-274250D01*
X-1267950Y-275000D01*
X-1266550D01*
X-1265150Y-274250D01*
X-1264100Y-273000D01*
X-1263575Y-271250D01*
X-1263925Y-269500D01*
X-1264800Y-268000D01*
X-1266375Y-267000D01*
X-1268475Y-266500D01*
X-1269700Y-265500D01*
X-1270225Y-263750D01*
X-1269875Y-262000D01*
X-1269000Y-260750D01*
X-1267775Y-260000D01*
X-1266550D01*
X-1265325Y-260500D01*
X-1264275Y-261750D01*
G01X-1249550Y-275000D02*
X-1256550D01*
Y-260000D01*
X-1249550D01*
G01X-1252350Y-267250D02*
X-1256550D01*
G01X-1242700Y-275000D02*
Y-260000D01*
X-1239200D01*
X-1237800Y-260750D01*
X-1236750Y-261750D01*
X-1235875Y-263250D01*
X-1235175Y-265000D01*
X-1235000Y-267500D01*
X-1235175Y-270000D01*
X-1235875Y-271750D01*
X-1236750Y-273250D01*
X-1237800Y-274250D01*
X-1239200Y-275000D01*
X-1242700D01*
G01X-1210450Y-260000D02*
Y-275000D01*
G01X-1214475Y-260000D02*
X-1206425D01*
G01X-1196250Y-275000D02*
X-1197650Y-274750D01*
X-1198875Y-273750D01*
X-1199925Y-272250D01*
X-1200625Y-270500D01*
X-1200975Y-268500D01*
Y-266500D01*
X-1200625Y-264500D01*
X-1199925Y-262750D01*
X-1198875Y-261250D01*
X-1197650Y-260250D01*
X-1196250Y-260000D01*
X-1194850Y-260250D01*
X-1193625Y-261250D01*
X-1192575Y-262750D01*
X-1191875Y-264500D01*
X-1191525Y-266500D01*
Y-268500D01*
X-1191875Y-270500D01*
X-1192575Y-272250D01*
X-1193625Y-273750D01*
X-1194850Y-274750D01*
X-1196250Y-275000D01*
G01X-1172225Y-260000D02*
X-1167850Y-275000D01*
X-1163475Y-260000D01*
G01X-1155750D02*
X-1151550D01*
G01X-1153650D02*
Y-275000D01*
G01X-1155750D02*
X-1151550D01*
G01X-1143125Y-273000D02*
X-1141725Y-274250D01*
X-1140150Y-275000D01*
X-1138750D01*
X-1137350Y-274250D01*
X-1136300Y-273000D01*
X-1135775Y-271250D01*
X-1136125Y-269500D01*
X-1137000Y-268000D01*
X-1138575Y-267000D01*
X-1140675Y-266500D01*
X-1141900Y-265500D01*
X-1142425Y-263750D01*
X-1142075Y-262000D01*
X-1141200Y-260750D01*
X-1139975Y-260000D01*
X-1138750D01*
X-1137525Y-260500D01*
X-1136475Y-261750D01*
G01X-1129100Y-260000D02*
Y-270750D01*
X-1128400Y-273000D01*
X-1127000Y-274500D01*
X-1125250Y-275000D01*
X-1123500Y-274500D01*
X-1122100Y-273000D01*
X-1121400Y-270750D01*
Y-260000D01*
G01X-1115425Y-275000D02*
X-1111050Y-260000D01*
X-1106675Y-275000D01*
G01X-1108250Y-269750D02*
X-1113850D01*
G01X-1100350Y-260000D02*
Y-275000D01*
X-1093350D01*
G01X-1086150Y-260000D02*
Y-275000D01*
X-1079150D01*
G01X-1068450D02*
Y-268250D01*
X-1071950Y-260000D01*
G01X-1064950D02*
X-1068450Y-268250D01*
G01X-1044425Y-260000D02*
X-1040050Y-275000D01*
X-1035675Y-260000D01*
G01X-1022350Y-275000D02*
X-1029350D01*
Y-260000D01*
X-1022350D01*
G01X-1025150Y-267250D02*
X-1029350D01*
G01X-1015150Y-275000D02*
Y-260000D01*
X-1010775D01*
X-1009375Y-260750D01*
X-1008500Y-261750D01*
X-1008150Y-263750D01*
X-1008500Y-265750D01*
X-1009550Y-267000D01*
X-1010775Y-267750D01*
X-1015150D01*
G01X-1010775D02*
X-1008150Y-275000D01*
G01X-999550Y-260000D02*
X-995350D01*
G01X-997450D02*
Y-275000D01*
G01X-999550D02*
X-995350D01*
G01X-986575D02*
Y-260000D01*
X-979925D01*
G01X-982375Y-267250D02*
X-986575D01*
G01X-969050Y-275000D02*
Y-268250D01*
X-972550Y-260000D01*
G01X-965550D02*
X-969050Y-268250D01*
G01X-944150Y-275000D02*
Y-260000D01*
X-939950D01*
X-938550Y-260750D01*
X-937500Y-262500D01*
X-937150Y-264500D01*
X-937500Y-266500D01*
X-938375Y-268000D01*
X-939950Y-268750D01*
X-944150D01*
G01X-929950Y-275000D02*
Y-260000D01*
X-925575D01*
X-924175Y-260750D01*
X-923300Y-261750D01*
X-922950Y-263750D01*
X-923300Y-265750D01*
X-924350Y-267000D01*
X-925575Y-267750D01*
X-929950D01*
G01X-925575D02*
X-922950Y-275000D01*
G01X-912250D02*
X-913650Y-274750D01*
X-914875Y-273750D01*
X-915925Y-272250D01*
X-916625Y-270500D01*
X-916975Y-268500D01*
Y-266500D01*
X-916625Y-264500D01*
X-915925Y-262750D01*
X-914875Y-261250D01*
X-913650Y-260250D01*
X-912250Y-260000D01*
X-910850Y-260250D01*
X-909625Y-261250D01*
X-908575Y-262750D01*
X-907875Y-264500D01*
X-907525Y-266500D01*
Y-268500D01*
X-907875Y-270500D01*
X-908575Y-272250D01*
X-909625Y-273750D01*
X-910850Y-274750D01*
X-912250Y-275000D01*
G01X-901550D02*
Y-260000D01*
X-897350D01*
X-895950Y-260750D01*
X-894900Y-262500D01*
X-894550Y-264500D01*
X-894900Y-266500D01*
X-895775Y-268000D01*
X-897350Y-268750D01*
X-901550D01*
G01X-880350Y-275000D02*
X-887350D01*
Y-260000D01*
X-880350D01*
G01X-883150Y-267250D02*
X-887350D01*
G01X-873150Y-275000D02*
Y-260000D01*
X-868775D01*
X-867375Y-260750D01*
X-866500Y-261750D01*
X-866150Y-263750D01*
X-866500Y-265750D01*
X-867550Y-267000D01*
X-868775Y-267750D01*
X-873150D01*
G01X-868775D02*
X-866150Y-275000D01*
G01X-844750Y-260000D02*
Y-275000D01*
X-837750D01*
G01X-831425D02*
X-827050Y-260000D01*
X-822675Y-275000D01*
G01X-824250Y-269750D02*
X-829850D01*
G01X-812850Y-275000D02*
Y-268250D01*
X-816350Y-260000D01*
G01X-809350D02*
X-812850Y-268250D01*
G01X-795150Y-275000D02*
X-802150D01*
Y-260000D01*
X-795150D01*
G01X-797950Y-267250D02*
X-802150D01*
G01X-787950Y-275000D02*
Y-260000D01*
X-783575D01*
X-782175Y-260750D01*
X-781300Y-261750D01*
X-780950Y-263750D01*
X-781300Y-265750D01*
X-782350Y-267000D01*
X-783575Y-267750D01*
X-787950D01*
G01X-783575D02*
X-780950Y-275000D01*
G01X-759725Y-273000D02*
X-758325Y-274250D01*
X-756750Y-275000D01*
X-755350D01*
X-753950Y-274250D01*
X-752900Y-273000D01*
X-752375Y-271250D01*
X-752725Y-269500D01*
X-753600Y-268000D01*
X-755175Y-267000D01*
X-757275Y-266500D01*
X-758500Y-265500D01*
X-759025Y-263750D01*
X-758675Y-262000D01*
X-757800Y-260750D01*
X-756575Y-260000D01*
X-755350D01*
X-754125Y-260500D01*
X-753075Y-261750D01*
G01X-741850Y-260000D02*
Y-275000D01*
G01X-745875Y-260000D02*
X-737825D01*
G01X-732025Y-275000D02*
X-727650Y-260000D01*
X-723275Y-275000D01*
G01X-724850Y-269750D02*
X-730450D01*
G01X-709600Y-261250D02*
X-710650Y-260500D01*
X-711875Y-260000D01*
X-713275D01*
X-714850Y-260750D01*
X-716075Y-262000D01*
X-716950Y-263500D01*
X-717650Y-266000D01*
X-717825Y-268250D01*
X-717475Y-270500D01*
X-716950Y-272000D01*
X-715900Y-273500D01*
X-714675Y-274500D01*
X-713450Y-275000D01*
X-712225D01*
X-711000Y-274500D01*
X-709950Y-273750D01*
X-709075Y-272750D01*
G01X-703100Y-275000D02*
Y-260000D01*
G01X-696450D02*
X-703100Y-269250D01*
G01X-695400Y-275000D02*
X-700125Y-265000D01*
G01X-1639950Y-240000D02*
Y-225000D01*
X-1635575D01*
X-1634175Y-225750D01*
X-1633300Y-226750D01*
X-1632950Y-228750D01*
X-1633300Y-230750D01*
X-1634350Y-232000D01*
X-1635575Y-232750D01*
X-1639950D01*
G01X-1635575D02*
X-1632950Y-240000D01*
G01X-1618750D02*
X-1625750D01*
Y-225000D01*
X-1618750D01*
G01X-1621550Y-232250D02*
X-1625750D01*
G01X-1611550Y-240000D02*
Y-225000D01*
X-1607350D01*
X-1605950Y-225750D01*
X-1604900Y-227500D01*
X-1604550Y-229500D01*
X-1604900Y-231500D01*
X-1605775Y-233000D01*
X-1607350Y-233750D01*
X-1611550D01*
G01X-1593850Y-240000D02*
X-1595250Y-239750D01*
X-1596475Y-238750D01*
X-1597525Y-237250D01*
X-1598225Y-235500D01*
X-1598575Y-233500D01*
Y-231500D01*
X-1598225Y-229500D01*
X-1597525Y-227750D01*
X-1596475Y-226250D01*
X-1595250Y-225250D01*
X-1593850Y-225000D01*
X-1592450Y-225250D01*
X-1591225Y-226250D01*
X-1590175Y-227750D01*
X-1589475Y-229500D01*
X-1589125Y-231500D01*
Y-233500D01*
X-1589475Y-235500D01*
X-1590175Y-237250D01*
X-1591225Y-238750D01*
X-1592450Y-239750D01*
X-1593850Y-240000D01*
G01X-1583150D02*
Y-225000D01*
X-1578775D01*
X-1577375Y-225750D01*
X-1576500Y-226750D01*
X-1576150Y-228750D01*
X-1576500Y-230750D01*
X-1577550Y-232000D01*
X-1578775Y-232750D01*
X-1583150D01*
G01X-1578775D02*
X-1576150Y-240000D01*
G01X-1565450Y-225000D02*
Y-240000D01*
G01X-1569475Y-225000D02*
X-1561425D01*
G01X-1554925Y-238000D02*
X-1553525Y-239250D01*
X-1551950Y-240000D01*
X-1550550D01*
X-1549150Y-239250D01*
X-1548100Y-238000D01*
X-1547575Y-236250D01*
X-1547925Y-234500D01*
X-1548800Y-233000D01*
X-1550375Y-232000D01*
X-1552475Y-231500D01*
X-1553700Y-230500D01*
X-1554225Y-228750D01*
X-1553875Y-227000D01*
X-1553000Y-225750D01*
X-1551775Y-225000D01*
X-1550550D01*
X-1549325Y-225500D01*
X-1548275Y-226750D01*
G01X-1526350Y-240000D02*
Y-225000D01*
X-1522150D01*
X-1520750Y-225750D01*
X-1519700Y-227500D01*
X-1519350Y-229500D01*
X-1519700Y-231500D01*
X-1520575Y-233000D01*
X-1522150Y-233750D01*
X-1526350D01*
G01X-1505150Y-240000D02*
X-1512150D01*
Y-225000D01*
X-1505150D01*
G01X-1507950Y-232250D02*
X-1512150D01*
G01X-1497950Y-240000D02*
Y-225000D01*
X-1493575D01*
X-1492175Y-225750D01*
X-1491300Y-226750D01*
X-1490950Y-228750D01*
X-1491300Y-230750D01*
X-1492350Y-232000D01*
X-1493575Y-232750D01*
X-1497950D01*
G01X-1493575D02*
X-1490950Y-240000D01*
G01X-1469550Y-225000D02*
Y-240000D01*
X-1462550D01*
G01X-1451850D02*
X-1453250Y-239750D01*
X-1454475Y-238750D01*
X-1455525Y-237250D01*
X-1456225Y-235500D01*
X-1456575Y-233500D01*
Y-231500D01*
X-1456225Y-229500D01*
X-1455525Y-227750D01*
X-1454475Y-226250D01*
X-1453250Y-225250D01*
X-1451850Y-225000D01*
X-1450450Y-225250D01*
X-1449225Y-226250D01*
X-1448175Y-227750D01*
X-1447475Y-229500D01*
X-1447125Y-231500D01*
Y-233500D01*
X-1447475Y-235500D01*
X-1448175Y-237250D01*
X-1449225Y-238750D01*
X-1450450Y-239750D01*
X-1451850Y-240000D01*
G01X-1437650Y-225000D02*
Y-240000D01*
G01X-1441675Y-225000D02*
X-1433625D01*
G01X-1411350D02*
X-1407150D01*
G01X-1409250D02*
Y-240000D01*
G01X-1411350D02*
X-1407150D01*
G01X-1399075D02*
Y-225000D01*
X-1391025Y-240000D01*
Y-225000D01*
G01X-1384175Y-240000D02*
Y-225000D01*
X-1377525D01*
G01X-1379975Y-232250D02*
X-1384175D01*
G01X-1366650Y-240000D02*
X-1368050Y-239750D01*
X-1369275Y-238750D01*
X-1370325Y-237250D01*
X-1371025Y-235500D01*
X-1371375Y-233500D01*
Y-231500D01*
X-1371025Y-229500D01*
X-1370325Y-227750D01*
X-1369275Y-226250D01*
X-1368050Y-225250D01*
X-1366650Y-225000D01*
X-1365250Y-225250D01*
X-1364025Y-226250D01*
X-1362975Y-227750D01*
X-1362275Y-229500D01*
X-1361925Y-231500D01*
Y-233500D01*
X-1362275Y-235500D01*
X-1362975Y-237250D01*
X-1364025Y-238750D01*
X-1365250Y-239750D01*
X-1366650Y-240000D01*
G01X-1355950D02*
Y-225000D01*
X-1351575D01*
X-1350175Y-225750D01*
X-1349300Y-226750D01*
X-1348950Y-228750D01*
X-1349300Y-230750D01*
X-1350350Y-232000D01*
X-1351575Y-232750D01*
X-1355950D01*
G01X-1351575D02*
X-1348950Y-240000D01*
G01X-1342800D02*
Y-225000D01*
X-1338250Y-237500D01*
X-1333700Y-225000D01*
Y-240000D01*
G01X-1328425D02*
X-1324050Y-225000D01*
X-1319675Y-240000D01*
G01X-1321250Y-234750D02*
X-1326850D01*
G01X-1309850Y-225000D02*
Y-240000D01*
G01X-1313875Y-225000D02*
X-1305825D01*
G01X-1297750D02*
X-1293550D01*
G01X-1295650D02*
Y-240000D01*
G01X-1297750D02*
X-1293550D01*
G01X-1281450D02*
X-1282850Y-239750D01*
X-1284075Y-238750D01*
X-1285125Y-237250D01*
X-1285825Y-235500D01*
X-1286175Y-233500D01*
Y-231500D01*
X-1285825Y-229500D01*
X-1285125Y-227750D01*
X-1284075Y-226250D01*
X-1282850Y-225250D01*
X-1281450Y-225000D01*
X-1280050Y-225250D01*
X-1278825Y-226250D01*
X-1277775Y-227750D01*
X-1277075Y-229500D01*
X-1276725Y-231500D01*
Y-233500D01*
X-1277075Y-235500D01*
X-1277775Y-237250D01*
X-1278825Y-238750D01*
X-1280050Y-239750D01*
X-1281450Y-240000D01*
G01X-1271275D02*
Y-225000D01*
X-1263225Y-240000D01*
Y-225000D01*
G01X-1242350Y-240000D02*
Y-225000D01*
X-1238150D01*
X-1236750Y-225750D01*
X-1235700Y-227500D01*
X-1235350Y-229500D01*
X-1235700Y-231500D01*
X-1236575Y-233000D01*
X-1238150Y-233750D01*
X-1242350D01*
G01X-1221150Y-240000D02*
X-1228150D01*
Y-225000D01*
X-1221150D01*
G01X-1223950Y-232250D02*
X-1228150D01*
G01X-1213950Y-240000D02*
Y-225000D01*
X-1209575D01*
X-1208175Y-225750D01*
X-1207300Y-226750D01*
X-1206950Y-228750D01*
X-1207300Y-230750D01*
X-1208350Y-232000D01*
X-1209575Y-232750D01*
X-1213950D01*
G01X-1209575D02*
X-1206950Y-240000D01*
G01X-1185900D02*
Y-225000D01*
X-1182400D01*
X-1181000Y-225750D01*
X-1179950Y-226750D01*
X-1179075Y-228250D01*
X-1178375Y-230000D01*
X-1178200Y-232500D01*
X-1178375Y-235000D01*
X-1179075Y-236750D01*
X-1179950Y-238250D01*
X-1181000Y-239250D01*
X-1182400Y-240000D01*
X-1185900D01*
G01X-1172225D02*
X-1167850Y-225000D01*
X-1163475Y-240000D01*
G01X-1165050Y-234750D02*
X-1170650D01*
G01X-1153650Y-225000D02*
Y-240000D01*
G01X-1157675Y-225000D02*
X-1149625D01*
G01X-1135950Y-240000D02*
X-1142950D01*
Y-225000D01*
X-1135950D01*
G01X-1138750Y-232250D02*
X-1142950D01*
G01X-1107200Y-226250D02*
X-1108250Y-225500D01*
X-1109475Y-225000D01*
X-1110875D01*
X-1112450Y-225750D01*
X-1113675Y-227000D01*
X-1114550Y-228500D01*
X-1115250Y-231000D01*
X-1115425Y-233250D01*
X-1115075Y-235500D01*
X-1114550Y-237000D01*
X-1113500Y-238500D01*
X-1112275Y-239500D01*
X-1111050Y-240000D01*
X-1109825D01*
X-1108600Y-239500D01*
X-1107550Y-238750D01*
X-1106675Y-237750D01*
G01X-1096850Y-240000D02*
X-1098250Y-239750D01*
X-1099475Y-238750D01*
X-1100525Y-237250D01*
X-1101225Y-235500D01*
X-1101575Y-233500D01*
Y-231500D01*
X-1101225Y-229500D01*
X-1100525Y-227750D01*
X-1099475Y-226250D01*
X-1098250Y-225250D01*
X-1096850Y-225000D01*
X-1095450Y-225250D01*
X-1094225Y-226250D01*
X-1093175Y-227750D01*
X-1092475Y-229500D01*
X-1092125Y-231500D01*
Y-233500D01*
X-1092475Y-235500D01*
X-1093175Y-237250D01*
X-1094225Y-238750D01*
X-1095450Y-239750D01*
X-1096850Y-240000D01*
G01X-1086500D02*
Y-225000D01*
X-1083000D01*
X-1081600Y-225750D01*
X-1080550Y-226750D01*
X-1079675Y-228250D01*
X-1078975Y-230000D01*
X-1078800Y-232500D01*
X-1078975Y-235000D01*
X-1079675Y-236750D01*
X-1080550Y-238250D01*
X-1081600Y-239250D01*
X-1083000Y-240000D01*
X-1086500D01*
G01X-1064950D02*
X-1071950D01*
Y-225000D01*
X-1064950D01*
G01X-1067750Y-232250D02*
X-1071950D01*
G01X-1044600Y-240000D02*
Y-225000D01*
X-1040050Y-237500D01*
X-1035500Y-225000D01*
Y-240000D01*
G01X-1029700Y-225000D02*
Y-235750D01*
X-1029000Y-238000D01*
X-1027600Y-239500D01*
X-1025850Y-240000D01*
X-1024100Y-239500D01*
X-1022700Y-238000D01*
X-1022000Y-235750D01*
Y-225000D01*
G01X-1015325Y-238000D02*
X-1013925Y-239250D01*
X-1012350Y-240000D01*
X-1010950D01*
X-1009550Y-239250D01*
X-1008500Y-238000D01*
X-1007975Y-236250D01*
X-1008325Y-234500D01*
X-1009200Y-233000D01*
X-1010775Y-232000D01*
X-1012875Y-231500D01*
X-1014100Y-230500D01*
X-1014625Y-228750D01*
X-1014275Y-227000D01*
X-1013400Y-225750D01*
X-1012175Y-225000D01*
X-1010950D01*
X-1009725Y-225500D01*
X-1008675Y-226750D01*
G01X-997450Y-225000D02*
Y-240000D01*
G01X-1001475Y-225000D02*
X-993425D01*
G01X-967650Y-232000D02*
X-966950Y-231250D01*
X-966425Y-230000D01*
X-966075Y-228250D01*
X-966425Y-226750D01*
X-967125Y-225750D01*
X-968350Y-225000D01*
X-973075D01*
Y-240000D01*
X-967300D01*
X-966075Y-239000D01*
X-965375Y-237500D01*
X-965025Y-235750D01*
X-965375Y-234000D01*
X-966425Y-232500D01*
X-967650Y-232000D01*
X-973075D01*
G01X-951350Y-240000D02*
X-958350D01*
Y-225000D01*
X-951350D01*
G01X-954150Y-232250D02*
X-958350D01*
G01X-930825Y-240000D02*
X-926450Y-225000D01*
X-922075Y-240000D01*
G01X-923650Y-234750D02*
X-929250D01*
G01X-916625Y-225000D02*
X-912250Y-240000D01*
X-907875Y-225000D01*
G01X-902425Y-240000D02*
X-898050Y-225000D01*
X-893675Y-240000D01*
G01X-895250Y-234750D02*
X-900850D01*
G01X-885950Y-225000D02*
X-881750D01*
G01X-883850D02*
Y-240000D01*
G01X-885950D02*
X-881750D01*
G01X-873150Y-225000D02*
Y-240000D01*
X-866150D01*
G01X-859825D02*
X-855450Y-225000D01*
X-851075Y-240000D01*
G01X-852650Y-234750D02*
X-858250D01*
G01X-839850Y-232000D02*
X-839150Y-231250D01*
X-838625Y-230000D01*
X-838275Y-228250D01*
X-838625Y-226750D01*
X-839325Y-225750D01*
X-840550Y-225000D01*
X-845275D01*
Y-240000D01*
X-839500D01*
X-838275Y-239000D01*
X-837575Y-237500D01*
X-837225Y-235750D01*
X-837575Y-234000D01*
X-838625Y-232500D01*
X-839850Y-232000D01*
X-845275D01*
G01X-830550Y-225000D02*
Y-240000D01*
X-823550D01*
G01X-809350D02*
X-816350D01*
Y-225000D01*
X-809350D01*
G01X-812150Y-232250D02*
X-816350D01*
G01X-788300Y-225000D02*
Y-235750D01*
X-787600Y-238000D01*
X-786200Y-239500D01*
X-784450Y-240000D01*
X-782700Y-239500D01*
X-781300Y-238000D01*
X-780600Y-235750D01*
Y-225000D01*
G01X-773750Y-240000D02*
Y-225000D01*
X-769550D01*
X-768150Y-225750D01*
X-767100Y-227500D01*
X-766750Y-229500D01*
X-767100Y-231500D01*
X-767975Y-233000D01*
X-769550Y-233750D01*
X-773750D01*
G01X-756050Y-240000D02*
X-757450Y-239750D01*
X-758675Y-238750D01*
X-759725Y-237250D01*
X-760425Y-235500D01*
X-760775Y-233500D01*
Y-231500D01*
X-760425Y-229500D01*
X-759725Y-227750D01*
X-758675Y-226250D01*
X-757450Y-225250D01*
X-756050Y-225000D01*
X-754650Y-225250D01*
X-753425Y-226250D01*
X-752375Y-227750D01*
X-751675Y-229500D01*
X-751325Y-231500D01*
Y-233500D01*
X-751675Y-235500D01*
X-752375Y-237250D01*
X-753425Y-238750D01*
X-754650Y-239750D01*
X-756050Y-240000D01*
G01X-745875D02*
Y-225000D01*
X-737825Y-240000D01*
Y-225000D01*
G01X-716950Y-240000D02*
Y-225000D01*
X-712575D01*
X-711175Y-225750D01*
X-710300Y-226750D01*
X-709950Y-228750D01*
X-710300Y-230750D01*
X-711350Y-232000D01*
X-712575Y-232750D01*
X-716950D01*
G01X-712575D02*
X-709950Y-240000D01*
G01X-695750D02*
X-702750D01*
Y-225000D01*
X-695750D01*
G01X-698550Y-232250D02*
X-702750D01*
G01X-685050Y-240000D02*
X-686450Y-239750D01*
X-687675Y-238750D01*
X-688725Y-237250D01*
X-689425Y-235500D01*
X-689775Y-233500D01*
Y-231500D01*
X-689425Y-229500D01*
X-688725Y-227750D01*
X-687675Y-226250D01*
X-686450Y-225250D01*
X-685050Y-225000D01*
X-683650Y-225250D01*
X-682425Y-226250D01*
X-681375Y-227750D01*
X-680675Y-229500D01*
X-680325Y-231500D01*
Y-233500D01*
X-680675Y-235500D01*
X-681375Y-237250D01*
X-682425Y-238750D01*
X-683650Y-239750D01*
X-685050Y-240000D01*
G01X-683650Y-236000D02*
X-681550Y-240000D01*
G01X-674700Y-225000D02*
Y-235750D01*
X-674000Y-238000D01*
X-672600Y-239500D01*
X-670850Y-240000D01*
X-669100Y-239500D01*
X-667700Y-238000D01*
X-667000Y-235750D01*
Y-225000D01*
G01X-653150Y-240000D02*
X-660150D01*
Y-225000D01*
X-653150D01*
G01X-655950Y-232250D02*
X-660150D01*
G01X-646125Y-238000D02*
X-644725Y-239250D01*
X-643150Y-240000D01*
X-641750D01*
X-640350Y-239250D01*
X-639300Y-238000D01*
X-638775Y-236250D01*
X-639125Y-234500D01*
X-640000Y-233000D01*
X-641575Y-232000D01*
X-643675Y-231500D01*
X-644900Y-230500D01*
X-645425Y-228750D01*
X-645075Y-227000D01*
X-644200Y-225750D01*
X-642975Y-225000D01*
X-641750D01*
X-640525Y-225500D01*
X-639475Y-226750D01*
G01X-628250Y-225000D02*
Y-240000D01*
G01X-632275Y-225000D02*
X-624225D01*
G01X-614050Y-240500D02*
X-614400Y-240250D01*
Y-239750D01*
X-614050Y-239500D01*
X-613700Y-239750D01*
Y-240250D01*
X-614050Y-240500D01*
G01X-1641000Y-210000D02*
Y-195000D01*
X-1636450Y-207500D01*
X-1631900Y-195000D01*
Y-210000D01*
G01X-1626100Y-195000D02*
Y-205750D01*
X-1625400Y-208000D01*
X-1624000Y-209500D01*
X-1622250Y-210000D01*
X-1620500Y-209500D01*
X-1619100Y-208000D01*
X-1618400Y-205750D01*
Y-195000D01*
G01X-1611725Y-208000D02*
X-1610325Y-209250D01*
X-1608750Y-210000D01*
X-1607350D01*
X-1605950Y-209250D01*
X-1604900Y-208000D01*
X-1604375Y-206250D01*
X-1604725Y-204500D01*
X-1605600Y-203000D01*
X-1607175Y-202000D01*
X-1609275Y-201500D01*
X-1610500Y-200500D01*
X-1611025Y-198750D01*
X-1610675Y-197000D01*
X-1609800Y-195750D01*
X-1608575Y-195000D01*
X-1607350D01*
X-1606125Y-195500D01*
X-1605075Y-196750D01*
G01X-1593850Y-195000D02*
Y-210000D01*
G01X-1597875Y-195000D02*
X-1589825D01*
G01X-1564050Y-202000D02*
X-1563350Y-201250D01*
X-1562825Y-200000D01*
X-1562475Y-198250D01*
X-1562825Y-196750D01*
X-1563525Y-195750D01*
X-1564750Y-195000D01*
X-1569475D01*
Y-210000D01*
X-1563700D01*
X-1562475Y-209000D01*
X-1561775Y-207500D01*
X-1561425Y-205750D01*
X-1561775Y-204000D01*
X-1562825Y-202500D01*
X-1564050Y-202000D01*
X-1569475D01*
G01X-1547750Y-210000D02*
X-1554750D01*
Y-195000D01*
X-1547750D01*
G01X-1550550Y-202250D02*
X-1554750D01*
G01X-1527400Y-210000D02*
Y-195000D01*
X-1522850Y-207500D01*
X-1518300Y-195000D01*
Y-210000D01*
G01X-1513025D02*
X-1508650Y-195000D01*
X-1504275Y-210000D01*
G01X-1505850Y-204750D02*
X-1511450D01*
G01X-1496550Y-195000D02*
X-1492350D01*
G01X-1494450D02*
Y-210000D01*
G01X-1496550D02*
X-1492350D01*
G01X-1484275D02*
Y-195000D01*
X-1476225Y-210000D01*
Y-195000D01*
G01X-1466050D02*
Y-210000D01*
G01X-1470075Y-195000D02*
X-1462025D01*
G01X-1456225Y-210000D02*
X-1451850Y-195000D01*
X-1447475Y-210000D01*
G01X-1449050Y-204750D02*
X-1454650D01*
G01X-1439750Y-195000D02*
X-1435550D01*
G01X-1437650D02*
Y-210000D01*
G01X-1439750D02*
X-1435550D01*
G01X-1427475D02*
Y-195000D01*
X-1419425Y-210000D01*
Y-195000D01*
G01X-1405750Y-210000D02*
X-1412750D01*
Y-195000D01*
X-1405750D01*
G01X-1408550Y-202250D02*
X-1412750D01*
G01X-1398900Y-210000D02*
Y-195000D01*
X-1395400D01*
X-1394000Y-195750D01*
X-1392950Y-196750D01*
X-1392075Y-198250D01*
X-1391375Y-200000D01*
X-1391200Y-202500D01*
X-1391375Y-205000D01*
X-1392075Y-206750D01*
X-1392950Y-208250D01*
X-1394000Y-209250D01*
X-1395400Y-210000D01*
X-1398900D01*
G01X-1365250Y-202000D02*
X-1364550Y-201250D01*
X-1364025Y-200000D01*
X-1363675Y-198250D01*
X-1364025Y-196750D01*
X-1364725Y-195750D01*
X-1365950Y-195000D01*
X-1370675D01*
Y-210000D01*
X-1364900D01*
X-1363675Y-209000D01*
X-1362975Y-207500D01*
X-1362625Y-205750D01*
X-1362975Y-204000D01*
X-1364025Y-202500D01*
X-1365250Y-202000D01*
X-1370675D01*
G01X-1352450Y-210000D02*
Y-203250D01*
X-1355950Y-195000D01*
G01X-1348950D02*
X-1352450Y-203250D01*
G01X-1327725Y-208000D02*
X-1326325Y-209250D01*
X-1324750Y-210000D01*
X-1323350D01*
X-1321950Y-209250D01*
X-1320900Y-208000D01*
X-1320375Y-206250D01*
X-1320725Y-204500D01*
X-1321600Y-203000D01*
X-1323175Y-202000D01*
X-1325275Y-201500D01*
X-1326500Y-200500D01*
X-1327025Y-198750D01*
X-1326675Y-197000D01*
X-1325800Y-195750D01*
X-1324575Y-195000D01*
X-1323350D01*
X-1322125Y-195500D01*
X-1321075Y-196750D01*
G01X-1313700Y-195000D02*
Y-205750D01*
X-1313000Y-208000D01*
X-1311600Y-209500D01*
X-1309850Y-210000D01*
X-1308100Y-209500D01*
X-1306700Y-208000D01*
X-1306000Y-205750D01*
Y-195000D01*
G01X-1299150Y-210000D02*
Y-195000D01*
X-1294950D01*
X-1293550Y-195750D01*
X-1292500Y-197500D01*
X-1292150Y-199500D01*
X-1292500Y-201500D01*
X-1293375Y-203000D01*
X-1294950Y-203750D01*
X-1299150D01*
G01X-1284950Y-210000D02*
Y-195000D01*
X-1280750D01*
X-1279350Y-195750D01*
X-1278300Y-197500D01*
X-1277950Y-199500D01*
X-1278300Y-201500D01*
X-1279175Y-203000D01*
X-1280750Y-203750D01*
X-1284950D01*
G01X-1270750Y-195000D02*
Y-210000D01*
X-1263750D01*
G01X-1255150Y-195000D02*
X-1250950D01*
G01X-1253050D02*
Y-210000D01*
G01X-1255150D02*
X-1250950D01*
G01X-1235350D02*
X-1242350D01*
Y-195000D01*
X-1235350D01*
G01X-1238150Y-202250D02*
X-1242350D01*
G01X-1228150Y-210000D02*
Y-195000D01*
X-1223775D01*
X-1222375Y-195750D01*
X-1221500Y-196750D01*
X-1221150Y-198750D01*
X-1221500Y-200750D01*
X-1222550Y-202000D01*
X-1223775Y-202750D01*
X-1228150D01*
G01X-1223775D02*
X-1221150Y-210000D01*
G01X-1199575D02*
Y-195000D01*
X-1192925D01*
G01X-1195375Y-202250D02*
X-1199575D01*
G01X-1182050Y-210000D02*
X-1183450Y-209750D01*
X-1184675Y-208750D01*
X-1185725Y-207250D01*
X-1186425Y-205500D01*
X-1186775Y-203500D01*
Y-201500D01*
X-1186425Y-199500D01*
X-1185725Y-197750D01*
X-1184675Y-196250D01*
X-1183450Y-195250D01*
X-1182050Y-195000D01*
X-1180650Y-195250D01*
X-1179425Y-196250D01*
X-1178375Y-197750D01*
X-1177675Y-199500D01*
X-1177325Y-201500D01*
Y-203500D01*
X-1177675Y-205500D01*
X-1178375Y-207250D01*
X-1179425Y-208750D01*
X-1180650Y-209750D01*
X-1182050Y-210000D01*
G01X-1171350D02*
Y-195000D01*
X-1166975D01*
X-1165575Y-195750D01*
X-1164700Y-196750D01*
X-1164350Y-198750D01*
X-1164700Y-200750D01*
X-1165750Y-202000D01*
X-1166975Y-202750D01*
X-1171350D01*
G01X-1166975D02*
X-1164350Y-210000D01*
G01X-1142950D02*
Y-195000D01*
X-1138575D01*
X-1137175Y-195750D01*
X-1136300Y-196750D01*
X-1135950Y-198750D01*
X-1136300Y-200750D01*
X-1137350Y-202000D01*
X-1138575Y-202750D01*
X-1142950D01*
G01X-1138575D02*
X-1135950Y-210000D01*
G01X-1121750D02*
X-1128750D01*
Y-195000D01*
X-1121750D01*
G01X-1124550Y-202250D02*
X-1128750D01*
G01X-1114375Y-210000D02*
Y-195000D01*
X-1107725D01*
G01X-1110175Y-202250D02*
X-1114375D01*
G01X-1093350Y-210000D02*
X-1100350D01*
Y-195000D01*
X-1093350D01*
G01X-1096150Y-202250D02*
X-1100350D01*
G01X-1086150Y-210000D02*
Y-195000D01*
X-1081775D01*
X-1080375Y-195750D01*
X-1079500Y-196750D01*
X-1079150Y-198750D01*
X-1079500Y-200750D01*
X-1080550Y-202000D01*
X-1081775Y-202750D01*
X-1086150D01*
G01X-1081775D02*
X-1079150Y-210000D01*
G01X-1064950D02*
X-1071950D01*
Y-195000D01*
X-1064950D01*
G01X-1067750Y-202250D02*
X-1071950D01*
G01X-1058275Y-210000D02*
Y-195000D01*
X-1050225Y-210000D01*
Y-195000D01*
G01X-1036200Y-196250D02*
X-1037250Y-195500D01*
X-1038475Y-195000D01*
X-1039875D01*
X-1041450Y-195750D01*
X-1042675Y-197000D01*
X-1043550Y-198500D01*
X-1044250Y-201000D01*
X-1044425Y-203250D01*
X-1044075Y-205500D01*
X-1043550Y-207000D01*
X-1042500Y-208500D01*
X-1041275Y-209500D01*
X-1040050Y-210000D01*
X-1038825D01*
X-1037600Y-209500D01*
X-1036550Y-208750D01*
X-1035675Y-207750D01*
G01X-1022350Y-210000D02*
X-1029350D01*
Y-195000D01*
X-1022350D01*
G01X-1025150Y-202250D02*
X-1029350D01*
G01X-996050Y-202000D02*
X-995350Y-201250D01*
X-994825Y-200000D01*
X-994475Y-198250D01*
X-994825Y-196750D01*
X-995525Y-195750D01*
X-996750Y-195000D01*
X-1001475D01*
Y-210000D01*
X-995700D01*
X-994475Y-209000D01*
X-993775Y-207500D01*
X-993425Y-205750D01*
X-993775Y-204000D01*
X-994825Y-202500D01*
X-996050Y-202000D01*
X-1001475D01*
G01X-983250Y-210000D02*
Y-203250D01*
X-986750Y-195000D01*
G01X-979750D02*
X-983250Y-203250D01*
G01X-958700Y-210000D02*
Y-195000D01*
X-955200D01*
X-953800Y-195750D01*
X-952750Y-196750D01*
X-951875Y-198250D01*
X-951175Y-200000D01*
X-951000Y-202500D01*
X-951175Y-205000D01*
X-951875Y-206750D01*
X-952750Y-208250D01*
X-953800Y-209250D01*
X-955200Y-210000D01*
X-958700D01*
G01X-937150D02*
X-944150D01*
Y-195000D01*
X-937150D01*
G01X-939950Y-202250D02*
X-944150D01*
G01X-930125Y-208000D02*
X-928725Y-209250D01*
X-927150Y-210000D01*
X-925750D01*
X-924350Y-209250D01*
X-923300Y-208000D01*
X-922775Y-206250D01*
X-923125Y-204500D01*
X-924000Y-203000D01*
X-925575Y-202000D01*
X-927675Y-201500D01*
X-928900Y-200500D01*
X-929425Y-198750D01*
X-929075Y-197000D01*
X-928200Y-195750D01*
X-926975Y-195000D01*
X-925750D01*
X-924525Y-195500D01*
X-923475Y-196750D01*
G01X-914350Y-195000D02*
X-910150D01*
G01X-912250D02*
Y-210000D01*
G01X-914350D02*
X-910150D01*
G01X-897000Y-202500D02*
X-893500D01*
Y-207000D01*
X-894550Y-208500D01*
X-895775Y-209500D01*
X-897525Y-210000D01*
X-899275Y-209500D01*
X-900500Y-208500D01*
X-901550Y-207000D01*
X-902250Y-205250D01*
X-902600Y-203250D01*
Y-201500D01*
X-902250Y-200000D01*
X-901550Y-198250D01*
X-900500Y-196750D01*
X-899450Y-195750D01*
X-898050Y-195000D01*
X-896825D01*
X-895425Y-195500D01*
X-894375Y-196500D01*
G01X-887875Y-210000D02*
Y-195000D01*
X-879825Y-210000D01*
Y-195000D01*
G01X-855450D02*
Y-210000D01*
G01X-859475Y-195000D02*
X-851425D01*
G01X-837750Y-210000D02*
X-844750D01*
Y-195000D01*
X-837750D01*
G01X-840550Y-202250D02*
X-844750D01*
G01X-831425Y-210000D02*
X-827050Y-195000D01*
X-822675Y-210000D01*
G01X-824250Y-204750D02*
X-829850D01*
G01X-817400Y-210000D02*
Y-195000D01*
X-812850Y-207500D01*
X-808300Y-195000D01*
Y-210000D01*
G01X-788825D02*
X-784450Y-195000D01*
X-780075Y-210000D01*
G01X-781650Y-204750D02*
X-787250D01*
G01X-773925Y-208000D02*
X-772525Y-209250D01*
X-770950Y-210000D01*
X-769550D01*
X-768150Y-209250D01*
X-767100Y-208000D01*
X-766575Y-206250D01*
X-766925Y-204500D01*
X-767800Y-203000D01*
X-769375Y-202000D01*
X-771475Y-201500D01*
X-772700Y-200500D01*
X-773225Y-198750D01*
X-772875Y-197000D01*
X-772000Y-195750D01*
X-770775Y-195000D01*
X-769550D01*
X-768325Y-195500D01*
X-767275Y-196750D01*
G01X-745350Y-210000D02*
Y-195000D01*
X-740975D01*
X-739575Y-195750D01*
X-738700Y-196750D01*
X-738350Y-198750D01*
X-738700Y-200750D01*
X-739750Y-202000D01*
X-740975Y-202750D01*
X-745350D01*
G01X-740975D02*
X-738350Y-210000D01*
G01X-724150D02*
X-731150D01*
Y-195000D01*
X-724150D01*
G01X-726950Y-202250D02*
X-731150D01*
G01X-713450Y-210000D02*
X-714850Y-209750D01*
X-716075Y-208750D01*
X-717125Y-207250D01*
X-717825Y-205500D01*
X-718175Y-203500D01*
Y-201500D01*
X-717825Y-199500D01*
X-717125Y-197750D01*
X-716075Y-196250D01*
X-714850Y-195250D01*
X-713450Y-195000D01*
X-712050Y-195250D01*
X-710825Y-196250D01*
X-709775Y-197750D01*
X-709075Y-199500D01*
X-708725Y-201500D01*
Y-203500D01*
X-709075Y-205500D01*
X-709775Y-207250D01*
X-710825Y-208750D01*
X-712050Y-209750D01*
X-713450Y-210000D01*
G01X-712050Y-206000D02*
X-709950Y-210000D01*
G01X-703100Y-195000D02*
Y-205750D01*
X-702400Y-208000D01*
X-701000Y-209500D01*
X-699250Y-210000D01*
X-697500Y-209500D01*
X-696100Y-208000D01*
X-695400Y-205750D01*
Y-195000D01*
G01X-687150D02*
X-682950D01*
G01X-685050D02*
Y-210000D01*
G01X-687150D02*
X-682950D01*
G01X-674350D02*
Y-195000D01*
X-669975D01*
X-668575Y-195750D01*
X-667700Y-196750D01*
X-667350Y-198750D01*
X-667700Y-200750D01*
X-668750Y-202000D01*
X-669975Y-202750D01*
X-674350D01*
G01X-669975D02*
X-667350Y-210000D01*
G01X-653150D02*
X-660150D01*
Y-195000D01*
X-653150D01*
G01X-655950Y-202250D02*
X-660150D01*
G01X-646300Y-210000D02*
Y-195000D01*
X-642800D01*
X-641400Y-195750D01*
X-640350Y-196750D01*
X-639475Y-198250D01*
X-638775Y-200000D01*
X-638600Y-202500D01*
X-638775Y-205000D01*
X-639475Y-206750D01*
X-640350Y-208250D01*
X-641400Y-209250D01*
X-642800Y-210000D01*
X-646300D01*
G01X-628250Y-210500D02*
X-628600Y-210250D01*
Y-209750D01*
X-628250Y-209500D01*
X-627900Y-209750D01*
Y-210250D01*
X-628250Y-210500D01*
G01X-1639775Y-180000D02*
Y-165000D01*
X-1633125D01*
G01X-1635575Y-172250D02*
X-1639775D01*
G01X-1626100Y-165000D02*
Y-175750D01*
X-1625400Y-178000D01*
X-1624000Y-179500D01*
X-1622250Y-180000D01*
X-1620500Y-179500D01*
X-1619100Y-178000D01*
X-1618400Y-175750D01*
Y-165000D01*
G01X-1611550D02*
Y-180000D01*
X-1604550D01*
G01X-1597350Y-165000D02*
Y-180000D01*
X-1590350D01*
G01X-1569825D02*
X-1565450Y-165000D01*
X-1561075Y-180000D01*
G01X-1562650Y-174750D02*
X-1568250D01*
G01X-1555275Y-180000D02*
Y-165000D01*
X-1547225Y-180000D01*
Y-165000D01*
G01X-1540900Y-180000D02*
Y-165000D01*
X-1537400D01*
X-1536000Y-165750D01*
X-1534950Y-166750D01*
X-1534075Y-168250D01*
X-1533375Y-170000D01*
X-1533200Y-172500D01*
X-1533375Y-175000D01*
X-1534075Y-176750D01*
X-1534950Y-178250D01*
X-1536000Y-179250D01*
X-1537400Y-180000D01*
X-1540900D01*
G01X-1513025D02*
X-1508650Y-165000D01*
X-1504275Y-180000D01*
G01X-1505850Y-174750D02*
X-1511450D01*
G01X-1490600Y-166250D02*
X-1491650Y-165500D01*
X-1492875Y-165000D01*
X-1494275D01*
X-1495850Y-165750D01*
X-1497075Y-167000D01*
X-1497950Y-168500D01*
X-1498650Y-171000D01*
X-1498825Y-173250D01*
X-1498475Y-175500D01*
X-1497950Y-177000D01*
X-1496900Y-178500D01*
X-1495675Y-179500D01*
X-1494450Y-180000D01*
X-1493225D01*
X-1492000Y-179500D01*
X-1490950Y-178750D01*
X-1490075Y-177750D01*
G01X-1476400Y-166250D02*
X-1477450Y-165500D01*
X-1478675Y-165000D01*
X-1480075D01*
X-1481650Y-165750D01*
X-1482875Y-167000D01*
X-1483750Y-168500D01*
X-1484450Y-171000D01*
X-1484625Y-173250D01*
X-1484275Y-175500D01*
X-1483750Y-177000D01*
X-1482700Y-178500D01*
X-1481475Y-179500D01*
X-1480250Y-180000D01*
X-1479025D01*
X-1477800Y-179500D01*
X-1476750Y-178750D01*
X-1475875Y-177750D01*
G01X-1469900Y-165000D02*
Y-175750D01*
X-1469200Y-178000D01*
X-1467800Y-179500D01*
X-1466050Y-180000D01*
X-1464300Y-179500D01*
X-1462900Y-178000D01*
X-1462200Y-175750D01*
Y-165000D01*
G01X-1455350Y-180000D02*
Y-165000D01*
X-1450975D01*
X-1449575Y-165750D01*
X-1448700Y-166750D01*
X-1448350Y-168750D01*
X-1448700Y-170750D01*
X-1449750Y-172000D01*
X-1450975Y-172750D01*
X-1455350D01*
G01X-1450975D02*
X-1448350Y-180000D01*
G01X-1442025D02*
X-1437650Y-165000D01*
X-1433275Y-180000D01*
G01X-1434850Y-174750D02*
X-1440450D01*
G01X-1423450Y-165000D02*
Y-180000D01*
G01X-1427475Y-165000D02*
X-1419425D01*
G01X-1405750Y-180000D02*
X-1412750D01*
Y-165000D01*
X-1405750D01*
G01X-1408550Y-172250D02*
X-1412750D01*
G01X-1384350Y-180000D02*
Y-165000D01*
X-1379975D01*
X-1378575Y-165750D01*
X-1377700Y-166750D01*
X-1377350Y-168750D01*
X-1377700Y-170750D01*
X-1378750Y-172000D01*
X-1379975Y-172750D01*
X-1384350D01*
G01X-1379975D02*
X-1377350Y-180000D01*
G01X-1363150D02*
X-1370150D01*
Y-165000D01*
X-1363150D01*
G01X-1365950Y-172250D02*
X-1370150D01*
G01X-1355950Y-180000D02*
Y-165000D01*
X-1351750D01*
X-1350350Y-165750D01*
X-1349300Y-167500D01*
X-1348950Y-169500D01*
X-1349300Y-171500D01*
X-1350175Y-173000D01*
X-1351750Y-173750D01*
X-1355950D01*
G01X-1338250Y-180000D02*
X-1339650Y-179750D01*
X-1340875Y-178750D01*
X-1341925Y-177250D01*
X-1342625Y-175500D01*
X-1342975Y-173500D01*
Y-171500D01*
X-1342625Y-169500D01*
X-1341925Y-167750D01*
X-1340875Y-166250D01*
X-1339650Y-165250D01*
X-1338250Y-165000D01*
X-1336850Y-165250D01*
X-1335625Y-166250D01*
X-1334575Y-167750D01*
X-1333875Y-169500D01*
X-1333525Y-171500D01*
Y-173500D01*
X-1333875Y-175500D01*
X-1334575Y-177250D01*
X-1335625Y-178750D01*
X-1336850Y-179750D01*
X-1338250Y-180000D01*
G01X-1327550D02*
Y-165000D01*
X-1323175D01*
X-1321775Y-165750D01*
X-1320900Y-166750D01*
X-1320550Y-168750D01*
X-1320900Y-170750D01*
X-1321950Y-172000D01*
X-1323175Y-172750D01*
X-1327550D01*
G01X-1323175D02*
X-1320550Y-180000D01*
G01X-1309850Y-165000D02*
Y-180000D01*
G01X-1313875Y-165000D02*
X-1305825D01*
G01X-1297750D02*
X-1293550D01*
G01X-1295650D02*
Y-180000D01*
G01X-1297750D02*
X-1293550D01*
G01X-1285475D02*
Y-165000D01*
X-1277425Y-180000D01*
Y-165000D01*
G01X-1266200Y-172500D02*
X-1262700D01*
Y-177000D01*
X-1263750Y-178500D01*
X-1264975Y-179500D01*
X-1266725Y-180000D01*
X-1268475Y-179500D01*
X-1269700Y-178500D01*
X-1270750Y-177000D01*
X-1271450Y-175250D01*
X-1271800Y-173250D01*
Y-171500D01*
X-1271450Y-170000D01*
X-1270750Y-168250D01*
X-1269700Y-166750D01*
X-1268650Y-165750D01*
X-1267250Y-165000D01*
X-1266025D01*
X-1264625Y-165500D01*
X-1263575Y-166500D01*
G01X-1243225Y-180000D02*
X-1238850Y-165000D01*
X-1234475Y-180000D01*
G01X-1236050Y-174750D02*
X-1241650D01*
G01X-1228675Y-180000D02*
Y-165000D01*
X-1220625Y-180000D01*
Y-165000D01*
G01X-1214300Y-180000D02*
Y-165000D01*
X-1210800D01*
X-1209400Y-165750D01*
X-1208350Y-166750D01*
X-1207475Y-168250D01*
X-1206775Y-170000D01*
X-1206600Y-172500D01*
X-1206775Y-175000D01*
X-1207475Y-176750D01*
X-1208350Y-178250D01*
X-1209400Y-179250D01*
X-1210800Y-180000D01*
X-1214300D01*
G01X-1178200Y-166250D02*
X-1179250Y-165500D01*
X-1180475Y-165000D01*
X-1181875D01*
X-1183450Y-165750D01*
X-1184675Y-167000D01*
X-1185550Y-168500D01*
X-1186250Y-171000D01*
X-1186425Y-173250D01*
X-1186075Y-175500D01*
X-1185550Y-177000D01*
X-1184500Y-178500D01*
X-1183275Y-179500D01*
X-1182050Y-180000D01*
X-1180825D01*
X-1179600Y-179500D01*
X-1178550Y-178750D01*
X-1177675Y-177750D01*
G01X-1167850Y-180000D02*
X-1169250Y-179750D01*
X-1170475Y-178750D01*
X-1171525Y-177250D01*
X-1172225Y-175500D01*
X-1172575Y-173500D01*
Y-171500D01*
X-1172225Y-169500D01*
X-1171525Y-167750D01*
X-1170475Y-166250D01*
X-1169250Y-165250D01*
X-1167850Y-165000D01*
X-1166450Y-165250D01*
X-1165225Y-166250D01*
X-1164175Y-167750D01*
X-1163475Y-169500D01*
X-1163125Y-171500D01*
Y-173500D01*
X-1163475Y-175500D01*
X-1164175Y-177250D01*
X-1165225Y-178750D01*
X-1166450Y-179750D01*
X-1167850Y-180000D01*
G01X-1157500Y-165000D02*
Y-175750D01*
X-1156800Y-178000D01*
X-1155400Y-179500D01*
X-1153650Y-180000D01*
X-1151900Y-179500D01*
X-1150500Y-178000D01*
X-1149800Y-175750D01*
Y-165000D01*
G01X-1142950Y-180000D02*
Y-165000D01*
X-1138750D01*
X-1137350Y-165750D01*
X-1136300Y-167500D01*
X-1135950Y-169500D01*
X-1136300Y-171500D01*
X-1137175Y-173000D01*
X-1138750Y-173750D01*
X-1142950D01*
G01X-1125250Y-180000D02*
X-1126650Y-179750D01*
X-1127875Y-178750D01*
X-1128925Y-177250D01*
X-1129625Y-175500D01*
X-1129975Y-173500D01*
Y-171500D01*
X-1129625Y-169500D01*
X-1128925Y-167750D01*
X-1127875Y-166250D01*
X-1126650Y-165250D01*
X-1125250Y-165000D01*
X-1123850Y-165250D01*
X-1122625Y-166250D01*
X-1121575Y-167750D01*
X-1120875Y-169500D01*
X-1120525Y-171500D01*
Y-173500D01*
X-1120875Y-175500D01*
X-1121575Y-177250D01*
X-1122625Y-178750D01*
X-1123850Y-179750D01*
X-1125250Y-180000D01*
G01X-1115075D02*
Y-165000D01*
X-1107025Y-180000D01*
Y-165000D01*
G01X-1100525Y-178000D02*
X-1099125Y-179250D01*
X-1097550Y-180000D01*
X-1096150D01*
X-1094750Y-179250D01*
X-1093700Y-178000D01*
X-1093175Y-176250D01*
X-1093525Y-174500D01*
X-1094400Y-173000D01*
X-1095975Y-172000D01*
X-1098075Y-171500D01*
X-1099300Y-170500D01*
X-1099825Y-168750D01*
X-1099475Y-167000D01*
X-1098600Y-165750D01*
X-1097375Y-165000D01*
X-1096150D01*
X-1094925Y-165500D01*
X-1093875Y-166750D01*
G01X-1073000Y-180000D02*
Y-165000D01*
X-1068450Y-177500D01*
X-1063900Y-165000D01*
Y-180000D01*
G01X-1058100Y-165000D02*
Y-175750D01*
X-1057400Y-178000D01*
X-1056000Y-179500D01*
X-1054250Y-180000D01*
X-1052500Y-179500D01*
X-1051100Y-178000D01*
X-1050400Y-175750D01*
Y-165000D01*
G01X-1043725Y-178000D02*
X-1042325Y-179250D01*
X-1040750Y-180000D01*
X-1039350D01*
X-1037950Y-179250D01*
X-1036900Y-178000D01*
X-1036375Y-176250D01*
X-1036725Y-174500D01*
X-1037600Y-173000D01*
X-1039175Y-172000D01*
X-1041275Y-171500D01*
X-1042500Y-170500D01*
X-1043025Y-168750D01*
X-1042675Y-167000D01*
X-1041800Y-165750D01*
X-1040575Y-165000D01*
X-1039350D01*
X-1038125Y-165500D01*
X-1037075Y-166750D01*
G01X-1025850Y-165000D02*
Y-180000D01*
G01X-1029875Y-165000D02*
X-1021825D01*
G01X-996050Y-172000D02*
X-995350Y-171250D01*
X-994825Y-170000D01*
X-994475Y-168250D01*
X-994825Y-166750D01*
X-995525Y-165750D01*
X-996750Y-165000D01*
X-1001475D01*
Y-180000D01*
X-995700D01*
X-994475Y-179000D01*
X-993775Y-177500D01*
X-993425Y-175750D01*
X-993775Y-174000D01*
X-994825Y-172500D01*
X-996050Y-172000D01*
X-1001475D01*
G01X-979750Y-180000D02*
X-986750D01*
Y-165000D01*
X-979750D01*
G01X-982550Y-172250D02*
X-986750D01*
G01X-958350Y-180000D02*
Y-165000D01*
X-954150D01*
X-952750Y-165750D01*
X-951700Y-167500D01*
X-951350Y-169500D01*
X-951700Y-171500D01*
X-952575Y-173000D01*
X-954150Y-173750D01*
X-958350D01*
G01X-944150Y-180000D02*
Y-165000D01*
X-939775D01*
X-938375Y-165750D01*
X-937500Y-166750D01*
X-937150Y-168750D01*
X-937500Y-170750D01*
X-938550Y-172000D01*
X-939775Y-172750D01*
X-944150D01*
G01X-939775D02*
X-937150Y-180000D01*
G01X-926450D02*
X-927850Y-179750D01*
X-929075Y-178750D01*
X-930125Y-177250D01*
X-930825Y-175500D01*
X-931175Y-173500D01*
Y-171500D01*
X-930825Y-169500D01*
X-930125Y-167750D01*
X-929075Y-166250D01*
X-927850Y-165250D01*
X-926450Y-165000D01*
X-925050Y-165250D01*
X-923825Y-166250D01*
X-922775Y-167750D01*
X-922075Y-169500D01*
X-921725Y-171500D01*
Y-173500D01*
X-922075Y-175500D01*
X-922775Y-177250D01*
X-923825Y-178750D01*
X-925050Y-179750D01*
X-926450Y-180000D01*
G01X-916625Y-165000D02*
X-912250Y-180000D01*
X-907875Y-165000D01*
G01X-900150D02*
X-895950D01*
G01X-898050D02*
Y-180000D01*
G01X-900150D02*
X-895950D01*
G01X-887700D02*
Y-165000D01*
X-884200D01*
X-882800Y-165750D01*
X-881750Y-166750D01*
X-880875Y-168250D01*
X-880175Y-170000D01*
X-880000Y-172500D01*
X-880175Y-175000D01*
X-880875Y-176750D01*
X-881750Y-178250D01*
X-882800Y-179250D01*
X-884200Y-180000D01*
X-887700D01*
G01X-866150D02*
X-873150D01*
Y-165000D01*
X-866150D01*
G01X-868950Y-172250D02*
X-873150D01*
G01X-859300Y-180000D02*
Y-165000D01*
X-855800D01*
X-854400Y-165750D01*
X-853350Y-166750D01*
X-852475Y-168250D01*
X-851775Y-170000D01*
X-851600Y-172500D01*
X-851775Y-175000D01*
X-852475Y-176750D01*
X-853350Y-178250D01*
X-854400Y-179250D01*
X-855800Y-180000D01*
X-859300D01*
G01X-832300Y-165000D02*
X-829850Y-180000D01*
X-827050Y-165000D01*
X-824250Y-180000D01*
X-821800Y-165000D01*
G01X-814950D02*
X-810750D01*
G01X-812850D02*
Y-180000D01*
G01X-814950D02*
X-810750D01*
G01X-798650Y-165000D02*
Y-180000D01*
G01X-802675Y-165000D02*
X-794625D01*
G01X-788125Y-180000D02*
Y-165000D01*
G01X-780775D02*
Y-180000D01*
G01Y-172500D02*
X-788125D01*
G01X-754650Y-172000D02*
X-753950Y-171250D01*
X-753425Y-170000D01*
X-753075Y-168250D01*
X-753425Y-166750D01*
X-754125Y-165750D01*
X-755350Y-165000D01*
X-760075D01*
Y-180000D01*
X-754300D01*
X-753075Y-179000D01*
X-752375Y-177500D01*
X-752025Y-175750D01*
X-752375Y-174000D01*
X-753425Y-172500D01*
X-754650Y-172000D01*
X-760075D01*
G01X-741850Y-180000D02*
X-743250Y-179750D01*
X-744475Y-178750D01*
X-745525Y-177250D01*
X-746225Y-175500D01*
X-746575Y-173500D01*
Y-171500D01*
X-746225Y-169500D01*
X-745525Y-167750D01*
X-744475Y-166250D01*
X-743250Y-165250D01*
X-741850Y-165000D01*
X-740450Y-165250D01*
X-739225Y-166250D01*
X-738175Y-167750D01*
X-737475Y-169500D01*
X-737125Y-171500D01*
Y-173500D01*
X-737475Y-175500D01*
X-738175Y-177250D01*
X-739225Y-178750D01*
X-740450Y-179750D01*
X-741850Y-180000D01*
G01X-732025D02*
X-727650Y-165000D01*
X-723275Y-180000D01*
G01X-724850Y-174750D02*
X-730450D01*
G01X-716950Y-180000D02*
Y-165000D01*
X-712575D01*
X-711175Y-165750D01*
X-710300Y-166750D01*
X-709950Y-168750D01*
X-710300Y-170750D01*
X-711350Y-172000D01*
X-712575Y-172750D01*
X-716950D01*
G01X-712575D02*
X-709950Y-180000D01*
G01X-703100D02*
Y-165000D01*
X-699600D01*
X-698200Y-165750D01*
X-697150Y-166750D01*
X-696275Y-168250D01*
X-695575Y-170000D01*
X-695400Y-172500D01*
X-695575Y-175000D01*
X-696275Y-176750D01*
X-697150Y-178250D01*
X-698200Y-179250D01*
X-699600Y-180000D01*
X-703100D01*
G01X-688725Y-178000D02*
X-687325Y-179250D01*
X-685750Y-180000D01*
X-684350D01*
X-682950Y-179250D01*
X-681900Y-178000D01*
X-681375Y-176250D01*
X-681725Y-174500D01*
X-682600Y-173000D01*
X-684175Y-172000D01*
X-686275Y-171500D01*
X-687500Y-170500D01*
X-688025Y-168750D01*
X-687675Y-167000D01*
X-686800Y-165750D01*
X-685575Y-165000D01*
X-684350D01*
X-683125Y-165500D01*
X-682075Y-166750D01*
G01X-670850Y-180500D02*
X-671200Y-180250D01*
Y-179750D01*
X-670850Y-179500D01*
X-670500Y-179750D01*
Y-180250D01*
X-670850Y-180500D01*
G01X-645950Y-180000D02*
Y-165000D01*
X-641575D01*
X-640175Y-165750D01*
X-639300Y-166750D01*
X-638950Y-168750D01*
X-639300Y-170750D01*
X-640350Y-172000D01*
X-641575Y-172750D01*
X-645950D01*
G01X-641575D02*
X-638950Y-180000D01*
G01X-624750D02*
X-631750D01*
Y-165000D01*
X-624750D01*
G01X-627550Y-172250D02*
X-631750D01*
G01X-610200Y-166250D02*
X-611250Y-165500D01*
X-612475Y-165000D01*
X-613875D01*
X-615450Y-165750D01*
X-616675Y-167000D01*
X-617550Y-168500D01*
X-618250Y-171000D01*
X-618425Y-173250D01*
X-618075Y-175500D01*
X-617550Y-177000D01*
X-616500Y-178500D01*
X-615275Y-179500D01*
X-614050Y-180000D01*
X-612825D01*
X-611600Y-179500D01*
X-610550Y-178750D01*
X-609675Y-177750D01*
G01X-599850Y-180000D02*
X-601250Y-179750D01*
X-602475Y-178750D01*
X-603525Y-177250D01*
X-604225Y-175500D01*
X-604575Y-173500D01*
Y-171500D01*
X-604225Y-169500D01*
X-603525Y-167750D01*
X-602475Y-166250D01*
X-601250Y-165250D01*
X-599850Y-165000D01*
X-598450Y-165250D01*
X-597225Y-166250D01*
X-596175Y-167750D01*
X-595475Y-169500D01*
X-595125Y-171500D01*
Y-173500D01*
X-595475Y-175500D01*
X-596175Y-177250D01*
X-597225Y-178750D01*
X-598450Y-179750D01*
X-599850Y-180000D01*
G01X-589150D02*
Y-165000D01*
X-584775D01*
X-583375Y-165750D01*
X-582500Y-166750D01*
X-582150Y-168750D01*
X-582500Y-170750D01*
X-583550Y-172000D01*
X-584775Y-172750D01*
X-589150D01*
G01X-584775D02*
X-582150Y-180000D01*
G01X-575300D02*
Y-165000D01*
X-571800D01*
X-570400Y-165750D01*
X-569350Y-166750D01*
X-568475Y-168250D01*
X-567775Y-170000D01*
X-567600Y-172500D01*
X-567775Y-175000D01*
X-568475Y-176750D01*
X-569350Y-178250D01*
X-570400Y-179250D01*
X-571800Y-180000D01*
X-575300D01*
G01X-560925Y-178000D02*
X-559525Y-179250D01*
X-557950Y-180000D01*
X-556550D01*
X-555150Y-179250D01*
X-554100Y-178000D01*
X-553575Y-176250D01*
X-553925Y-174500D01*
X-554800Y-173000D01*
X-556375Y-172000D01*
X-558475Y-171500D01*
X-559700Y-170500D01*
X-560225Y-168750D01*
X-559875Y-167000D01*
X-559000Y-165750D01*
X-557775Y-165000D01*
X-556550D01*
X-555325Y-165500D01*
X-554275Y-166750D01*
G01X-1638550Y-135000D02*
X-1634350D01*
G01X-1636450D02*
Y-150000D01*
G01X-1638550D02*
X-1634350D01*
G01X-1626800D02*
Y-135000D01*
X-1622250Y-147500D01*
X-1617700Y-135000D01*
Y-150000D01*
G01X-1611550D02*
Y-135000D01*
X-1607350D01*
X-1605950Y-135750D01*
X-1604900Y-137500D01*
X-1604550Y-139500D01*
X-1604900Y-141500D01*
X-1605775Y-143000D01*
X-1607350Y-143750D01*
X-1611550D01*
G01X-1590350Y-150000D02*
X-1597350D01*
Y-135000D01*
X-1590350D01*
G01X-1593150Y-142250D02*
X-1597350D01*
G01X-1583500Y-150000D02*
Y-135000D01*
X-1580000D01*
X-1578600Y-135750D01*
X-1577550Y-136750D01*
X-1576675Y-138250D01*
X-1575975Y-140000D01*
X-1575800Y-142500D01*
X-1575975Y-145000D01*
X-1576675Y-146750D01*
X-1577550Y-148250D01*
X-1578600Y-149250D01*
X-1580000Y-150000D01*
X-1583500D01*
G01X-1569825D02*
X-1565450Y-135000D01*
X-1561075Y-150000D01*
G01X-1562650Y-144750D02*
X-1568250D01*
G01X-1555275Y-150000D02*
Y-135000D01*
X-1547225Y-150000D01*
Y-135000D01*
G01X-1533200Y-136250D02*
X-1534250Y-135500D01*
X-1535475Y-135000D01*
X-1536875D01*
X-1538450Y-135750D01*
X-1539675Y-137000D01*
X-1540550Y-138500D01*
X-1541250Y-141000D01*
X-1541425Y-143250D01*
X-1541075Y-145500D01*
X-1540550Y-147000D01*
X-1539500Y-148500D01*
X-1538275Y-149500D01*
X-1537050Y-150000D01*
X-1535825D01*
X-1534600Y-149500D01*
X-1533550Y-148750D01*
X-1532675Y-147750D01*
G01X-1519350Y-150000D02*
X-1526350D01*
Y-135000D01*
X-1519350D01*
G01X-1522150Y-142250D02*
X-1526350D01*
G01X-1497950Y-150000D02*
Y-135000D01*
X-1493575D01*
X-1492175Y-135750D01*
X-1491300Y-136750D01*
X-1490950Y-138750D01*
X-1491300Y-140750D01*
X-1492350Y-142000D01*
X-1493575Y-142750D01*
X-1497950D01*
G01X-1493575D02*
X-1490950Y-150000D01*
G01X-1476750D02*
X-1483750D01*
Y-135000D01*
X-1476750D01*
G01X-1479550Y-142250D02*
X-1483750D01*
G01X-1469550Y-150000D02*
Y-135000D01*
X-1465350D01*
X-1463950Y-135750D01*
X-1462900Y-137500D01*
X-1462550Y-139500D01*
X-1462900Y-141500D01*
X-1463775Y-143000D01*
X-1465350Y-143750D01*
X-1469550D01*
G01X-1451850Y-150000D02*
X-1453250Y-149750D01*
X-1454475Y-148750D01*
X-1455525Y-147250D01*
X-1456225Y-145500D01*
X-1456575Y-143500D01*
Y-141500D01*
X-1456225Y-139500D01*
X-1455525Y-137750D01*
X-1454475Y-136250D01*
X-1453250Y-135250D01*
X-1451850Y-135000D01*
X-1450450Y-135250D01*
X-1449225Y-136250D01*
X-1448175Y-137750D01*
X-1447475Y-139500D01*
X-1447125Y-141500D01*
Y-143500D01*
X-1447475Y-145500D01*
X-1448175Y-147250D01*
X-1449225Y-148750D01*
X-1450450Y-149750D01*
X-1451850Y-150000D01*
G01X-1441150D02*
Y-135000D01*
X-1436775D01*
X-1435375Y-135750D01*
X-1434500Y-136750D01*
X-1434150Y-138750D01*
X-1434500Y-140750D01*
X-1435550Y-142000D01*
X-1436775Y-142750D01*
X-1441150D01*
G01X-1436775D02*
X-1434150Y-150000D01*
G01X-1423450Y-135000D02*
Y-150000D01*
G01X-1427475Y-135000D02*
X-1419425D01*
G01X-1411350D02*
X-1407150D01*
G01X-1409250D02*
Y-150000D01*
G01X-1411350D02*
X-1407150D01*
G01X-1399075D02*
Y-135000D01*
X-1391025Y-150000D01*
Y-135000D01*
G01X-1379800Y-142500D02*
X-1376300D01*
Y-147000D01*
X-1377350Y-148500D01*
X-1378575Y-149500D01*
X-1380325Y-150000D01*
X-1382075Y-149500D01*
X-1383300Y-148500D01*
X-1384350Y-147000D01*
X-1385050Y-145250D01*
X-1385400Y-143250D01*
Y-141500D01*
X-1385050Y-140000D01*
X-1384350Y-138250D01*
X-1383300Y-136750D01*
X-1382250Y-135750D01*
X-1380850Y-135000D01*
X-1379625D01*
X-1378225Y-135500D01*
X-1377175Y-136500D01*
G01X-1357000Y-150000D02*
Y-135000D01*
X-1352450Y-147500D01*
X-1347900Y-135000D01*
Y-150000D01*
G01X-1342100Y-135000D02*
Y-145750D01*
X-1341400Y-148000D01*
X-1340000Y-149500D01*
X-1338250Y-150000D01*
X-1336500Y-149500D01*
X-1335100Y-148000D01*
X-1334400Y-145750D01*
Y-135000D01*
G01X-1327725Y-148000D02*
X-1326325Y-149250D01*
X-1324750Y-150000D01*
X-1323350D01*
X-1321950Y-149250D01*
X-1320900Y-148000D01*
X-1320375Y-146250D01*
X-1320725Y-144500D01*
X-1321600Y-143000D01*
X-1323175Y-142000D01*
X-1325275Y-141500D01*
X-1326500Y-140500D01*
X-1327025Y-138750D01*
X-1326675Y-137000D01*
X-1325800Y-135750D01*
X-1324575Y-135000D01*
X-1323350D01*
X-1322125Y-135500D01*
X-1321075Y-136750D01*
G01X-1309850Y-135000D02*
Y-150000D01*
G01X-1313875Y-135000D02*
X-1305825D01*
G01X-1285125Y-148000D02*
X-1283725Y-149250D01*
X-1282150Y-150000D01*
X-1280750D01*
X-1279350Y-149250D01*
X-1278300Y-148000D01*
X-1277775Y-146250D01*
X-1278125Y-144500D01*
X-1279000Y-143000D01*
X-1280575Y-142000D01*
X-1282675Y-141500D01*
X-1283900Y-140500D01*
X-1284425Y-138750D01*
X-1284075Y-137000D01*
X-1283200Y-135750D01*
X-1281975Y-135000D01*
X-1280750D01*
X-1279525Y-135500D01*
X-1278475Y-136750D01*
G01X-1270750Y-150000D02*
Y-135000D01*
X-1266550D01*
X-1265150Y-135750D01*
X-1264100Y-137500D01*
X-1263750Y-139500D01*
X-1264100Y-141500D01*
X-1264975Y-143000D01*
X-1266550Y-143750D01*
X-1270750D01*
G01X-1249550Y-150000D02*
X-1256550D01*
Y-135000D01*
X-1249550D01*
G01X-1252350Y-142250D02*
X-1256550D01*
G01X-1235000Y-136250D02*
X-1236050Y-135500D01*
X-1237275Y-135000D01*
X-1238675D01*
X-1240250Y-135750D01*
X-1241475Y-137000D01*
X-1242350Y-138500D01*
X-1243050Y-141000D01*
X-1243225Y-143250D01*
X-1242875Y-145500D01*
X-1242350Y-147000D01*
X-1241300Y-148500D01*
X-1240075Y-149500D01*
X-1238850Y-150000D01*
X-1237625D01*
X-1236400Y-149500D01*
X-1235350Y-148750D01*
X-1234475Y-147750D01*
G01X-1226750Y-135000D02*
X-1222550D01*
G01X-1224650D02*
Y-150000D01*
G01X-1226750D02*
X-1222550D01*
G01X-1213775D02*
Y-135000D01*
X-1207125D01*
G01X-1209575Y-142250D02*
X-1213775D01*
G01X-1196250Y-150000D02*
Y-143250D01*
X-1199750Y-135000D01*
G01X-1192750D02*
X-1196250Y-143250D01*
G01X-1164350Y-150000D02*
X-1171350D01*
Y-135000D01*
X-1164350D01*
G01X-1167150Y-142250D02*
X-1171350D01*
G01X-1158025Y-150000D02*
X-1153650Y-135000D01*
X-1149275Y-150000D01*
G01X-1150850Y-144750D02*
X-1156450D01*
G01X-1135600Y-136250D02*
X-1136650Y-135500D01*
X-1137875Y-135000D01*
X-1139275D01*
X-1140850Y-135750D01*
X-1142075Y-137000D01*
X-1142950Y-138500D01*
X-1143650Y-141000D01*
X-1143825Y-143250D01*
X-1143475Y-145500D01*
X-1142950Y-147000D01*
X-1141900Y-148500D01*
X-1140675Y-149500D01*
X-1139450Y-150000D01*
X-1138225D01*
X-1137000Y-149500D01*
X-1135950Y-148750D01*
X-1135075Y-147750D01*
G01X-1128925Y-150000D02*
Y-135000D01*
G01X-1121575D02*
Y-150000D01*
G01Y-142500D02*
X-1128925D01*
G01X-1093000Y-136250D02*
X-1094050Y-135500D01*
X-1095275Y-135000D01*
X-1096675D01*
X-1098250Y-135750D01*
X-1099475Y-137000D01*
X-1100350Y-138500D01*
X-1101050Y-141000D01*
X-1101225Y-143250D01*
X-1100875Y-145500D01*
X-1100350Y-147000D01*
X-1099300Y-148500D01*
X-1098075Y-149500D01*
X-1096850Y-150000D01*
X-1095625D01*
X-1094400Y-149500D01*
X-1093350Y-148750D01*
X-1092475Y-147750D01*
G01X-1082650Y-150000D02*
X-1084050Y-149750D01*
X-1085275Y-148750D01*
X-1086325Y-147250D01*
X-1087025Y-145500D01*
X-1087375Y-143500D01*
Y-141500D01*
X-1087025Y-139500D01*
X-1086325Y-137750D01*
X-1085275Y-136250D01*
X-1084050Y-135250D01*
X-1082650Y-135000D01*
X-1081250Y-135250D01*
X-1080025Y-136250D01*
X-1078975Y-137750D01*
X-1078275Y-139500D01*
X-1077925Y-141500D01*
Y-143500D01*
X-1078275Y-145500D01*
X-1078975Y-147250D01*
X-1080025Y-148750D01*
X-1081250Y-149750D01*
X-1082650Y-150000D01*
G01X-1072475D02*
Y-135000D01*
X-1064425Y-150000D01*
Y-135000D01*
G01X-1054250D02*
Y-150000D01*
G01X-1058275Y-135000D02*
X-1050225D01*
G01X-1043550Y-150000D02*
Y-135000D01*
X-1039175D01*
X-1037775Y-135750D01*
X-1036900Y-136750D01*
X-1036550Y-138750D01*
X-1036900Y-140750D01*
X-1037950Y-142000D01*
X-1039175Y-142750D01*
X-1043550D01*
G01X-1039175D02*
X-1036550Y-150000D01*
G01X-1025850D02*
X-1027250Y-149750D01*
X-1028475Y-148750D01*
X-1029525Y-147250D01*
X-1030225Y-145500D01*
X-1030575Y-143500D01*
Y-141500D01*
X-1030225Y-139500D01*
X-1029525Y-137750D01*
X-1028475Y-136250D01*
X-1027250Y-135250D01*
X-1025850Y-135000D01*
X-1024450Y-135250D01*
X-1023225Y-136250D01*
X-1022175Y-137750D01*
X-1021475Y-139500D01*
X-1021125Y-141500D01*
Y-143500D01*
X-1021475Y-145500D01*
X-1022175Y-147250D01*
X-1023225Y-148750D01*
X-1024450Y-149750D01*
X-1025850Y-150000D01*
G01X-1015150Y-135000D02*
Y-150000D01*
X-1008150D01*
G01X-1000950Y-135000D02*
Y-150000D01*
X-993950D01*
G01X-979750D02*
X-986750D01*
Y-135000D01*
X-979750D01*
G01X-982550Y-142250D02*
X-986750D01*
G01X-972900Y-150000D02*
Y-135000D01*
X-969400D01*
X-968000Y-135750D01*
X-966950Y-136750D01*
X-966075Y-138250D01*
X-965375Y-140000D01*
X-965200Y-142500D01*
X-965375Y-145000D01*
X-966075Y-146750D01*
X-966950Y-148250D01*
X-968000Y-149250D01*
X-969400Y-150000D01*
X-972900D01*
G01X-942750Y-135000D02*
X-938550D01*
G01X-940650D02*
Y-150000D01*
G01X-942750D02*
X-938550D01*
G01X-931000D02*
Y-135000D01*
X-926450Y-147500D01*
X-921900Y-135000D01*
Y-150000D01*
G01X-915750D02*
Y-135000D01*
X-911550D01*
X-910150Y-135750D01*
X-909100Y-137500D01*
X-908750Y-139500D01*
X-909100Y-141500D01*
X-909975Y-143000D01*
X-911550Y-143750D01*
X-915750D01*
G01X-894550Y-150000D02*
X-901550D01*
Y-135000D01*
X-894550D01*
G01X-897350Y-142250D02*
X-901550D01*
G01X-887700Y-150000D02*
Y-135000D01*
X-884200D01*
X-882800Y-135750D01*
X-881750Y-136750D01*
X-880875Y-138250D01*
X-880175Y-140000D01*
X-880000Y-142500D01*
X-880175Y-145000D01*
X-880875Y-146750D01*
X-881750Y-148250D01*
X-882800Y-149250D01*
X-884200Y-150000D01*
X-887700D01*
G01X-874025D02*
X-869650Y-135000D01*
X-865275Y-150000D01*
G01X-866850Y-144750D02*
X-872450D01*
G01X-859475Y-150000D02*
Y-135000D01*
X-851425Y-150000D01*
Y-135000D01*
G01X-837400Y-136250D02*
X-838450Y-135500D01*
X-839675Y-135000D01*
X-841075D01*
X-842650Y-135750D01*
X-843875Y-137000D01*
X-844750Y-138500D01*
X-845450Y-141000D01*
X-845625Y-143250D01*
X-845275Y-145500D01*
X-844750Y-147000D01*
X-843700Y-148500D01*
X-842475Y-149500D01*
X-841250Y-150000D01*
X-840025D01*
X-838800Y-149500D01*
X-837750Y-148750D01*
X-836875Y-147750D01*
G01X-823550Y-150000D02*
X-830550D01*
Y-135000D01*
X-823550D01*
G01X-826350Y-142250D02*
X-830550D01*
G01X-797600Y-142500D02*
X-794100D01*
Y-147000D01*
X-795150Y-148500D01*
X-796375Y-149500D01*
X-798125Y-150000D01*
X-799875Y-149500D01*
X-801100Y-148500D01*
X-802150Y-147000D01*
X-802850Y-145250D01*
X-803200Y-143250D01*
Y-141500D01*
X-802850Y-140000D01*
X-802150Y-138250D01*
X-801100Y-136750D01*
X-800050Y-135750D01*
X-798650Y-135000D01*
X-797425D01*
X-796025Y-135500D01*
X-794975Y-136500D01*
G01X-780950Y-150000D02*
X-787950D01*
Y-135000D01*
X-780950D01*
G01X-783750Y-142250D02*
X-787950D01*
G01X-770250Y-150000D02*
X-771650Y-149750D01*
X-772875Y-148750D01*
X-773925Y-147250D01*
X-774625Y-145500D01*
X-774975Y-143500D01*
Y-141500D01*
X-774625Y-139500D01*
X-773925Y-137750D01*
X-772875Y-136250D01*
X-771650Y-135250D01*
X-770250Y-135000D01*
X-768850Y-135250D01*
X-767625Y-136250D01*
X-766575Y-137750D01*
X-765875Y-139500D01*
X-765525Y-141500D01*
Y-143500D01*
X-765875Y-145500D01*
X-766575Y-147250D01*
X-767625Y-148750D01*
X-768850Y-149750D01*
X-770250Y-150000D01*
G01X-760600D02*
Y-135000D01*
X-756050Y-147500D01*
X-751500Y-135000D01*
Y-150000D01*
G01X-738350D02*
X-745350D01*
Y-135000D01*
X-738350D01*
G01X-741150Y-142250D02*
X-745350D01*
G01X-727650Y-135000D02*
Y-150000D01*
G01X-731675Y-135000D02*
X-723625D01*
G01X-716950Y-150000D02*
Y-135000D01*
X-712575D01*
X-711175Y-135750D01*
X-710300Y-136750D01*
X-709950Y-138750D01*
X-710300Y-140750D01*
X-711350Y-142000D01*
X-712575Y-142750D01*
X-716950D01*
G01X-712575D02*
X-709950Y-150000D01*
G01X-699250D02*
Y-143250D01*
X-702750Y-135000D01*
G01X-695750D02*
X-699250Y-143250D01*
G01X-669450Y-142000D02*
X-668750Y-141250D01*
X-668225Y-140000D01*
X-667875Y-138250D01*
X-668225Y-136750D01*
X-668925Y-135750D01*
X-670150Y-135000D01*
X-674875D01*
Y-150000D01*
X-669100D01*
X-667875Y-149000D01*
X-667175Y-147500D01*
X-666825Y-145750D01*
X-667175Y-144000D01*
X-668225Y-142500D01*
X-669450Y-142000D01*
X-674875D01*
G01X-656650Y-150000D02*
Y-143250D01*
X-660150Y-135000D01*
G01X-653150D02*
X-656650Y-143250D01*
G01X-631750Y-135000D02*
Y-150000D01*
X-624750D01*
G01X-618425D02*
X-614050Y-135000D01*
X-609675Y-150000D01*
G01X-611250Y-144750D02*
X-616850D01*
G01X-599850Y-150000D02*
Y-143250D01*
X-603350Y-135000D01*
G01X-596350D02*
X-599850Y-143250D01*
G01X-582150Y-150000D02*
X-589150D01*
Y-135000D01*
X-582150D01*
G01X-584950Y-142250D02*
X-589150D01*
G01X-574950Y-150000D02*
Y-135000D01*
X-570575D01*
X-569175Y-135750D01*
X-568300Y-136750D01*
X-567950Y-138750D01*
X-568300Y-140750D01*
X-569350Y-142000D01*
X-570575Y-142750D01*
X-574950D01*
G01X-570575D02*
X-567950Y-150000D01*
G01X-557250Y-150500D02*
X-557600Y-150250D01*
Y-149750D01*
X-557250Y-149500D01*
X-556900Y-149750D01*
Y-150250D01*
X-557250Y-150500D01*
G01X-1632600Y-106250D02*
X-1633650Y-105500D01*
X-1634875Y-105000D01*
X-1636275D01*
X-1637850Y-105750D01*
X-1639075Y-107000D01*
X-1639950Y-108500D01*
X-1640650Y-111000D01*
X-1640825Y-113250D01*
X-1640475Y-115500D01*
X-1639950Y-117000D01*
X-1638900Y-118500D01*
X-1637675Y-119500D01*
X-1636450Y-120000D01*
X-1635225D01*
X-1634000Y-119500D01*
X-1632950Y-118750D01*
X-1632075Y-117750D01*
G01X-1622250Y-120000D02*
X-1623650Y-119750D01*
X-1624875Y-118750D01*
X-1625925Y-117250D01*
X-1626625Y-115500D01*
X-1626975Y-113500D01*
Y-111500D01*
X-1626625Y-109500D01*
X-1625925Y-107750D01*
X-1624875Y-106250D01*
X-1623650Y-105250D01*
X-1622250Y-105000D01*
X-1620850Y-105250D01*
X-1619625Y-106250D01*
X-1618575Y-107750D01*
X-1617875Y-109500D01*
X-1617525Y-111500D01*
Y-113500D01*
X-1617875Y-115500D01*
X-1618575Y-117250D01*
X-1619625Y-118750D01*
X-1620850Y-119750D01*
X-1622250Y-120000D01*
G01X-1612075D02*
Y-105000D01*
X-1604025Y-120000D01*
Y-105000D01*
G01X-1593850D02*
Y-120000D01*
G01X-1597875Y-105000D02*
X-1589825D01*
G01X-1583150Y-120000D02*
Y-105000D01*
X-1578775D01*
X-1577375Y-105750D01*
X-1576500Y-106750D01*
X-1576150Y-108750D01*
X-1576500Y-110750D01*
X-1577550Y-112000D01*
X-1578775Y-112750D01*
X-1583150D01*
G01X-1578775D02*
X-1576150Y-120000D01*
G01X-1565450D02*
X-1566850Y-119750D01*
X-1568075Y-118750D01*
X-1569125Y-117250D01*
X-1569825Y-115500D01*
X-1570175Y-113500D01*
Y-111500D01*
X-1569825Y-109500D01*
X-1569125Y-107750D01*
X-1568075Y-106250D01*
X-1566850Y-105250D01*
X-1565450Y-105000D01*
X-1564050Y-105250D01*
X-1562825Y-106250D01*
X-1561775Y-107750D01*
X-1561075Y-109500D01*
X-1560725Y-111500D01*
Y-113500D01*
X-1561075Y-115500D01*
X-1561775Y-117250D01*
X-1562825Y-118750D01*
X-1564050Y-119750D01*
X-1565450Y-120000D01*
G01X-1554750Y-105000D02*
Y-120000D01*
X-1547750D01*
G01X-1540550Y-105000D02*
Y-120000D01*
X-1533550D01*
G01X-1519350D02*
X-1526350D01*
Y-105000D01*
X-1519350D01*
G01X-1522150Y-112250D02*
X-1526350D01*
G01X-1512500Y-120000D02*
Y-105000D01*
X-1509000D01*
X-1507600Y-105750D01*
X-1506550Y-106750D01*
X-1505675Y-108250D01*
X-1504975Y-110000D01*
X-1504800Y-112500D01*
X-1504975Y-115000D01*
X-1505675Y-116750D01*
X-1506550Y-118250D01*
X-1507600Y-119250D01*
X-1509000Y-120000D01*
X-1512500D01*
G01X-1482350Y-105000D02*
X-1478150D01*
G01X-1480250D02*
Y-120000D01*
G01X-1482350D02*
X-1478150D01*
G01X-1470600D02*
Y-105000D01*
X-1466050Y-117500D01*
X-1461500Y-105000D01*
Y-120000D01*
G01X-1455350D02*
Y-105000D01*
X-1451150D01*
X-1449750Y-105750D01*
X-1448700Y-107500D01*
X-1448350Y-109500D01*
X-1448700Y-111500D01*
X-1449575Y-113000D01*
X-1451150Y-113750D01*
X-1455350D01*
G01X-1434150Y-120000D02*
X-1441150D01*
Y-105000D01*
X-1434150D01*
G01X-1436950Y-112250D02*
X-1441150D01*
G01X-1427300Y-120000D02*
Y-105000D01*
X-1423800D01*
X-1422400Y-105750D01*
X-1421350Y-106750D01*
X-1420475Y-108250D01*
X-1419775Y-110000D01*
X-1419600Y-112500D01*
X-1419775Y-115000D01*
X-1420475Y-116750D01*
X-1421350Y-118250D01*
X-1422400Y-119250D01*
X-1423800Y-120000D01*
X-1427300D01*
G01X-1413625D02*
X-1409250Y-105000D01*
X-1404875Y-120000D01*
G01X-1406450Y-114750D02*
X-1412050D01*
G01X-1399075Y-120000D02*
Y-105000D01*
X-1391025Y-120000D01*
Y-105000D01*
G01X-1377000Y-106250D02*
X-1378050Y-105500D01*
X-1379275Y-105000D01*
X-1380675D01*
X-1382250Y-105750D01*
X-1383475Y-107000D01*
X-1384350Y-108500D01*
X-1385050Y-111000D01*
X-1385225Y-113250D01*
X-1384875Y-115500D01*
X-1384350Y-117000D01*
X-1383300Y-118500D01*
X-1382075Y-119500D01*
X-1380850Y-120000D01*
X-1379625D01*
X-1378400Y-119500D01*
X-1377350Y-118750D01*
X-1376475Y-117750D01*
G01X-1363150Y-120000D02*
X-1370150D01*
Y-105000D01*
X-1363150D01*
G01X-1365950Y-112250D02*
X-1370150D01*
G01X-1341575Y-120000D02*
Y-105000D01*
X-1334925D01*
G01X-1337375Y-112250D02*
X-1341575D01*
G01X-1324050Y-120000D02*
X-1325450Y-119750D01*
X-1326675Y-118750D01*
X-1327725Y-117250D01*
X-1328425Y-115500D01*
X-1328775Y-113500D01*
Y-111500D01*
X-1328425Y-109500D01*
X-1327725Y-107750D01*
X-1326675Y-106250D01*
X-1325450Y-105250D01*
X-1324050Y-105000D01*
X-1322650Y-105250D01*
X-1321425Y-106250D01*
X-1320375Y-107750D01*
X-1319675Y-109500D01*
X-1319325Y-111500D01*
Y-113500D01*
X-1319675Y-115500D01*
X-1320375Y-117250D01*
X-1321425Y-118750D01*
X-1322650Y-119750D01*
X-1324050Y-120000D01*
G01X-1313350D02*
Y-105000D01*
X-1308975D01*
X-1307575Y-105750D01*
X-1306700Y-106750D01*
X-1306350Y-108750D01*
X-1306700Y-110750D01*
X-1307750Y-112000D01*
X-1308975Y-112750D01*
X-1313350D01*
G01X-1308975D02*
X-1306350Y-120000D01*
G01X-1277950D02*
X-1284950D01*
Y-105000D01*
X-1277950D01*
G01X-1280750Y-112250D02*
X-1284950D01*
G01X-1271625Y-120000D02*
X-1267250Y-105000D01*
X-1262875Y-120000D01*
G01X-1264450Y-114750D02*
X-1270050D01*
G01X-1249200Y-106250D02*
X-1250250Y-105500D01*
X-1251475Y-105000D01*
X-1252875D01*
X-1254450Y-105750D01*
X-1255675Y-107000D01*
X-1256550Y-108500D01*
X-1257250Y-111000D01*
X-1257425Y-113250D01*
X-1257075Y-115500D01*
X-1256550Y-117000D01*
X-1255500Y-118500D01*
X-1254275Y-119500D01*
X-1253050Y-120000D01*
X-1251825D01*
X-1250600Y-119500D01*
X-1249550Y-118750D01*
X-1248675Y-117750D01*
G01X-1242525Y-120000D02*
Y-105000D01*
G01X-1235175D02*
Y-120000D01*
G01Y-112500D02*
X-1242525D01*
G01X-1213950Y-105000D02*
Y-120000D01*
X-1206950D01*
G01X-1200625D02*
X-1196250Y-105000D01*
X-1191875Y-120000D01*
G01X-1193450Y-114750D02*
X-1199050D01*
G01X-1182050Y-120000D02*
Y-113250D01*
X-1185550Y-105000D01*
G01X-1178550D02*
X-1182050Y-113250D01*
G01X-1164350Y-120000D02*
X-1171350D01*
Y-105000D01*
X-1164350D01*
G01X-1167150Y-112250D02*
X-1171350D01*
G01X-1157150Y-120000D02*
Y-105000D01*
X-1152775D01*
X-1151375Y-105750D01*
X-1150500Y-106750D01*
X-1150150Y-108750D01*
X-1150500Y-110750D01*
X-1151550Y-112000D01*
X-1152775Y-112750D01*
X-1157150D01*
G01X-1152775D02*
X-1150150Y-120000D01*
G01X-1139450Y-120500D02*
X-1139800Y-120250D01*
Y-119750D01*
X-1139450Y-119500D01*
X-1139100Y-119750D01*
Y-120250D01*
X-1139450Y-120500D01*
G01X-1115600Y-120000D02*
Y-105000D01*
X-1111050Y-117500D01*
X-1106500Y-105000D01*
Y-120000D01*
G01X-1093350D02*
X-1100350D01*
Y-105000D01*
X-1093350D01*
G01X-1096150Y-112250D02*
X-1100350D01*
G01X-1087025Y-120000D02*
X-1082650Y-105000D01*
X-1078275Y-120000D01*
G01X-1079850Y-114750D02*
X-1085450D01*
G01X-1072125Y-118000D02*
X-1070725Y-119250D01*
X-1069150Y-120000D01*
X-1067750D01*
X-1066350Y-119250D01*
X-1065300Y-118000D01*
X-1064775Y-116250D01*
X-1065125Y-114500D01*
X-1066000Y-113000D01*
X-1067575Y-112000D01*
X-1069675Y-111500D01*
X-1070900Y-110500D01*
X-1071425Y-108750D01*
X-1071075Y-107000D01*
X-1070200Y-105750D01*
X-1068975Y-105000D01*
X-1067750D01*
X-1066525Y-105500D01*
X-1065475Y-106750D01*
G01X-1058100Y-105000D02*
Y-115750D01*
X-1057400Y-118000D01*
X-1056000Y-119500D01*
X-1054250Y-120000D01*
X-1052500Y-119500D01*
X-1051100Y-118000D01*
X-1050400Y-115750D01*
Y-105000D01*
G01X-1043550Y-120000D02*
Y-105000D01*
X-1039175D01*
X-1037775Y-105750D01*
X-1036900Y-106750D01*
X-1036550Y-108750D01*
X-1036900Y-110750D01*
X-1037950Y-112000D01*
X-1039175Y-112750D01*
X-1043550D01*
G01X-1039175D02*
X-1036550Y-120000D01*
G01X-1022350D02*
X-1029350D01*
Y-105000D01*
X-1022350D01*
G01X-1025150Y-112250D02*
X-1029350D01*
G01X-1016200Y-120000D02*
Y-105000D01*
X-1011650Y-117500D01*
X-1007100Y-105000D01*
Y-120000D01*
G01X-993950D02*
X-1000950D01*
Y-105000D01*
X-993950D01*
G01X-996750Y-112250D02*
X-1000950D01*
G01X-987275Y-120000D02*
Y-105000D01*
X-979225Y-120000D01*
Y-105000D01*
G01X-969050D02*
Y-120000D01*
G01X-973075Y-105000D02*
X-965025D01*
G01X-958525Y-118000D02*
X-957125Y-119250D01*
X-955550Y-120000D01*
X-954150D01*
X-952750Y-119250D01*
X-951700Y-118000D01*
X-951175Y-116250D01*
X-951525Y-114500D01*
X-952400Y-113000D01*
X-953975Y-112000D01*
X-956075Y-111500D01*
X-957300Y-110500D01*
X-957825Y-108750D01*
X-957475Y-107000D01*
X-956600Y-105750D01*
X-955375Y-105000D01*
X-954150D01*
X-952925Y-105500D01*
X-951875Y-106750D01*
G01X-931000Y-120000D02*
Y-105000D01*
X-926450Y-117500D01*
X-921900Y-105000D01*
Y-120000D01*
G01X-916100Y-105000D02*
Y-115750D01*
X-915400Y-118000D01*
X-914000Y-119500D01*
X-912250Y-120000D01*
X-910500Y-119500D01*
X-909100Y-118000D01*
X-908400Y-115750D01*
Y-105000D01*
G01X-901725Y-118000D02*
X-900325Y-119250D01*
X-898750Y-120000D01*
X-897350D01*
X-895950Y-119250D01*
X-894900Y-118000D01*
X-894375Y-116250D01*
X-894725Y-114500D01*
X-895600Y-113000D01*
X-897175Y-112000D01*
X-899275Y-111500D01*
X-900500Y-110500D01*
X-901025Y-108750D01*
X-900675Y-107000D01*
X-899800Y-105750D01*
X-898575Y-105000D01*
X-897350D01*
X-896125Y-105500D01*
X-895075Y-106750D01*
G01X-883850Y-105000D02*
Y-120000D01*
G01X-887875Y-105000D02*
X-879825D01*
G01X-854050Y-112000D02*
X-853350Y-111250D01*
X-852825Y-110000D01*
X-852475Y-108250D01*
X-852825Y-106750D01*
X-853525Y-105750D01*
X-854750Y-105000D01*
X-859475D01*
Y-120000D01*
X-853700D01*
X-852475Y-119000D01*
X-851775Y-117500D01*
X-851425Y-115750D01*
X-851775Y-114000D01*
X-852825Y-112500D01*
X-854050Y-112000D01*
X-859475D01*
G01X-837750Y-120000D02*
X-844750D01*
Y-105000D01*
X-837750D01*
G01X-840550Y-112250D02*
X-844750D01*
G01X-816350Y-120000D02*
Y-105000D01*
X-812150D01*
X-810750Y-105750D01*
X-809700Y-107500D01*
X-809350Y-109500D01*
X-809700Y-111500D01*
X-810575Y-113000D01*
X-812150Y-113750D01*
X-816350D01*
G01X-795150Y-120000D02*
X-802150D01*
Y-105000D01*
X-795150D01*
G01X-797950Y-112250D02*
X-802150D01*
G01X-787950Y-120000D02*
Y-105000D01*
X-783575D01*
X-782175Y-105750D01*
X-781300Y-106750D01*
X-780950Y-108750D01*
X-781300Y-110750D01*
X-782350Y-112000D01*
X-783575Y-112750D01*
X-787950D01*
G01X-783575D02*
X-780950Y-120000D01*
G01X-773575D02*
Y-105000D01*
X-766925D01*
G01X-769375Y-112250D02*
X-773575D01*
G01X-756050Y-120000D02*
X-757450Y-119750D01*
X-758675Y-118750D01*
X-759725Y-117250D01*
X-760425Y-115500D01*
X-760775Y-113500D01*
Y-111500D01*
X-760425Y-109500D01*
X-759725Y-107750D01*
X-758675Y-106250D01*
X-757450Y-105250D01*
X-756050Y-105000D01*
X-754650Y-105250D01*
X-753425Y-106250D01*
X-752375Y-107750D01*
X-751675Y-109500D01*
X-751325Y-111500D01*
Y-113500D01*
X-751675Y-115500D01*
X-752375Y-117250D01*
X-753425Y-118750D01*
X-754650Y-119750D01*
X-756050Y-120000D01*
G01X-745350D02*
Y-105000D01*
X-740975D01*
X-739575Y-105750D01*
X-738700Y-106750D01*
X-738350Y-108750D01*
X-738700Y-110750D01*
X-739750Y-112000D01*
X-740975Y-112750D01*
X-745350D01*
G01X-740975D02*
X-738350Y-120000D01*
G01X-732200D02*
Y-105000D01*
X-727650Y-117500D01*
X-723100Y-105000D01*
Y-120000D01*
G01X-709950D02*
X-716950D01*
Y-105000D01*
X-709950D01*
G01X-712750Y-112250D02*
X-716950D01*
G01X-703100Y-120000D02*
Y-105000D01*
X-699600D01*
X-698200Y-105750D01*
X-697150Y-106750D01*
X-696275Y-108250D01*
X-695575Y-110000D01*
X-695400Y-112500D01*
X-695575Y-115000D01*
X-696275Y-116750D01*
X-697150Y-118250D01*
X-698200Y-119250D01*
X-699600Y-120000D01*
X-703100D01*
G01X-669450Y-112000D02*
X-668750Y-111250D01*
X-668225Y-110000D01*
X-667875Y-108250D01*
X-668225Y-106750D01*
X-668925Y-105750D01*
X-670150Y-105000D01*
X-674875D01*
Y-120000D01*
X-669100D01*
X-667875Y-119000D01*
X-667175Y-117500D01*
X-666825Y-115750D01*
X-667175Y-114000D01*
X-668225Y-112500D01*
X-669450Y-112000D01*
X-674875D01*
G01X-656650Y-120000D02*
Y-113250D01*
X-660150Y-105000D01*
G01X-653150D02*
X-656650Y-113250D01*
G01X-628250Y-105000D02*
Y-120000D01*
G01X-632275Y-105000D02*
X-624225D01*
G01X-617900Y-120000D02*
Y-105000D01*
X-614400D01*
X-613000Y-105750D01*
X-611950Y-106750D01*
X-611075Y-108250D01*
X-610375Y-110000D01*
X-610200Y-112500D01*
X-610375Y-115000D01*
X-611075Y-116750D01*
X-611950Y-118250D01*
X-613000Y-119250D01*
X-614400Y-120000D01*
X-617900D01*
G01X-603350D02*
Y-105000D01*
X-598975D01*
X-597575Y-105750D01*
X-596700Y-106750D01*
X-596350Y-108750D01*
X-596700Y-110750D01*
X-597750Y-112000D01*
X-598975Y-112750D01*
X-603350D01*
G01X-598975D02*
X-596350Y-120000D01*
G01X-585650Y-120500D02*
X-586000Y-120250D01*
Y-119750D01*
X-585650Y-119500D01*
X-585300Y-119750D01*
Y-120250D01*
X-585650Y-120500D01*
G01X-1693250Y-90000D02*
Y-75000D01*
X-1695350Y-78000D01*
G01Y-90000D02*
X-1691150D01*
G01X-1679050D02*
X-1677825Y-89750D01*
X-1676425Y-89000D01*
X-1675550Y-87750D01*
X-1675200Y-86000D01*
X-1675550Y-84250D01*
X-1676600Y-82750D01*
X-1678175Y-82000D01*
X-1679925D01*
X-1680975Y-81500D01*
X-1681850Y-80250D01*
X-1682200Y-78500D01*
X-1681675Y-76750D01*
X-1680450Y-75500D01*
X-1679050Y-75000D01*
X-1677650Y-75500D01*
X-1676425Y-76750D01*
X-1675900Y-78500D01*
X-1676250Y-80250D01*
X-1677125Y-81500D01*
X-1678175Y-82000D01*
X-1679925D01*
X-1681500Y-82750D01*
X-1682550Y-84250D01*
X-1682900Y-86000D01*
X-1682550Y-87750D01*
X-1681675Y-89000D01*
X-1680275Y-89750D01*
X-1679050Y-90000D01*
G01X-1638550Y-75000D02*
X-1634350D01*
G01X-1636450D02*
Y-90000D01*
G01X-1638550D02*
X-1634350D01*
G01X-1626800D02*
Y-75000D01*
X-1622250Y-87500D01*
X-1617700Y-75000D01*
Y-90000D01*
G01X-1611550D02*
Y-75000D01*
X-1607350D01*
X-1605950Y-75750D01*
X-1604900Y-77500D01*
X-1604550Y-79500D01*
X-1604900Y-81500D01*
X-1605775Y-83000D01*
X-1607350Y-83750D01*
X-1611550D01*
G01X-1590350Y-90000D02*
X-1597350D01*
Y-75000D01*
X-1590350D01*
G01X-1593150Y-82250D02*
X-1597350D01*
G01X-1583500Y-90000D02*
Y-75000D01*
X-1580000D01*
X-1578600Y-75750D01*
X-1577550Y-76750D01*
X-1576675Y-78250D01*
X-1575975Y-80000D01*
X-1575800Y-82500D01*
X-1575975Y-85000D01*
X-1576675Y-86750D01*
X-1577550Y-88250D01*
X-1578600Y-89250D01*
X-1580000Y-90000D01*
X-1583500D01*
G01X-1569825D02*
X-1565450Y-75000D01*
X-1561075Y-90000D01*
G01X-1562650Y-84750D02*
X-1568250D01*
G01X-1555275Y-90000D02*
Y-75000D01*
X-1547225Y-90000D01*
Y-75000D01*
G01X-1533200Y-76250D02*
X-1534250Y-75500D01*
X-1535475Y-75000D01*
X-1536875D01*
X-1538450Y-75750D01*
X-1539675Y-77000D01*
X-1540550Y-78500D01*
X-1541250Y-81000D01*
X-1541425Y-83250D01*
X-1541075Y-85500D01*
X-1540550Y-87000D01*
X-1539500Y-88500D01*
X-1538275Y-89500D01*
X-1537050Y-90000D01*
X-1535825D01*
X-1534600Y-89500D01*
X-1533550Y-88750D01*
X-1532675Y-87750D01*
G01X-1519350Y-90000D02*
X-1526350D01*
Y-75000D01*
X-1519350D01*
G01X-1522150Y-82250D02*
X-1526350D01*
G01X-1494450Y-75000D02*
Y-90000D01*
G01X-1498475Y-75000D02*
X-1490425D01*
G01X-1480250Y-90000D02*
X-1481650Y-89750D01*
X-1482875Y-88750D01*
X-1483925Y-87250D01*
X-1484625Y-85500D01*
X-1484975Y-83500D01*
Y-81500D01*
X-1484625Y-79500D01*
X-1483925Y-77750D01*
X-1482875Y-76250D01*
X-1481650Y-75250D01*
X-1480250Y-75000D01*
X-1478850Y-75250D01*
X-1477625Y-76250D01*
X-1476575Y-77750D01*
X-1475875Y-79500D01*
X-1475525Y-81500D01*
Y-83500D01*
X-1475875Y-85500D01*
X-1476575Y-87250D01*
X-1477625Y-88750D01*
X-1478850Y-89750D01*
X-1480250Y-90000D01*
G01X-1450450Y-82000D02*
X-1449750Y-81250D01*
X-1449225Y-80000D01*
X-1448875Y-78250D01*
X-1449225Y-76750D01*
X-1449925Y-75750D01*
X-1451150Y-75000D01*
X-1455875D01*
Y-90000D01*
X-1450100D01*
X-1448875Y-89000D01*
X-1448175Y-87500D01*
X-1447825Y-85750D01*
X-1448175Y-84000D01*
X-1449225Y-82500D01*
X-1450450Y-82000D01*
X-1455875D01*
G01X-1434150Y-90000D02*
X-1441150D01*
Y-75000D01*
X-1434150D01*
G01X-1436950Y-82250D02*
X-1441150D01*
G01X-1413625Y-75000D02*
X-1409250Y-90000D01*
X-1404875Y-75000D01*
G01X-1391550Y-90000D02*
X-1398550D01*
Y-75000D01*
X-1391550D01*
G01X-1394350Y-82250D02*
X-1398550D01*
G01X-1384350Y-90000D02*
Y-75000D01*
X-1379975D01*
X-1378575Y-75750D01*
X-1377700Y-76750D01*
X-1377350Y-78750D01*
X-1377700Y-80750D01*
X-1378750Y-82000D01*
X-1379975Y-82750D01*
X-1384350D01*
G01X-1379975D02*
X-1377350Y-90000D01*
G01X-1368750Y-75000D02*
X-1364550D01*
G01X-1366650D02*
Y-90000D01*
G01X-1368750D02*
X-1364550D01*
G01X-1355775D02*
Y-75000D01*
X-1349125D01*
G01X-1351575Y-82250D02*
X-1355775D01*
G01X-1340350Y-75000D02*
X-1336150D01*
G01X-1338250D02*
Y-90000D01*
G01X-1340350D02*
X-1336150D01*
G01X-1320550D02*
X-1327550D01*
Y-75000D01*
X-1320550D01*
G01X-1323350Y-82250D02*
X-1327550D01*
G01X-1313700Y-90000D02*
Y-75000D01*
X-1310200D01*
X-1308800Y-75750D01*
X-1307750Y-76750D01*
X-1306875Y-78250D01*
X-1306175Y-80000D01*
X-1306000Y-82500D01*
X-1306175Y-85000D01*
X-1306875Y-86750D01*
X-1307750Y-88250D01*
X-1308800Y-89250D01*
X-1310200Y-90000D01*
X-1313700D01*
G01X-1284950D02*
Y-75000D01*
X-1280750D01*
X-1279350Y-75750D01*
X-1278300Y-77500D01*
X-1277950Y-79500D01*
X-1278300Y-81500D01*
X-1279175Y-83000D01*
X-1280750Y-83750D01*
X-1284950D01*
G01X-1263750Y-90000D02*
X-1270750D01*
Y-75000D01*
X-1263750D01*
G01X-1266550Y-82250D02*
X-1270750D01*
G01X-1256550Y-90000D02*
Y-75000D01*
X-1252175D01*
X-1250775Y-75750D01*
X-1249900Y-76750D01*
X-1249550Y-78750D01*
X-1249900Y-80750D01*
X-1250950Y-82000D01*
X-1252175Y-82750D01*
X-1256550D01*
G01X-1252175D02*
X-1249550Y-90000D01*
G01X-1224650Y-75000D02*
Y-90000D01*
G01X-1228675Y-75000D02*
X-1220625D01*
G01X-1214825Y-90000D02*
X-1210450Y-75000D01*
X-1206075Y-90000D01*
G01X-1207650Y-84750D02*
X-1213250D01*
G01X-1194850Y-82000D02*
X-1194150Y-81250D01*
X-1193625Y-80000D01*
X-1193275Y-78250D01*
X-1193625Y-76750D01*
X-1194325Y-75750D01*
X-1195550Y-75000D01*
X-1200275D01*
Y-90000D01*
X-1194500D01*
X-1193275Y-89000D01*
X-1192575Y-87500D01*
X-1192225Y-85750D01*
X-1192575Y-84000D01*
X-1193625Y-82500D01*
X-1194850Y-82000D01*
X-1200275D01*
G01X-1185550Y-75000D02*
Y-90000D01*
X-1178550D01*
G01X-1164350D02*
X-1171350D01*
Y-75000D01*
X-1164350D01*
G01X-1167150Y-82250D02*
X-1171350D01*
G01X-1153650Y-90500D02*
X-1154000Y-90250D01*
Y-89750D01*
X-1153650Y-89500D01*
X-1153300Y-89750D01*
Y-90250D01*
X-1153650Y-90500D01*
G01X-1127350Y-75000D02*
X-1123150D01*
G01X-1125250D02*
Y-90000D01*
G01X-1127350D02*
X-1123150D01*
G01X-1115600D02*
Y-75000D01*
X-1111050Y-87500D01*
X-1106500Y-75000D01*
Y-90000D01*
G01X-1100350D02*
Y-75000D01*
X-1096150D01*
X-1094750Y-75750D01*
X-1093700Y-77500D01*
X-1093350Y-79500D01*
X-1093700Y-81500D01*
X-1094575Y-83000D01*
X-1096150Y-83750D01*
X-1100350D01*
G01X-1079150Y-90000D02*
X-1086150D01*
Y-75000D01*
X-1079150D01*
G01X-1081950Y-82250D02*
X-1086150D01*
G01X-1072300Y-90000D02*
Y-75000D01*
X-1068800D01*
X-1067400Y-75750D01*
X-1066350Y-76750D01*
X-1065475Y-78250D01*
X-1064775Y-80000D01*
X-1064600Y-82500D01*
X-1064775Y-85000D01*
X-1065475Y-86750D01*
X-1066350Y-88250D01*
X-1067400Y-89250D01*
X-1068800Y-90000D01*
X-1072300D01*
G01X-1058625D02*
X-1054250Y-75000D01*
X-1049875Y-90000D01*
G01X-1051450Y-84750D02*
X-1057050D01*
G01X-1044075Y-90000D02*
Y-75000D01*
X-1036025Y-90000D01*
Y-75000D01*
G01X-1022000Y-76250D02*
X-1023050Y-75500D01*
X-1024275Y-75000D01*
X-1025675D01*
X-1027250Y-75750D01*
X-1028475Y-77000D01*
X-1029350Y-78500D01*
X-1030050Y-81000D01*
X-1030225Y-83250D01*
X-1029875Y-85500D01*
X-1029350Y-87000D01*
X-1028300Y-88500D01*
X-1027075Y-89500D01*
X-1025850Y-90000D01*
X-1024625D01*
X-1023400Y-89500D01*
X-1022350Y-88750D01*
X-1021475Y-87750D01*
G01X-1008150Y-90000D02*
X-1015150D01*
Y-75000D01*
X-1008150D01*
G01X-1010950Y-82250D02*
X-1015150D01*
G01X-979400Y-76250D02*
X-980450Y-75500D01*
X-981675Y-75000D01*
X-983075D01*
X-984650Y-75750D01*
X-985875Y-77000D01*
X-986750Y-78500D01*
X-987450Y-81000D01*
X-987625Y-83250D01*
X-987275Y-85500D01*
X-986750Y-87000D01*
X-985700Y-88500D01*
X-984475Y-89500D01*
X-983250Y-90000D01*
X-982025D01*
X-980800Y-89500D01*
X-979750Y-88750D01*
X-978875Y-87750D01*
G01X-969050Y-90000D02*
X-970450Y-89750D01*
X-971675Y-88750D01*
X-972725Y-87250D01*
X-973425Y-85500D01*
X-973775Y-83500D01*
Y-81500D01*
X-973425Y-79500D01*
X-972725Y-77750D01*
X-971675Y-76250D01*
X-970450Y-75250D01*
X-969050Y-75000D01*
X-967650Y-75250D01*
X-966425Y-76250D01*
X-965375Y-77750D01*
X-964675Y-79500D01*
X-964325Y-81500D01*
Y-83500D01*
X-964675Y-85500D01*
X-965375Y-87250D01*
X-966425Y-88750D01*
X-967650Y-89750D01*
X-969050Y-90000D01*
G01X-958700Y-75000D02*
Y-85750D01*
X-958000Y-88000D01*
X-956600Y-89500D01*
X-954850Y-90000D01*
X-953100Y-89500D01*
X-951700Y-88000D01*
X-951000Y-85750D01*
Y-75000D01*
G01X-944150Y-90000D02*
Y-75000D01*
X-939950D01*
X-938550Y-75750D01*
X-937500Y-77500D01*
X-937150Y-79500D01*
X-937500Y-81500D01*
X-938375Y-83000D01*
X-939950Y-83750D01*
X-944150D01*
G01X-926450Y-90000D02*
X-927850Y-89750D01*
X-929075Y-88750D01*
X-930125Y-87250D01*
X-930825Y-85500D01*
X-931175Y-83500D01*
Y-81500D01*
X-930825Y-79500D01*
X-930125Y-77750D01*
X-929075Y-76250D01*
X-927850Y-75250D01*
X-926450Y-75000D01*
X-925050Y-75250D01*
X-923825Y-76250D01*
X-922775Y-77750D01*
X-922075Y-79500D01*
X-921725Y-81500D01*
Y-83500D01*
X-922075Y-85500D01*
X-922775Y-87250D01*
X-923825Y-88750D01*
X-925050Y-89750D01*
X-926450Y-90000D01*
G01X-916275D02*
Y-75000D01*
X-908225Y-90000D01*
Y-75000D01*
G01X-901725Y-88000D02*
X-900325Y-89250D01*
X-898750Y-90000D01*
X-897350D01*
X-895950Y-89250D01*
X-894900Y-88000D01*
X-894375Y-86250D01*
X-894725Y-84500D01*
X-895600Y-83000D01*
X-897175Y-82000D01*
X-899275Y-81500D01*
X-900500Y-80500D01*
X-901025Y-78750D01*
X-900675Y-77000D01*
X-899800Y-75750D01*
X-898575Y-75000D01*
X-897350D01*
X-896125Y-75500D01*
X-895075Y-76750D01*
G01X-874200Y-90000D02*
Y-75000D01*
X-869650Y-87500D01*
X-865100Y-75000D01*
Y-90000D01*
G01X-859300Y-75000D02*
Y-85750D01*
X-858600Y-88000D01*
X-857200Y-89500D01*
X-855450Y-90000D01*
X-853700Y-89500D01*
X-852300Y-88000D01*
X-851600Y-85750D01*
Y-75000D01*
G01X-844925Y-88000D02*
X-843525Y-89250D01*
X-841950Y-90000D01*
X-840550D01*
X-839150Y-89250D01*
X-838100Y-88000D01*
X-837575Y-86250D01*
X-837925Y-84500D01*
X-838800Y-83000D01*
X-840375Y-82000D01*
X-842475Y-81500D01*
X-843700Y-80500D01*
X-844225Y-78750D01*
X-843875Y-77000D01*
X-843000Y-75750D01*
X-841775Y-75000D01*
X-840550D01*
X-839325Y-75500D01*
X-838275Y-76750D01*
G01X-827050Y-75000D02*
Y-90000D01*
G01X-831075Y-75000D02*
X-823025D01*
G01X-802150Y-90000D02*
Y-75000D01*
X-797775D01*
X-796375Y-75750D01*
X-795500Y-76750D01*
X-795150Y-78750D01*
X-795500Y-80750D01*
X-796550Y-82000D01*
X-797775Y-82750D01*
X-802150D01*
G01X-797775D02*
X-795150Y-90000D01*
G01X-780950D02*
X-787950D01*
Y-75000D01*
X-780950D01*
G01X-783750Y-82250D02*
X-787950D01*
G01X-773575Y-90000D02*
Y-75000D01*
X-766925D01*
G01X-769375Y-82250D02*
X-773575D01*
G01X-759550Y-75000D02*
Y-90000D01*
X-752550D01*
G01X-738350D02*
X-745350D01*
Y-75000D01*
X-738350D01*
G01X-741150Y-82250D02*
X-745350D01*
G01X-723800Y-76250D02*
X-724850Y-75500D01*
X-726075Y-75000D01*
X-727475D01*
X-729050Y-75750D01*
X-730275Y-77000D01*
X-731150Y-78500D01*
X-731850Y-81000D01*
X-732025Y-83250D01*
X-731675Y-85500D01*
X-731150Y-87000D01*
X-730100Y-88500D01*
X-728875Y-89500D01*
X-727650Y-90000D01*
X-726425D01*
X-725200Y-89500D01*
X-724150Y-88750D01*
X-723275Y-87750D01*
G01X-713450Y-75000D02*
Y-90000D01*
G01X-717475Y-75000D02*
X-709425D01*
G01X-681550Y-90000D02*
X-688550D01*
Y-75000D01*
X-681550D01*
G01X-684350Y-82250D02*
X-688550D01*
G01X-675225Y-90000D02*
X-670850Y-75000D01*
X-666475Y-90000D01*
G01X-668050Y-84750D02*
X-673650D01*
G01X-652800Y-76250D02*
X-653850Y-75500D01*
X-655075Y-75000D01*
X-656475D01*
X-658050Y-75750D01*
X-659275Y-77000D01*
X-660150Y-78500D01*
X-660850Y-81000D01*
X-661025Y-83250D01*
X-660675Y-85500D01*
X-660150Y-87000D01*
X-659100Y-88500D01*
X-657875Y-89500D01*
X-656650Y-90000D01*
X-655425D01*
X-654200Y-89500D01*
X-653150Y-88750D01*
X-652275Y-87750D01*
G01X-646125Y-90000D02*
Y-75000D01*
G01X-638775D02*
Y-90000D01*
G01Y-82500D02*
X-646125D01*
G01X-1693250Y-55000D02*
Y-40000D01*
X-1695350Y-43000D01*
G01Y-55000D02*
X-1691150D01*
G01X-1679400D02*
X-1679050Y-51750D01*
X-1678525Y-49000D01*
X-1677825Y-46500D01*
X-1676950Y-43750D01*
X-1675550Y-40000D01*
X-1682550D01*
G01X-1664850Y-55500D02*
X-1665200Y-55250D01*
Y-54750D01*
X-1664850Y-54500D01*
X-1664500Y-54750D01*
Y-55250D01*
X-1664850Y-55500D01*
G01X-1639950Y-55000D02*
Y-40000D01*
X-1635575D01*
X-1634175Y-40750D01*
X-1633300Y-41750D01*
X-1632950Y-43750D01*
X-1633300Y-45750D01*
X-1634350Y-47000D01*
X-1635575Y-47750D01*
X-1639950D01*
G01X-1635575D02*
X-1632950Y-55000D01*
G01X-1618750D02*
X-1625750D01*
Y-40000D01*
X-1618750D01*
G01X-1621550Y-47250D02*
X-1625750D01*
G01X-1612600Y-55000D02*
Y-40000D01*
X-1608050Y-52500D01*
X-1603500Y-40000D01*
Y-55000D01*
G01X-1593850D02*
X-1595250Y-54750D01*
X-1596475Y-53750D01*
X-1597525Y-52250D01*
X-1598225Y-50500D01*
X-1598575Y-48500D01*
Y-46500D01*
X-1598225Y-44500D01*
X-1597525Y-42750D01*
X-1596475Y-41250D01*
X-1595250Y-40250D01*
X-1593850Y-40000D01*
X-1592450Y-40250D01*
X-1591225Y-41250D01*
X-1590175Y-42750D01*
X-1589475Y-44500D01*
X-1589125Y-46500D01*
Y-48500D01*
X-1589475Y-50500D01*
X-1590175Y-52250D01*
X-1591225Y-53750D01*
X-1592450Y-54750D01*
X-1593850Y-55000D01*
G01X-1584025Y-40000D02*
X-1579650Y-55000D01*
X-1575275Y-40000D01*
G01X-1561950Y-55000D02*
X-1568950D01*
Y-40000D01*
X-1561950D01*
G01X-1564750Y-47250D02*
X-1568950D01*
G01X-1541425Y-55000D02*
X-1537050Y-40000D01*
X-1532675Y-55000D01*
G01X-1534250Y-49750D02*
X-1539850D01*
G01X-1526350Y-40000D02*
Y-55000D01*
X-1519350D01*
G01X-1512150Y-40000D02*
Y-55000D01*
X-1505150D01*
G01X-1484100Y-40000D02*
Y-50750D01*
X-1483400Y-53000D01*
X-1482000Y-54500D01*
X-1480250Y-55000D01*
X-1478500Y-54500D01*
X-1477100Y-53000D01*
X-1476400Y-50750D01*
Y-40000D01*
G01X-1470075Y-55000D02*
Y-40000D01*
X-1462025Y-55000D01*
Y-40000D01*
G01X-1455700D02*
Y-50750D01*
X-1455000Y-53000D01*
X-1453600Y-54500D01*
X-1451850Y-55000D01*
X-1450100Y-54500D01*
X-1448700Y-53000D01*
X-1448000Y-50750D01*
Y-40000D01*
G01X-1441325Y-53000D02*
X-1439925Y-54250D01*
X-1438350Y-55000D01*
X-1436950D01*
X-1435550Y-54250D01*
X-1434500Y-53000D01*
X-1433975Y-51250D01*
X-1434325Y-49500D01*
X-1435200Y-48000D01*
X-1436775Y-47000D01*
X-1438875Y-46500D01*
X-1440100Y-45500D01*
X-1440625Y-43750D01*
X-1440275Y-42000D01*
X-1439400Y-40750D01*
X-1438175Y-40000D01*
X-1436950D01*
X-1435725Y-40500D01*
X-1434675Y-41750D01*
G01X-1419950Y-55000D02*
X-1426950D01*
Y-40000D01*
X-1419950D01*
G01X-1422750Y-47250D02*
X-1426950D01*
G01X-1413100Y-55000D02*
Y-40000D01*
X-1409600D01*
X-1408200Y-40750D01*
X-1407150Y-41750D01*
X-1406275Y-43250D01*
X-1405575Y-45000D01*
X-1405400Y-47500D01*
X-1405575Y-50000D01*
X-1406275Y-51750D01*
X-1407150Y-53250D01*
X-1408200Y-54250D01*
X-1409600Y-55000D01*
X-1413100D01*
G01X-1384350D02*
Y-40000D01*
X-1380150D01*
X-1378750Y-40750D01*
X-1377700Y-42500D01*
X-1377350Y-44500D01*
X-1377700Y-46500D01*
X-1378575Y-48000D01*
X-1380150Y-48750D01*
X-1384350D01*
G01X-1371025Y-55000D02*
X-1366650Y-40000D01*
X-1362275Y-55000D01*
G01X-1363850Y-49750D02*
X-1369450D01*
G01X-1356300Y-55000D02*
Y-40000D01*
X-1352800D01*
X-1351400Y-40750D01*
X-1350350Y-41750D01*
X-1349475Y-43250D01*
X-1348775Y-45000D01*
X-1348600Y-47500D01*
X-1348775Y-50000D01*
X-1349475Y-51750D01*
X-1350350Y-53250D01*
X-1351400Y-54250D01*
X-1352800Y-55000D01*
X-1356300D01*
G01X-1341925Y-53000D02*
X-1340525Y-54250D01*
X-1338950Y-55000D01*
X-1337550D01*
X-1336150Y-54250D01*
X-1335100Y-53000D01*
X-1334575Y-51250D01*
X-1334925Y-49500D01*
X-1335800Y-48000D01*
X-1337375Y-47000D01*
X-1339475Y-46500D01*
X-1340700Y-45500D01*
X-1341225Y-43750D01*
X-1340875Y-42000D01*
X-1340000Y-40750D01*
X-1338775Y-40000D01*
X-1337550D01*
X-1336325Y-40500D01*
X-1335275Y-41750D01*
G01X-1313175Y-55000D02*
Y-40000D01*
X-1306525D01*
G01X-1308975Y-47250D02*
X-1313175D01*
G01X-1299150Y-55000D02*
Y-40000D01*
X-1294775D01*
X-1293375Y-40750D01*
X-1292500Y-41750D01*
X-1292150Y-43750D01*
X-1292500Y-45750D01*
X-1293550Y-47000D01*
X-1294775Y-47750D01*
X-1299150D01*
G01X-1294775D02*
X-1292150Y-55000D01*
G01X-1281450D02*
X-1282850Y-54750D01*
X-1284075Y-53750D01*
X-1285125Y-52250D01*
X-1285825Y-50500D01*
X-1286175Y-48500D01*
Y-46500D01*
X-1285825Y-44500D01*
X-1285125Y-42750D01*
X-1284075Y-41250D01*
X-1282850Y-40250D01*
X-1281450Y-40000D01*
X-1280050Y-40250D01*
X-1278825Y-41250D01*
X-1277775Y-42750D01*
X-1277075Y-44500D01*
X-1276725Y-46500D01*
Y-48500D01*
X-1277075Y-50500D01*
X-1277775Y-52250D01*
X-1278825Y-53750D01*
X-1280050Y-54750D01*
X-1281450Y-55000D01*
G01X-1271800D02*
Y-40000D01*
X-1267250Y-52500D01*
X-1262700Y-40000D01*
Y-55000D01*
G01X-1240950Y-40000D02*
X-1236750D01*
G01X-1238850D02*
Y-55000D01*
G01X-1240950D02*
X-1236750D01*
G01X-1228675D02*
Y-40000D01*
X-1220625Y-55000D01*
Y-40000D01*
G01X-1214475Y-55000D02*
Y-40000D01*
X-1206425Y-55000D01*
Y-40000D01*
G01X-1192750Y-55000D02*
X-1199750D01*
Y-40000D01*
X-1192750D01*
G01X-1195550Y-47250D02*
X-1199750D01*
G01X-1185550Y-55000D02*
Y-40000D01*
X-1181175D01*
X-1179775Y-40750D01*
X-1178900Y-41750D01*
X-1178550Y-43750D01*
X-1178900Y-45750D01*
X-1179950Y-47000D01*
X-1181175Y-47750D01*
X-1185550D01*
G01X-1181175D02*
X-1178550Y-55000D01*
G01X-1157150Y-40000D02*
Y-55000D01*
X-1150150D01*
G01X-1143825D02*
X-1139450Y-40000D01*
X-1135075Y-55000D01*
G01X-1136650Y-49750D02*
X-1142250D01*
G01X-1125250Y-55000D02*
Y-48250D01*
X-1128750Y-40000D01*
G01X-1121750D02*
X-1125250Y-48250D01*
G01X-1107550Y-55000D02*
X-1114550D01*
Y-40000D01*
X-1107550D01*
G01X-1110350Y-47250D02*
X-1114550D01*
G01X-1100350Y-55000D02*
Y-40000D01*
X-1095975D01*
X-1094575Y-40750D01*
X-1093700Y-41750D01*
X-1093350Y-43750D01*
X-1093700Y-45750D01*
X-1094750Y-47000D01*
X-1095975Y-47750D01*
X-1100350D01*
G01X-1095975D02*
X-1093350Y-55000D01*
G01X-1086325Y-53000D02*
X-1084925Y-54250D01*
X-1083350Y-55000D01*
X-1081950D01*
X-1080550Y-54250D01*
X-1079500Y-53000D01*
X-1078975Y-51250D01*
X-1079325Y-49500D01*
X-1080200Y-48000D01*
X-1081775Y-47000D01*
X-1083875Y-46500D01*
X-1085100Y-45500D01*
X-1085625Y-43750D01*
X-1085275Y-42000D01*
X-1084400Y-40750D01*
X-1083175Y-40000D01*
X-1081950D01*
X-1080725Y-40500D01*
X-1079675Y-41750D01*
G01X-1068450Y-55500D02*
X-1068800Y-55250D01*
Y-54750D01*
X-1068450Y-54500D01*
X-1068100Y-54750D01*
Y-55250D01*
X-1068450Y-55500D01*
G01X-1638550Y-5000D02*
X-1634350D01*
G01X-1636450D02*
Y-20000D01*
G01X-1638550D02*
X-1634350D01*
G01X-1625575D02*
Y-5000D01*
X-1618925D01*
G01X-1621375Y-12250D02*
X-1625575D01*
G01X-1595950Y-5000D02*
X-1591750D01*
G01X-1593850D02*
Y-20000D01*
G01X-1595950D02*
X-1591750D01*
G01X-1584200D02*
Y-5000D01*
X-1579650Y-17500D01*
X-1575100Y-5000D01*
Y-20000D01*
G01X-1568950D02*
Y-5000D01*
X-1564750D01*
X-1563350Y-5750D01*
X-1562300Y-7500D01*
X-1561950Y-9500D01*
X-1562300Y-11500D01*
X-1563175Y-13000D01*
X-1564750Y-13750D01*
X-1568950D01*
G01X-1555625Y-20000D02*
X-1551250Y-5000D01*
X-1546875Y-20000D01*
G01X-1548450Y-14750D02*
X-1554050D01*
G01X-1533200Y-6250D02*
X-1534250Y-5500D01*
X-1535475Y-5000D01*
X-1536875D01*
X-1538450Y-5750D01*
X-1539675Y-7000D01*
X-1540550Y-8500D01*
X-1541250Y-11000D01*
X-1541425Y-13250D01*
X-1541075Y-15500D01*
X-1540550Y-17000D01*
X-1539500Y-18500D01*
X-1538275Y-19500D01*
X-1537050Y-20000D01*
X-1535825D01*
X-1534600Y-19500D01*
X-1533550Y-18750D01*
X-1532675Y-17750D01*
G01X-1522850Y-5000D02*
Y-20000D01*
G01X-1526875Y-5000D02*
X-1518825D01*
G01X-1494450D02*
Y-20000D01*
G01X-1498475Y-5000D02*
X-1490425D01*
G01X-1480250Y-20000D02*
X-1481650Y-19750D01*
X-1482875Y-18750D01*
X-1483925Y-17250D01*
X-1484625Y-15500D01*
X-1484975Y-13500D01*
Y-11500D01*
X-1484625Y-9500D01*
X-1483925Y-7750D01*
X-1482875Y-6250D01*
X-1481650Y-5250D01*
X-1480250Y-5000D01*
X-1478850Y-5250D01*
X-1477625Y-6250D01*
X-1476575Y-7750D01*
X-1475875Y-9500D01*
X-1475525Y-11500D01*
Y-13500D01*
X-1475875Y-15500D01*
X-1476575Y-17250D01*
X-1477625Y-18750D01*
X-1478850Y-19750D01*
X-1480250Y-20000D01*
G01X-1455350Y-5000D02*
Y-20000D01*
X-1448350D01*
G01X-1434150D02*
X-1441150D01*
Y-5000D01*
X-1434150D01*
G01X-1436950Y-12250D02*
X-1441150D01*
G01X-1422400Y-12500D02*
X-1418900D01*
Y-17000D01*
X-1419950Y-18500D01*
X-1421175Y-19500D01*
X-1422925Y-20000D01*
X-1424675Y-19500D01*
X-1425900Y-18500D01*
X-1426950Y-17000D01*
X-1427650Y-15250D01*
X-1428000Y-13250D01*
Y-11500D01*
X-1427650Y-10000D01*
X-1426950Y-8250D01*
X-1425900Y-6750D01*
X-1424850Y-5750D01*
X-1423450Y-5000D01*
X-1422225D01*
X-1420825Y-5500D01*
X-1419775Y-6500D01*
G01X-1411350Y-5000D02*
X-1407150D01*
G01X-1409250D02*
Y-20000D01*
G01X-1411350D02*
X-1407150D01*
G01X-1393650Y-12000D02*
X-1392950Y-11250D01*
X-1392425Y-10000D01*
X-1392075Y-8250D01*
X-1392425Y-6750D01*
X-1393125Y-5750D01*
X-1394350Y-5000D01*
X-1399075D01*
Y-20000D01*
X-1393300D01*
X-1392075Y-19000D01*
X-1391375Y-17500D01*
X-1391025Y-15750D01*
X-1391375Y-14000D01*
X-1392425Y-12500D01*
X-1393650Y-12000D01*
X-1399075D01*
G01X-1382950Y-5000D02*
X-1378750D01*
G01X-1380850D02*
Y-20000D01*
G01X-1382950D02*
X-1378750D01*
G01X-1370150Y-5000D02*
Y-20000D01*
X-1363150D01*
G01X-1354550Y-5000D02*
X-1350350D01*
G01X-1352450D02*
Y-20000D01*
G01X-1354550D02*
X-1350350D01*
G01X-1338250Y-5000D02*
Y-20000D01*
G01X-1342275Y-5000D02*
X-1334225D01*
G01X-1324050Y-20000D02*
Y-13250D01*
X-1327550Y-5000D01*
G01X-1320550D02*
X-1324050Y-13250D01*
G01X-1309850Y-20500D02*
X-1310200Y-20250D01*
Y-19750D01*
X-1309850Y-19500D01*
X-1309500Y-19750D01*
Y-20250D01*
X-1309850Y-20500D01*
G01X-1640125Y12000D02*
X-1638725Y10750D01*
X-1637150Y10000D01*
X-1635750D01*
X-1634350Y10750D01*
X-1633300Y12000D01*
X-1632775Y13750D01*
X-1633125Y15500D01*
X-1634000Y17000D01*
X-1635575Y18000D01*
X-1637675Y18500D01*
X-1638900Y19500D01*
X-1639425Y21250D01*
X-1639075Y23000D01*
X-1638200Y24250D01*
X-1636975Y25000D01*
X-1635750D01*
X-1634525Y24500D01*
X-1633475Y23250D01*
G01X-1624350Y25000D02*
X-1620150D01*
G01X-1622250D02*
Y10000D01*
G01X-1624350D02*
X-1620150D01*
G01X-1611550Y25000D02*
Y10000D01*
X-1604550D01*
G01X-1597700D02*
Y25000D01*
G01X-1591050D02*
X-1597700Y15750D01*
G01X-1590000Y10000D02*
X-1594725Y20000D01*
G01X-1583325Y12000D02*
X-1581925Y10750D01*
X-1580350Y10000D01*
X-1578950D01*
X-1577550Y10750D01*
X-1576500Y12000D01*
X-1575975Y13750D01*
X-1576325Y15500D01*
X-1577200Y17000D01*
X-1578775Y18000D01*
X-1580875Y18500D01*
X-1582100Y19500D01*
X-1582625Y21250D01*
X-1582275Y23000D01*
X-1581400Y24250D01*
X-1580175Y25000D01*
X-1578950D01*
X-1577725Y24500D01*
X-1576675Y23250D01*
G01X-1561600Y23750D02*
X-1562650Y24500D01*
X-1563875Y25000D01*
X-1565275D01*
X-1566850Y24250D01*
X-1568075Y23000D01*
X-1568950Y21500D01*
X-1569650Y19000D01*
X-1569825Y16750D01*
X-1569475Y14500D01*
X-1568950Y13000D01*
X-1567900Y11500D01*
X-1566675Y10500D01*
X-1565450Y10000D01*
X-1564225D01*
X-1563000Y10500D01*
X-1561950Y11250D01*
X-1561075Y12250D01*
G01X-1554750Y10000D02*
Y25000D01*
X-1550375D01*
X-1548975Y24250D01*
X-1548100Y23250D01*
X-1547750Y21250D01*
X-1548100Y19250D01*
X-1549150Y18000D01*
X-1550375Y17250D01*
X-1554750D01*
G01X-1550375D02*
X-1547750Y10000D01*
G01X-1533550D02*
X-1540550D01*
Y25000D01*
X-1533550D01*
G01X-1536350Y17750D02*
X-1540550D01*
G01X-1519350Y10000D02*
X-1526350D01*
Y25000D01*
X-1519350D01*
G01X-1522150Y17750D02*
X-1526350D01*
G01X-1512675Y10000D02*
Y25000D01*
X-1504625Y10000D01*
Y25000D01*
G01X-1483925Y12000D02*
X-1482525Y10750D01*
X-1480950Y10000D01*
X-1479550D01*
X-1478150Y10750D01*
X-1477100Y12000D01*
X-1476575Y13750D01*
X-1476925Y15500D01*
X-1477800Y17000D01*
X-1479375Y18000D01*
X-1481475Y18500D01*
X-1482700Y19500D01*
X-1483225Y21250D01*
X-1482875Y23000D01*
X-1482000Y24250D01*
X-1480775Y25000D01*
X-1479550D01*
X-1478325Y24500D01*
X-1477275Y23250D01*
G01X-1469725Y10000D02*
Y25000D01*
G01X-1462375D02*
Y10000D01*
G01Y17500D02*
X-1469725D01*
G01X-1456225Y10000D02*
X-1451850Y25000D01*
X-1447475Y10000D01*
G01X-1449050Y15250D02*
X-1454650D01*
G01X-1441150Y25000D02*
Y10000D01*
X-1434150D01*
G01X-1426950Y25000D02*
Y10000D01*
X-1419950D01*
G01X-1393650Y18000D02*
X-1392950Y18750D01*
X-1392425Y20000D01*
X-1392075Y21750D01*
X-1392425Y23250D01*
X-1393125Y24250D01*
X-1394350Y25000D01*
X-1399075D01*
Y10000D01*
X-1393300D01*
X-1392075Y11000D01*
X-1391375Y12500D01*
X-1391025Y14250D01*
X-1391375Y16000D01*
X-1392425Y17500D01*
X-1393650Y18000D01*
X-1399075D01*
G01X-1377350Y10000D02*
X-1384350D01*
Y25000D01*
X-1377350D01*
G01X-1380150Y17750D02*
X-1384350D01*
G01X-1352450Y10000D02*
X-1353850Y10250D01*
X-1355075Y11250D01*
X-1356125Y12750D01*
X-1356825Y14500D01*
X-1357175Y16500D01*
Y18500D01*
X-1356825Y20500D01*
X-1356125Y22250D01*
X-1355075Y23750D01*
X-1353850Y24750D01*
X-1352450Y25000D01*
X-1351050Y24750D01*
X-1349825Y23750D01*
X-1348775Y22250D01*
X-1348075Y20500D01*
X-1347725Y18500D01*
Y16500D01*
X-1348075Y14500D01*
X-1348775Y12750D01*
X-1349825Y11250D01*
X-1351050Y10250D01*
X-1352450Y10000D01*
G01X-1342275D02*
Y25000D01*
X-1334225Y10000D01*
Y25000D01*
G01X-1314225Y10000D02*
X-1309850Y25000D01*
X-1305475Y10000D01*
G01X-1307050Y15250D02*
X-1312650D01*
G01X-1299675Y10000D02*
Y25000D01*
X-1291625Y10000D01*
Y25000D01*
G01X-1281450Y10000D02*
Y16750D01*
X-1284950Y25000D01*
G01X-1277950D02*
X-1281450Y16750D01*
G01X-1249550Y10000D02*
X-1256550D01*
Y25000D01*
X-1249550D01*
G01X-1252350Y17750D02*
X-1256550D01*
G01X-1242525Y10000D02*
X-1235175Y25000D01*
G01X-1242525D02*
X-1235175Y10000D01*
G01X-1228150D02*
Y25000D01*
X-1223950D01*
X-1222550Y24250D01*
X-1221500Y22500D01*
X-1221150Y20500D01*
X-1221500Y18500D01*
X-1222375Y17000D01*
X-1223950Y16250D01*
X-1228150D01*
G01X-1210450Y10000D02*
X-1211850Y10250D01*
X-1213075Y11250D01*
X-1214125Y12750D01*
X-1214825Y14500D01*
X-1215175Y16500D01*
Y18500D01*
X-1214825Y20500D01*
X-1214125Y22250D01*
X-1213075Y23750D01*
X-1211850Y24750D01*
X-1210450Y25000D01*
X-1209050Y24750D01*
X-1207825Y23750D01*
X-1206775Y22250D01*
X-1206075Y20500D01*
X-1205725Y18500D01*
Y16500D01*
X-1206075Y14500D01*
X-1206775Y12750D01*
X-1207825Y11250D01*
X-1209050Y10250D01*
X-1210450Y10000D01*
G01X-1199925Y12000D02*
X-1198525Y10750D01*
X-1196950Y10000D01*
X-1195550D01*
X-1194150Y10750D01*
X-1193100Y12000D01*
X-1192575Y13750D01*
X-1192925Y15500D01*
X-1193800Y17000D01*
X-1195375Y18000D01*
X-1197475Y18500D01*
X-1198700Y19500D01*
X-1199225Y21250D01*
X-1198875Y23000D01*
X-1198000Y24250D01*
X-1196775Y25000D01*
X-1195550D01*
X-1194325Y24500D01*
X-1193275Y23250D01*
G01X-1178550Y10000D02*
X-1185550D01*
Y25000D01*
X-1178550D01*
G01X-1181350Y17750D02*
X-1185550D01*
G01X-1171700Y10000D02*
Y25000D01*
X-1168200D01*
X-1166800Y24250D01*
X-1165750Y23250D01*
X-1164875Y21750D01*
X-1164175Y20000D01*
X-1164000Y17500D01*
X-1164175Y15000D01*
X-1164875Y13250D01*
X-1165750Y11750D01*
X-1166800Y10750D01*
X-1168200Y10000D01*
X-1171700D01*
G01X-1135600Y23750D02*
X-1136650Y24500D01*
X-1137875Y25000D01*
X-1139275D01*
X-1140850Y24250D01*
X-1142075Y23000D01*
X-1142950Y21500D01*
X-1143650Y19000D01*
X-1143825Y16750D01*
X-1143475Y14500D01*
X-1142950Y13000D01*
X-1141900Y11500D01*
X-1140675Y10500D01*
X-1139450Y10000D01*
X-1138225D01*
X-1137000Y10500D01*
X-1135950Y11250D01*
X-1135075Y12250D01*
G01X-1125250Y10000D02*
X-1126650Y10250D01*
X-1127875Y11250D01*
X-1128925Y12750D01*
X-1129625Y14500D01*
X-1129975Y16500D01*
Y18500D01*
X-1129625Y20500D01*
X-1128925Y22250D01*
X-1127875Y23750D01*
X-1126650Y24750D01*
X-1125250Y25000D01*
X-1123850Y24750D01*
X-1122625Y23750D01*
X-1121575Y22250D01*
X-1120875Y20500D01*
X-1120525Y18500D01*
Y16500D01*
X-1120875Y14500D01*
X-1121575Y12750D01*
X-1122625Y11250D01*
X-1123850Y10250D01*
X-1125250Y10000D01*
G01X-1114550D02*
Y25000D01*
X-1110350D01*
X-1108950Y24250D01*
X-1107900Y22500D01*
X-1107550Y20500D01*
X-1107900Y18500D01*
X-1108775Y17000D01*
X-1110350Y16250D01*
X-1114550D01*
G01X-1100350Y10000D02*
Y25000D01*
X-1096150D01*
X-1094750Y24250D01*
X-1093700Y22500D01*
X-1093350Y20500D01*
X-1093700Y18500D01*
X-1094575Y17000D01*
X-1096150Y16250D01*
X-1100350D01*
G01X-1079150Y10000D02*
X-1086150D01*
Y25000D01*
X-1079150D01*
G01X-1081950Y17750D02*
X-1086150D01*
G01X-1071950Y10000D02*
Y25000D01*
X-1067575D01*
X-1066175Y24250D01*
X-1065300Y23250D01*
X-1064950Y21250D01*
X-1065300Y19250D01*
X-1066350Y18000D01*
X-1067575Y17250D01*
X-1071950D01*
G01X-1067575D02*
X-1064950Y10000D01*
G01X-1043550D02*
Y25000D01*
X-1039350D01*
X-1037950Y24250D01*
X-1036900Y22500D01*
X-1036550Y20500D01*
X-1036900Y18500D01*
X-1037775Y17000D01*
X-1039350Y16250D01*
X-1043550D01*
G01X-1030225Y10000D02*
X-1025850Y25000D01*
X-1021475Y10000D01*
G01X-1023050Y15250D02*
X-1028650D01*
G01X-1015500Y10000D02*
Y25000D01*
X-1012000D01*
X-1010600Y24250D01*
X-1009550Y23250D01*
X-1008675Y21750D01*
X-1007975Y20000D01*
X-1007800Y17500D01*
X-1007975Y15000D01*
X-1008675Y13250D01*
X-1009550Y11750D01*
X-1010600Y10750D01*
X-1012000Y10000D01*
X-1015500D01*
G01X-997450Y9500D02*
X-997800Y9750D01*
Y10250D01*
X-997450Y10500D01*
X-997100Y10250D01*
Y9750D01*
X-997450Y9500D01*
G01X-969050Y25000D02*
Y10000D01*
G01X-973075Y25000D02*
X-965025D01*
G01X-958350Y10000D02*
Y25000D01*
X-953975D01*
X-952575Y24250D01*
X-951700Y23250D01*
X-951350Y21250D01*
X-951700Y19250D01*
X-952750Y18000D01*
X-953975Y17250D01*
X-958350D01*
G01X-953975D02*
X-951350Y10000D01*
G01X-942750Y25000D02*
X-938550D01*
G01X-940650D02*
Y10000D01*
G01X-942750D02*
X-938550D01*
G01X-931000D02*
Y25000D01*
X-926450Y12500D01*
X-921900Y25000D01*
Y10000D01*
G01X-916800D02*
Y25000D01*
X-912250Y12500D01*
X-907700Y25000D01*
Y10000D01*
G01X-900150Y25000D02*
X-895950D01*
G01X-898050D02*
Y10000D01*
G01X-900150D02*
X-895950D01*
G01X-887875D02*
Y25000D01*
X-879825Y10000D01*
Y25000D01*
G01X-868600Y17500D02*
X-865100D01*
Y13000D01*
X-866150Y11500D01*
X-867375Y10500D01*
X-869125Y10000D01*
X-870875Y10500D01*
X-872100Y11500D01*
X-873150Y13000D01*
X-873850Y14750D01*
X-874200Y16750D01*
Y18500D01*
X-873850Y20000D01*
X-873150Y21750D01*
X-872100Y23250D01*
X-871050Y24250D01*
X-869650Y25000D01*
X-868425D01*
X-867025Y24500D01*
X-865975Y23500D01*
G01X-845625Y10000D02*
X-841250Y25000D01*
X-836875Y10000D01*
G01X-838450Y15250D02*
X-844050D01*
G01X-830550Y25000D02*
Y10000D01*
X-823550D01*
G01X-816350Y25000D02*
Y10000D01*
X-809350D01*
G01X-798650D02*
X-800050Y10250D01*
X-801275Y11250D01*
X-802325Y12750D01*
X-803025Y14500D01*
X-803375Y16500D01*
Y18500D01*
X-803025Y20500D01*
X-802325Y22250D01*
X-801275Y23750D01*
X-800050Y24750D01*
X-798650Y25000D01*
X-797250Y24750D01*
X-796025Y23750D01*
X-794975Y22250D01*
X-794275Y20500D01*
X-793925Y18500D01*
Y16500D01*
X-794275Y14500D01*
X-794975Y12750D01*
X-796025Y11250D01*
X-797250Y10250D01*
X-798650Y10000D01*
G01X-789700Y25000D02*
X-787250Y10000D01*
X-784450Y25000D01*
X-781650Y10000D01*
X-779200Y25000D01*
G01X-766750Y10000D02*
X-773750D01*
Y25000D01*
X-766750D01*
G01X-769550Y17750D02*
X-773750D01*
G01X-759900Y10000D02*
Y25000D01*
X-756400D01*
X-755000Y24250D01*
X-753950Y23250D01*
X-753075Y21750D01*
X-752375Y20000D01*
X-752200Y17500D01*
X-752375Y15000D01*
X-753075Y13250D01*
X-753950Y11750D01*
X-755000Y10750D01*
X-756400Y10000D01*
X-759900D01*
G01X-724150D02*
X-731150D01*
Y25000D01*
X-724150D01*
G01X-726950Y17750D02*
X-731150D01*
G01X-717825Y25000D02*
X-713450Y10000D01*
X-709075Y25000D01*
G01X-695750Y10000D02*
X-702750D01*
Y25000D01*
X-695750D01*
G01X-698550Y17750D02*
X-702750D01*
G01X-689075Y10000D02*
Y25000D01*
X-681025Y10000D01*
Y25000D01*
G01X-1693250Y40000D02*
Y55000D01*
X-1695350Y52000D01*
G01Y40000D02*
X-1691150D01*
G01X-1682375Y46250D02*
X-1681150Y48000D01*
X-1680100Y49000D01*
X-1678700Y49500D01*
X-1677475Y49000D01*
X-1676600Y48000D01*
X-1675900Y46500D01*
X-1675725Y44750D01*
X-1675900Y43250D01*
X-1676600Y41750D01*
X-1677650Y40500D01*
X-1678875Y40000D01*
X-1680275Y40500D01*
X-1681500Y42000D01*
X-1682200Y44250D01*
X-1682375Y46750D01*
X-1682025Y50000D01*
X-1681500Y51750D01*
X-1680625Y53500D01*
X-1679400Y54750D01*
X-1678175Y55000D01*
X-1676950Y54500D01*
X-1676075Y53250D01*
G01X-1664850Y39500D02*
X-1665200Y39750D01*
Y40250D01*
X-1664850Y40500D01*
X-1664500Y40250D01*
Y39750D01*
X-1664850Y39500D01*
G01X-1640125Y42000D02*
X-1638725Y40750D01*
X-1637150Y40000D01*
X-1635750D01*
X-1634350Y40750D01*
X-1633300Y42000D01*
X-1632775Y43750D01*
X-1633125Y45500D01*
X-1634000Y47000D01*
X-1635575Y48000D01*
X-1637675Y48500D01*
X-1638900Y49500D01*
X-1639425Y51250D01*
X-1639075Y53000D01*
X-1638200Y54250D01*
X-1636975Y55000D01*
X-1635750D01*
X-1634525Y54500D01*
X-1633475Y53250D01*
G01X-1624350Y55000D02*
X-1620150D01*
G01X-1622250D02*
Y40000D01*
G01X-1624350D02*
X-1620150D01*
G01X-1611550Y55000D02*
Y40000D01*
X-1604550D01*
G01X-1597700D02*
Y55000D01*
G01X-1591050D02*
X-1597700Y45750D01*
G01X-1590000Y40000D02*
X-1594725Y50000D01*
G01X-1583325Y42000D02*
X-1581925Y40750D01*
X-1580350Y40000D01*
X-1578950D01*
X-1577550Y40750D01*
X-1576500Y42000D01*
X-1575975Y43750D01*
X-1576325Y45500D01*
X-1577200Y47000D01*
X-1578775Y48000D01*
X-1580875Y48500D01*
X-1582100Y49500D01*
X-1582625Y51250D01*
X-1582275Y53000D01*
X-1581400Y54250D01*
X-1580175Y55000D01*
X-1578950D01*
X-1577725Y54500D01*
X-1576675Y53250D01*
G01X-1561600Y53750D02*
X-1562650Y54500D01*
X-1563875Y55000D01*
X-1565275D01*
X-1566850Y54250D01*
X-1568075Y53000D01*
X-1568950Y51500D01*
X-1569650Y49000D01*
X-1569825Y46750D01*
X-1569475Y44500D01*
X-1568950Y43000D01*
X-1567900Y41500D01*
X-1566675Y40500D01*
X-1565450Y40000D01*
X-1564225D01*
X-1563000Y40500D01*
X-1561950Y41250D01*
X-1561075Y42250D01*
G01X-1554750Y40000D02*
Y55000D01*
X-1550375D01*
X-1548975Y54250D01*
X-1548100Y53250D01*
X-1547750Y51250D01*
X-1548100Y49250D01*
X-1549150Y48000D01*
X-1550375Y47250D01*
X-1554750D01*
G01X-1550375D02*
X-1547750Y40000D01*
G01X-1533550D02*
X-1540550D01*
Y55000D01*
X-1533550D01*
G01X-1536350Y47750D02*
X-1540550D01*
G01X-1519350Y40000D02*
X-1526350D01*
Y55000D01*
X-1519350D01*
G01X-1522150Y47750D02*
X-1526350D01*
G01X-1512675Y40000D02*
Y55000D01*
X-1504625Y40000D01*
Y55000D01*
G01X-1478850Y48000D02*
X-1478150Y48750D01*
X-1477625Y50000D01*
X-1477275Y51750D01*
X-1477625Y53250D01*
X-1478325Y54250D01*
X-1479550Y55000D01*
X-1484275D01*
Y40000D01*
X-1478500D01*
X-1477275Y41000D01*
X-1476575Y42500D01*
X-1476225Y44250D01*
X-1476575Y46000D01*
X-1477625Y47500D01*
X-1478850Y48000D01*
X-1484275D01*
G01X-1466050Y40000D02*
X-1467450Y40250D01*
X-1468675Y41250D01*
X-1469725Y42750D01*
X-1470425Y44500D01*
X-1470775Y46500D01*
Y48500D01*
X-1470425Y50500D01*
X-1469725Y52250D01*
X-1468675Y53750D01*
X-1467450Y54750D01*
X-1466050Y55000D01*
X-1464650Y54750D01*
X-1463425Y53750D01*
X-1462375Y52250D01*
X-1461675Y50500D01*
X-1461325Y48500D01*
Y46500D01*
X-1461675Y44500D01*
X-1462375Y42750D01*
X-1463425Y41250D01*
X-1464650Y40250D01*
X-1466050Y40000D01*
G01X-1451850Y55000D02*
Y40000D01*
G01X-1455875Y55000D02*
X-1447825D01*
G01X-1441325Y40000D02*
Y55000D01*
G01X-1433975D02*
Y40000D01*
G01Y47500D02*
X-1441325D01*
G01X-1412925Y42000D02*
X-1411525Y40750D01*
X-1409950Y40000D01*
X-1408550D01*
X-1407150Y40750D01*
X-1406100Y42000D01*
X-1405575Y43750D01*
X-1405925Y45500D01*
X-1406800Y47000D01*
X-1408375Y48000D01*
X-1410475Y48500D01*
X-1411700Y49500D01*
X-1412225Y51250D01*
X-1411875Y53000D01*
X-1411000Y54250D01*
X-1409775Y55000D01*
X-1408550D01*
X-1407325Y54500D01*
X-1406275Y53250D01*
G01X-1397150Y55000D02*
X-1392950D01*
G01X-1395050D02*
Y40000D01*
G01X-1397150D02*
X-1392950D01*
G01X-1384700D02*
Y55000D01*
X-1381200D01*
X-1379800Y54250D01*
X-1378750Y53250D01*
X-1377875Y51750D01*
X-1377175Y50000D01*
X-1377000Y47500D01*
X-1377175Y45000D01*
X-1377875Y43250D01*
X-1378750Y41750D01*
X-1379800Y40750D01*
X-1381200Y40000D01*
X-1384700D01*
G01X-1363150D02*
X-1370150D01*
Y55000D01*
X-1363150D01*
G01X-1365950Y47750D02*
X-1370150D01*
G01X-1356125Y42000D02*
X-1354725Y40750D01*
X-1353150Y40000D01*
X-1351750D01*
X-1350350Y40750D01*
X-1349300Y42000D01*
X-1348775Y43750D01*
X-1349125Y45500D01*
X-1350000Y47000D01*
X-1351575Y48000D01*
X-1353675Y48500D01*
X-1354900Y49500D01*
X-1355425Y51250D01*
X-1355075Y53000D01*
X-1354200Y54250D01*
X-1352975Y55000D01*
X-1351750D01*
X-1350525Y54500D01*
X-1349475Y53250D01*
G01X-1327900Y55000D02*
Y44250D01*
X-1327200Y42000D01*
X-1325800Y40500D01*
X-1324050Y40000D01*
X-1322300Y40500D01*
X-1320900Y42000D01*
X-1320200Y44250D01*
Y55000D01*
G01X-1313525Y42000D02*
X-1312125Y40750D01*
X-1310550Y40000D01*
X-1309150D01*
X-1307750Y40750D01*
X-1306700Y42000D01*
X-1306175Y43750D01*
X-1306525Y45500D01*
X-1307400Y47000D01*
X-1308975Y48000D01*
X-1311075Y48500D01*
X-1312300Y49500D01*
X-1312825Y51250D01*
X-1312475Y53000D01*
X-1311600Y54250D01*
X-1310375Y55000D01*
X-1309150D01*
X-1307925Y54500D01*
X-1306875Y53250D01*
G01X-1297750Y55000D02*
X-1293550D01*
G01X-1295650D02*
Y40000D01*
G01X-1297750D02*
X-1293550D01*
G01X-1285475D02*
Y55000D01*
X-1277425Y40000D01*
Y55000D01*
G01X-1266200Y47500D02*
X-1262700D01*
Y43000D01*
X-1263750Y41500D01*
X-1264975Y40500D01*
X-1266725Y40000D01*
X-1268475Y40500D01*
X-1269700Y41500D01*
X-1270750Y43000D01*
X-1271450Y44750D01*
X-1271800Y46750D01*
Y48500D01*
X-1271450Y50000D01*
X-1270750Y51750D01*
X-1269700Y53250D01*
X-1268650Y54250D01*
X-1267250Y55000D01*
X-1266025D01*
X-1264625Y54500D01*
X-1263575Y53500D01*
G01X-1242875Y40000D02*
Y55000D01*
X-1234825Y40000D01*
Y55000D01*
G01X-1224650Y40000D02*
X-1226050Y40250D01*
X-1227275Y41250D01*
X-1228325Y42750D01*
X-1229025Y44500D01*
X-1229375Y46500D01*
Y48500D01*
X-1229025Y50500D01*
X-1228325Y52250D01*
X-1227275Y53750D01*
X-1226050Y54750D01*
X-1224650Y55000D01*
X-1223250Y54750D01*
X-1222025Y53750D01*
X-1220975Y52250D01*
X-1220275Y50500D01*
X-1219925Y48500D01*
Y46500D01*
X-1220275Y44500D01*
X-1220975Y42750D01*
X-1222025Y41250D01*
X-1223250Y40250D01*
X-1224650Y40000D01*
G01X-1214475D02*
Y55000D01*
X-1206425Y40000D01*
Y55000D01*
G01X-1198525Y45000D02*
X-1193975D01*
G01X-1178200Y53750D02*
X-1179250Y54500D01*
X-1180475Y55000D01*
X-1181875D01*
X-1183450Y54250D01*
X-1184675Y53000D01*
X-1185550Y51500D01*
X-1186250Y49000D01*
X-1186425Y46750D01*
X-1186075Y44500D01*
X-1185550Y43000D01*
X-1184500Y41500D01*
X-1183275Y40500D01*
X-1182050Y40000D01*
X-1180825D01*
X-1179600Y40500D01*
X-1178550Y41250D01*
X-1177675Y42250D01*
G01X-1167850Y40000D02*
X-1169250Y40250D01*
X-1170475Y41250D01*
X-1171525Y42750D01*
X-1172225Y44500D01*
X-1172575Y46500D01*
Y48500D01*
X-1172225Y50500D01*
X-1171525Y52250D01*
X-1170475Y53750D01*
X-1169250Y54750D01*
X-1167850Y55000D01*
X-1166450Y54750D01*
X-1165225Y53750D01*
X-1164175Y52250D01*
X-1163475Y50500D01*
X-1163125Y48500D01*
Y46500D01*
X-1163475Y44500D01*
X-1164175Y42750D01*
X-1165225Y41250D01*
X-1166450Y40250D01*
X-1167850Y40000D01*
G01X-1157675D02*
Y55000D01*
X-1149625Y40000D01*
Y55000D01*
G01X-1143300Y40000D02*
Y55000D01*
X-1139800D01*
X-1138400Y54250D01*
X-1137350Y53250D01*
X-1136475Y51750D01*
X-1135775Y50000D01*
X-1135600Y47500D01*
X-1135775Y45000D01*
X-1136475Y43250D01*
X-1137350Y41750D01*
X-1138400Y40750D01*
X-1139800Y40000D01*
X-1143300D01*
G01X-1129100Y55000D02*
Y44250D01*
X-1128400Y42000D01*
X-1127000Y40500D01*
X-1125250Y40000D01*
X-1123500Y40500D01*
X-1122100Y42000D01*
X-1121400Y44250D01*
Y55000D01*
G01X-1107200Y53750D02*
X-1108250Y54500D01*
X-1109475Y55000D01*
X-1110875D01*
X-1112450Y54250D01*
X-1113675Y53000D01*
X-1114550Y51500D01*
X-1115250Y49000D01*
X-1115425Y46750D01*
X-1115075Y44500D01*
X-1114550Y43000D01*
X-1113500Y41500D01*
X-1112275Y40500D01*
X-1111050Y40000D01*
X-1109825D01*
X-1108600Y40500D01*
X-1107550Y41250D01*
X-1106675Y42250D01*
G01X-1096850Y55000D02*
Y40000D01*
G01X-1100875Y55000D02*
X-1092825D01*
G01X-1084750D02*
X-1080550D01*
G01X-1082650D02*
Y40000D01*
G01X-1084750D02*
X-1080550D01*
G01X-1072825Y55000D02*
X-1068450Y40000D01*
X-1064075Y55000D01*
G01X-1050750Y40000D02*
X-1057750D01*
Y55000D01*
X-1050750D01*
G01X-1053550Y47750D02*
X-1057750D01*
G01X-1027950Y55000D02*
X-1023750D01*
G01X-1025850D02*
Y40000D01*
G01X-1027950D02*
X-1023750D01*
G01X-1015675D02*
Y55000D01*
X-1007625Y40000D01*
Y55000D01*
G01X-1001300Y40000D02*
Y55000D01*
G01X-994650D02*
X-1001300Y45750D01*
G01X-993600Y40000D02*
X-998325Y50000D01*
G01X-983250Y39500D02*
X-983600Y39750D01*
Y40250D01*
X-983250Y40500D01*
X-982900Y40250D01*
Y39750D01*
X-983250Y39500D01*
G01X-951000Y53750D02*
X-952050Y54500D01*
X-953275Y55000D01*
X-954675D01*
X-956250Y54250D01*
X-957475Y53000D01*
X-958350Y51500D01*
X-959050Y49000D01*
X-959225Y46750D01*
X-958875Y44500D01*
X-958350Y43000D01*
X-957300Y41500D01*
X-956075Y40500D01*
X-954850Y40000D01*
X-953625D01*
X-952400Y40500D01*
X-951350Y41250D01*
X-950475Y42250D01*
G01X-940650Y40000D02*
X-942050Y40250D01*
X-943275Y41250D01*
X-944325Y42750D01*
X-945025Y44500D01*
X-945375Y46500D01*
Y48500D01*
X-945025Y50500D01*
X-944325Y52250D01*
X-943275Y53750D01*
X-942050Y54750D01*
X-940650Y55000D01*
X-939250Y54750D01*
X-938025Y53750D01*
X-936975Y52250D01*
X-936275Y50500D01*
X-935925Y48500D01*
Y46500D01*
X-936275Y44500D01*
X-936975Y42750D01*
X-938025Y41250D01*
X-939250Y40250D01*
X-940650Y40000D01*
G01X-929950Y55000D02*
Y40000D01*
X-922950D01*
G01X-912250D02*
X-913650Y40250D01*
X-914875Y41250D01*
X-915925Y42750D01*
X-916625Y44500D01*
X-916975Y46500D01*
Y48500D01*
X-916625Y50500D01*
X-915925Y52250D01*
X-914875Y53750D01*
X-913650Y54750D01*
X-912250Y55000D01*
X-910850Y54750D01*
X-909625Y53750D01*
X-908575Y52250D01*
X-907875Y50500D01*
X-907525Y48500D01*
Y46500D01*
X-907875Y44500D01*
X-908575Y42750D01*
X-909625Y41250D01*
X-910850Y40250D01*
X-912250Y40000D01*
G01X-901550D02*
Y55000D01*
X-897175D01*
X-895775Y54250D01*
X-894900Y53250D01*
X-894550Y51250D01*
X-894900Y49250D01*
X-895950Y48000D01*
X-897175Y47250D01*
X-901550D01*
G01X-897175D02*
X-894550Y40000D01*
G01X-883850Y39500D02*
X-884200Y39750D01*
Y40250D01*
X-883850Y40500D01*
X-883500Y40250D01*
Y39750D01*
X-883850Y39500D01*
G01Y46250D02*
X-884200Y46500D01*
Y47000D01*
X-883850Y47250D01*
X-883500Y47000D01*
Y46500D01*
X-883850Y46250D01*
G01X-860700Y55000D02*
X-858250Y40000D01*
X-855450Y55000D01*
X-852650Y40000D01*
X-850200Y55000D01*
G01X-844925Y40000D02*
Y55000D01*
G01X-837575D02*
Y40000D01*
G01Y47500D02*
X-844925D01*
G01X-829150Y55000D02*
X-824950D01*
G01X-827050D02*
Y40000D01*
G01X-829150D02*
X-824950D01*
G01X-812850Y55000D02*
Y40000D01*
G01X-816875Y55000D02*
X-808825D01*
G01X-795150Y40000D02*
X-802150D01*
Y55000D01*
X-795150D01*
G01X-797950Y47750D02*
X-802150D01*
G01X-784450Y39500D02*
X-784800Y39750D01*
Y40250D01*
X-784450Y40500D01*
X-784100Y40250D01*
Y39750D01*
X-784450Y39500D01*
G01X-760075Y40000D02*
Y55000D01*
X-752025Y40000D01*
Y55000D01*
G01X-741850Y40000D02*
X-743250Y40250D01*
X-744475Y41250D01*
X-745525Y42750D01*
X-746225Y44500D01*
X-746575Y46500D01*
Y48500D01*
X-746225Y50500D01*
X-745525Y52250D01*
X-744475Y53750D01*
X-743250Y54750D01*
X-741850Y55000D01*
X-740450Y54750D01*
X-739225Y53750D01*
X-738175Y52250D01*
X-737475Y50500D01*
X-737125Y48500D01*
Y46500D01*
X-737475Y44500D01*
X-738175Y42750D01*
X-739225Y41250D01*
X-740450Y40250D01*
X-741850Y40000D01*
G01X-1639950Y75000D02*
Y90000D01*
X-1635575D01*
X-1634175Y89250D01*
X-1633300Y88250D01*
X-1632950Y86250D01*
X-1633300Y84250D01*
X-1634350Y83000D01*
X-1635575Y82250D01*
X-1639950D01*
G01X-1635575D02*
X-1632950Y75000D01*
G01X-1618750D02*
X-1625750D01*
Y90000D01*
X-1618750D01*
G01X-1621550Y82750D02*
X-1625750D01*
G01X-1611725Y77000D02*
X-1610325Y75750D01*
X-1608750Y75000D01*
X-1607350D01*
X-1605950Y75750D01*
X-1604900Y77000D01*
X-1604375Y78750D01*
X-1604725Y80500D01*
X-1605600Y82000D01*
X-1607175Y83000D01*
X-1609275Y83500D01*
X-1610500Y84500D01*
X-1611025Y86250D01*
X-1610675Y88000D01*
X-1609800Y89250D01*
X-1608575Y90000D01*
X-1607350D01*
X-1606125Y89500D01*
X-1605075Y88250D01*
G01X-1597350Y75000D02*
Y90000D01*
X-1593150D01*
X-1591750Y89250D01*
X-1590700Y87500D01*
X-1590350Y85500D01*
X-1590700Y83500D01*
X-1591575Y82000D01*
X-1593150Y81250D01*
X-1597350D01*
G01X-1576150Y75000D02*
X-1583150D01*
Y90000D01*
X-1576150D01*
G01X-1578950Y82750D02*
X-1583150D01*
G01X-1561600Y88750D02*
X-1562650Y89500D01*
X-1563875Y90000D01*
X-1565275D01*
X-1566850Y89250D01*
X-1568075Y88000D01*
X-1568950Y86500D01*
X-1569650Y84000D01*
X-1569825Y81750D01*
X-1569475Y79500D01*
X-1568950Y78000D01*
X-1567900Y76500D01*
X-1566675Y75500D01*
X-1565450Y75000D01*
X-1564225D01*
X-1563000Y75500D01*
X-1561950Y76250D01*
X-1561075Y77250D01*
G01X-1551250Y90000D02*
Y75000D01*
G01X-1555275Y90000D02*
X-1547225D01*
G01X-1522850D02*
Y75000D01*
G01X-1526875Y90000D02*
X-1518825D01*
G01X-1508650Y75000D02*
X-1510050Y75250D01*
X-1511275Y76250D01*
X-1512325Y77750D01*
X-1513025Y79500D01*
X-1513375Y81500D01*
Y83500D01*
X-1513025Y85500D01*
X-1512325Y87250D01*
X-1511275Y88750D01*
X-1510050Y89750D01*
X-1508650Y90000D01*
X-1507250Y89750D01*
X-1506025Y88750D01*
X-1504975Y87250D01*
X-1504275Y85500D01*
X-1503925Y83500D01*
Y81500D01*
X-1504275Y79500D01*
X-1504975Y77750D01*
X-1506025Y76250D01*
X-1507250Y75250D01*
X-1508650Y75000D01*
G01X-1484100D02*
Y90000D01*
X-1480600D01*
X-1479200Y89250D01*
X-1478150Y88250D01*
X-1477275Y86750D01*
X-1476575Y85000D01*
X-1476400Y82500D01*
X-1476575Y80000D01*
X-1477275Y78250D01*
X-1478150Y76750D01*
X-1479200Y75750D01*
X-1480600Y75000D01*
X-1484100D01*
G01X-1470425D02*
X-1466050Y90000D01*
X-1461675Y75000D01*
G01X-1463250Y80250D02*
X-1468850D01*
G01X-1451850Y90000D02*
Y75000D01*
G01X-1455875Y90000D02*
X-1447825D01*
G01X-1441500D02*
Y79250D01*
X-1440800Y77000D01*
X-1439400Y75500D01*
X-1437650Y75000D01*
X-1435900Y75500D01*
X-1434500Y77000D01*
X-1433800Y79250D01*
Y90000D01*
G01X-1428000Y75000D02*
Y90000D01*
X-1423450Y77500D01*
X-1418900Y90000D01*
Y75000D01*
G01X-1409250Y74500D02*
X-1409600Y74750D01*
Y75250D01*
X-1409250Y75500D01*
X-1408900Y75250D01*
Y74750D01*
X-1409250Y74500D01*
G01X-1640475Y105000D02*
Y120000D01*
X-1632425Y105000D01*
Y120000D01*
G01X-1622250Y105000D02*
X-1623650Y105250D01*
X-1624875Y106250D01*
X-1625925Y107750D01*
X-1626625Y109500D01*
X-1626975Y111500D01*
Y113500D01*
X-1626625Y115500D01*
X-1625925Y117250D01*
X-1624875Y118750D01*
X-1623650Y119750D01*
X-1622250Y120000D01*
X-1620850Y119750D01*
X-1619625Y118750D01*
X-1618575Y117250D01*
X-1617875Y115500D01*
X-1617525Y113500D01*
Y111500D01*
X-1617875Y109500D01*
X-1618575Y107750D01*
X-1619625Y106250D01*
X-1620850Y105250D01*
X-1622250Y105000D01*
G01X-1612075D02*
Y120000D01*
X-1604025Y105000D01*
Y120000D01*
G01X-1596125Y110000D02*
X-1591575D01*
G01X-1583150Y105000D02*
Y120000D01*
X-1578950D01*
X-1577550Y119250D01*
X-1576500Y117500D01*
X-1576150Y115500D01*
X-1576500Y113500D01*
X-1577375Y112000D01*
X-1578950Y111250D01*
X-1583150D01*
G01X-1568950Y120000D02*
Y105000D01*
X-1561950D01*
G01X-1555625D02*
X-1551250Y120000D01*
X-1546875Y105000D01*
G01X-1548450Y110250D02*
X-1554050D01*
G01X-1537050Y120000D02*
Y105000D01*
G01X-1541075Y120000D02*
X-1533025D01*
G01X-1519350Y105000D02*
X-1526350D01*
Y120000D01*
X-1519350D01*
G01X-1522150Y112750D02*
X-1526350D01*
G01X-1512500Y105000D02*
Y120000D01*
X-1509000D01*
X-1507600Y119250D01*
X-1506550Y118250D01*
X-1505675Y116750D01*
X-1504975Y115000D01*
X-1504800Y112500D01*
X-1504975Y110000D01*
X-1505675Y108250D01*
X-1506550Y106750D01*
X-1507600Y105750D01*
X-1509000Y105000D01*
X-1512500D01*
G01X-1483925D02*
Y120000D01*
G01X-1476575D02*
Y105000D01*
G01Y112500D02*
X-1483925D01*
G01X-1466050Y105000D02*
X-1467450Y105250D01*
X-1468675Y106250D01*
X-1469725Y107750D01*
X-1470425Y109500D01*
X-1470775Y111500D01*
Y113500D01*
X-1470425Y115500D01*
X-1469725Y117250D01*
X-1468675Y118750D01*
X-1467450Y119750D01*
X-1466050Y120000D01*
X-1464650Y119750D01*
X-1463425Y118750D01*
X-1462375Y117250D01*
X-1461675Y115500D01*
X-1461325Y113500D01*
Y111500D01*
X-1461675Y109500D01*
X-1462375Y107750D01*
X-1463425Y106250D01*
X-1464650Y105250D01*
X-1466050Y105000D01*
G01X-1455350Y120000D02*
Y105000D01*
X-1448350D01*
G01X-1434150D02*
X-1441150D01*
Y120000D01*
X-1434150D01*
G01X-1436950Y112750D02*
X-1441150D01*
G01X-1427125Y107000D02*
X-1425725Y105750D01*
X-1424150Y105000D01*
X-1422750D01*
X-1421350Y105750D01*
X-1420300Y107000D01*
X-1419775Y108750D01*
X-1420125Y110500D01*
X-1421000Y112000D01*
X-1422575Y113000D01*
X-1424675Y113500D01*
X-1425900Y114500D01*
X-1426425Y116250D01*
X-1426075Y118000D01*
X-1425200Y119250D01*
X-1423975Y120000D01*
X-1422750D01*
X-1421525Y119500D01*
X-1420475Y118250D01*
G01X-1398550Y105000D02*
X-1391550Y110000D01*
X-1398550Y115000D01*
G01X-1380850Y104500D02*
X-1381200Y104750D01*
Y105250D01*
X-1380850Y105500D01*
X-1380500Y105250D01*
Y104750D01*
X-1380850Y104500D01*
G01X-1369975Y117500D02*
X-1368925Y119000D01*
X-1367700Y119750D01*
X-1366300Y120000D01*
X-1364550Y119500D01*
X-1363325Y118250D01*
X-1362975Y116750D01*
X-1363150Y115250D01*
X-1363850Y114000D01*
X-1367350Y111500D01*
X-1368925Y109750D01*
X-1369975Y107250D01*
X-1370325Y105000D01*
X-1362975D01*
G01X-1352450Y120000D02*
X-1353850Y119500D01*
X-1354900Y118250D01*
X-1355600Y116750D01*
X-1356125Y114750D01*
X-1356300Y112500D01*
X-1356125Y110250D01*
X-1355600Y108250D01*
X-1354900Y106750D01*
X-1353850Y105500D01*
X-1352450Y105000D01*
X-1351050Y105500D01*
X-1350000Y106750D01*
X-1349300Y108250D01*
X-1348775Y110250D01*
X-1348600Y112500D01*
X-1348775Y114750D01*
X-1349300Y116750D01*
X-1350000Y118250D01*
X-1351050Y119500D01*
X-1352450Y120000D01*
G01X-1338250D02*
X-1339650Y119500D01*
X-1340700Y118250D01*
X-1341400Y116750D01*
X-1341925Y114750D01*
X-1342100Y112500D01*
X-1341925Y110250D01*
X-1341400Y108250D01*
X-1340700Y106750D01*
X-1339650Y105500D01*
X-1338250Y105000D01*
X-1336850Y105500D01*
X-1335800Y106750D01*
X-1335100Y108250D01*
X-1334575Y110250D01*
X-1334400Y112500D01*
X-1334575Y114750D01*
X-1335100Y116750D01*
X-1335800Y118250D01*
X-1336850Y119500D01*
X-1338250Y120000D01*
G01X-1313525Y107000D02*
X-1312125Y105750D01*
X-1310550Y105000D01*
X-1309150D01*
X-1307750Y105750D01*
X-1306700Y107000D01*
X-1306175Y108750D01*
X-1306525Y110500D01*
X-1307400Y112000D01*
X-1308975Y113000D01*
X-1311075Y113500D01*
X-1312300Y114500D01*
X-1312825Y116250D01*
X-1312475Y118000D01*
X-1311600Y119250D01*
X-1310375Y120000D01*
X-1309150D01*
X-1307925Y119500D01*
X-1306875Y118250D01*
G01X-1299325Y105000D02*
Y120000D01*
G01X-1291975D02*
Y105000D01*
G01Y112500D02*
X-1299325D01*
G01X-1285825Y105000D02*
X-1281450Y120000D01*
X-1277075Y105000D01*
G01X-1278650Y110250D02*
X-1284250D01*
G01X-1270750Y120000D02*
Y105000D01*
X-1263750D01*
G01X-1256550Y120000D02*
Y105000D01*
X-1249550D01*
G01X-1223250Y113000D02*
X-1222550Y113750D01*
X-1222025Y115000D01*
X-1221675Y116750D01*
X-1222025Y118250D01*
X-1222725Y119250D01*
X-1223950Y120000D01*
X-1228675D01*
Y105000D01*
X-1222900D01*
X-1221675Y106000D01*
X-1220975Y107500D01*
X-1220625Y109250D01*
X-1220975Y111000D01*
X-1222025Y112500D01*
X-1223250Y113000D01*
X-1228675D01*
G01X-1206950Y105000D02*
X-1213950D01*
Y120000D01*
X-1206950D01*
G01X-1209750Y112750D02*
X-1213950D01*
G01X-1187300Y120000D02*
X-1184850Y105000D01*
X-1182050Y120000D01*
X-1179250Y105000D01*
X-1176800Y120000D01*
G01X-1169950D02*
X-1165750D01*
G01X-1167850D02*
Y105000D01*
G01X-1169950D02*
X-1165750D01*
G01X-1153650Y120000D02*
Y105000D01*
G01X-1157675Y120000D02*
X-1149625D01*
G01X-1143125Y105000D02*
Y120000D01*
G01X-1135775D02*
Y105000D01*
G01Y112500D02*
X-1143125D01*
G01X-1127350Y120000D02*
X-1123150D01*
G01X-1125250D02*
Y105000D01*
G01X-1127350D02*
X-1123150D01*
G01X-1115075D02*
Y120000D01*
X-1107025Y105000D01*
Y120000D01*
G01X-1082650Y104500D02*
X-1083000Y104750D01*
Y105250D01*
X-1082650Y105500D01*
X-1082300Y105250D01*
Y104750D01*
X-1082650Y104500D01*
G01X-1068450Y120000D02*
X-1069850Y119500D01*
X-1070900Y118250D01*
X-1071600Y116750D01*
X-1072125Y114750D01*
X-1072300Y112500D01*
X-1072125Y110250D01*
X-1071600Y108250D01*
X-1070900Y106750D01*
X-1069850Y105500D01*
X-1068450Y105000D01*
X-1067050Y105500D01*
X-1066000Y106750D01*
X-1065300Y108250D01*
X-1064775Y110250D01*
X-1064600Y112500D01*
X-1064775Y114750D01*
X-1065300Y116750D01*
X-1066000Y118250D01*
X-1067050Y119500D01*
X-1068450Y120000D01*
G01X-1054250Y105000D02*
Y120000D01*
X-1056350Y117000D01*
G01Y105000D02*
X-1052150D01*
G01X-1037950D02*
Y120000D01*
X-1044425Y109250D01*
X-1035675D01*
G01X-1027425Y116750D02*
X-1026550Y120000D01*
G01X-1024275D02*
X-1025150Y116750D01*
G01X-1001300Y105000D02*
Y120000D01*
X-997800D01*
X-996400Y119250D01*
X-995350Y118250D01*
X-994475Y116750D01*
X-993775Y115000D01*
X-993600Y112500D01*
X-993775Y110000D01*
X-994475Y108250D01*
X-995350Y106750D01*
X-996400Y105750D01*
X-997800Y105000D01*
X-1001300D01*
G01X-985350Y120000D02*
X-981150D01*
G01X-983250D02*
Y105000D01*
G01X-985350D02*
X-981150D01*
G01X-973425D02*
X-969050Y120000D01*
X-964675Y105000D01*
G01X-966250Y110250D02*
X-971850D01*
G01X-959400Y105000D02*
Y120000D01*
X-954850Y107500D01*
X-950300Y120000D01*
Y105000D01*
G01X-937150D02*
X-944150D01*
Y120000D01*
X-937150D01*
G01X-939950Y112750D02*
X-944150D01*
G01X-926450Y120000D02*
Y105000D01*
G01X-930475Y120000D02*
X-922425D01*
G01X-908750Y105000D02*
X-915750D01*
Y120000D01*
X-908750D01*
G01X-911550Y112750D02*
X-915750D01*
G01X-901550Y105000D02*
Y120000D01*
X-897175D01*
X-895775Y119250D01*
X-894900Y118250D01*
X-894550Y116250D01*
X-894900Y114250D01*
X-895950Y113000D01*
X-897175Y112250D01*
X-901550D01*
G01X-897175D02*
X-894550Y105000D01*
G01X-869650Y120000D02*
Y105000D01*
G01X-873675Y120000D02*
X-865625D01*
G01X-858950Y105000D02*
Y120000D01*
X-854575D01*
X-853175Y119250D01*
X-852300Y118250D01*
X-851950Y116250D01*
X-852300Y114250D01*
X-853350Y113000D01*
X-854575Y112250D01*
X-858950D01*
G01X-854575D02*
X-851950Y105000D01*
G01X-845100Y120000D02*
Y109250D01*
X-844400Y107000D01*
X-843000Y105500D01*
X-841250Y105000D01*
X-839500Y105500D01*
X-838100Y107000D01*
X-837400Y109250D01*
Y120000D01*
G01X-823550Y105000D02*
X-830550D01*
Y120000D01*
X-823550D01*
G01X-826350Y112750D02*
X-830550D01*
G01X-802150Y105000D02*
Y120000D01*
X-797950D01*
X-796550Y119250D01*
X-795500Y117500D01*
X-795150Y115500D01*
X-795500Y113500D01*
X-796375Y112000D01*
X-797950Y111250D01*
X-802150D01*
G01X-784450Y105000D02*
X-785850Y105250D01*
X-787075Y106250D01*
X-788125Y107750D01*
X-788825Y109500D01*
X-789175Y111500D01*
Y113500D01*
X-788825Y115500D01*
X-788125Y117250D01*
X-787075Y118750D01*
X-785850Y119750D01*
X-784450Y120000D01*
X-783050Y119750D01*
X-781825Y118750D01*
X-780775Y117250D01*
X-780075Y115500D01*
X-779725Y113500D01*
Y111500D01*
X-780075Y109500D01*
X-780775Y107750D01*
X-781825Y106250D01*
X-783050Y105250D01*
X-784450Y105000D01*
G01X-773925Y107000D02*
X-772525Y105750D01*
X-770950Y105000D01*
X-769550D01*
X-768150Y105750D01*
X-767100Y107000D01*
X-766575Y108750D01*
X-766925Y110500D01*
X-767800Y112000D01*
X-769375Y113000D01*
X-771475Y113500D01*
X-772700Y114500D01*
X-773225Y116250D01*
X-772875Y118000D01*
X-772000Y119250D01*
X-770775Y120000D01*
X-769550D01*
X-768325Y119500D01*
X-767275Y118250D01*
G01X-758150Y120000D02*
X-753950D01*
G01X-756050D02*
Y105000D01*
G01X-758150D02*
X-753950D01*
G01X-741850Y120000D02*
Y105000D01*
G01X-745875Y120000D02*
X-737825D01*
G01X-729750D02*
X-725550D01*
G01X-727650D02*
Y105000D01*
G01X-729750D02*
X-725550D01*
G01X-713450D02*
X-714850Y105250D01*
X-716075Y106250D01*
X-717125Y107750D01*
X-717825Y109500D01*
X-718175Y111500D01*
Y113500D01*
X-717825Y115500D01*
X-717125Y117250D01*
X-716075Y118750D01*
X-714850Y119750D01*
X-713450Y120000D01*
X-712050Y119750D01*
X-710825Y118750D01*
X-709775Y117250D01*
X-709075Y115500D01*
X-708725Y113500D01*
Y111500D01*
X-709075Y109500D01*
X-709775Y107750D01*
X-710825Y106250D01*
X-712050Y105250D01*
X-713450Y105000D01*
G01X-703275D02*
Y120000D01*
X-695225Y105000D01*
Y120000D01*
G01X-676100D02*
X-673650Y105000D01*
X-670850Y120000D01*
X-668050Y105000D01*
X-665600Y120000D01*
G01X-658750D02*
X-654550D01*
G01X-656650D02*
Y105000D01*
G01X-658750D02*
X-654550D01*
G01X-642450Y120000D02*
Y105000D01*
G01X-646475Y120000D02*
X-638425D01*
G01X-631925Y105000D02*
Y120000D01*
G01X-624575D02*
Y105000D01*
G01Y112500D02*
X-631925D01*
G01X-1640125Y137000D02*
X-1638725Y135750D01*
X-1637150Y135000D01*
X-1635750D01*
X-1634350Y135750D01*
X-1633300Y137000D01*
X-1632775Y138750D01*
X-1633125Y140500D01*
X-1634000Y142000D01*
X-1635575Y143000D01*
X-1637675Y143500D01*
X-1638900Y144500D01*
X-1639425Y146250D01*
X-1639075Y148000D01*
X-1638200Y149250D01*
X-1636975Y150000D01*
X-1635750D01*
X-1634525Y149500D01*
X-1633475Y148250D01*
G01X-1625925Y135000D02*
Y150000D01*
G01X-1618575D02*
Y135000D01*
G01Y142500D02*
X-1625925D01*
G01X-1612425Y135000D02*
X-1608050Y150000D01*
X-1603675Y135000D01*
G01X-1605250Y140250D02*
X-1610850D01*
G01X-1597350Y150000D02*
Y135000D01*
X-1590350D01*
G01X-1583150Y150000D02*
Y135000D01*
X-1576150D01*
G01X-1549850Y143000D02*
X-1549150Y143750D01*
X-1548625Y145000D01*
X-1548275Y146750D01*
X-1548625Y148250D01*
X-1549325Y149250D01*
X-1550550Y150000D01*
X-1555275D01*
Y135000D01*
X-1549500D01*
X-1548275Y136000D01*
X-1547575Y137500D01*
X-1547225Y139250D01*
X-1547575Y141000D01*
X-1548625Y142500D01*
X-1549850Y143000D01*
X-1555275D01*
G01X-1533550Y135000D02*
X-1540550D01*
Y150000D01*
X-1533550D01*
G01X-1536350Y142750D02*
X-1540550D01*
G01X-1513900Y150000D02*
X-1511450Y135000D01*
X-1508650Y150000D01*
X-1505850Y135000D01*
X-1503400Y150000D01*
G01X-1496550D02*
X-1492350D01*
G01X-1494450D02*
Y135000D01*
G01X-1496550D02*
X-1492350D01*
G01X-1480250Y150000D02*
Y135000D01*
G01X-1484275Y150000D02*
X-1476225D01*
G01X-1469725Y135000D02*
Y150000D01*
G01X-1462375D02*
Y135000D01*
G01Y142500D02*
X-1469725D01*
G01X-1453950Y150000D02*
X-1449750D01*
G01X-1451850D02*
Y135000D01*
G01X-1453950D02*
X-1449750D01*
G01X-1441675D02*
Y150000D01*
X-1433625Y135000D01*
Y150000D01*
G01X-1409250Y134500D02*
X-1409600Y134750D01*
Y135250D01*
X-1409250Y135500D01*
X-1408900Y135250D01*
Y134750D01*
X-1409250Y134500D01*
G01X-1395050Y150000D02*
X-1396450Y149500D01*
X-1397500Y148250D01*
X-1398200Y146750D01*
X-1398725Y144750D01*
X-1398900Y142500D01*
X-1398725Y140250D01*
X-1398200Y138250D01*
X-1397500Y136750D01*
X-1396450Y135500D01*
X-1395050Y135000D01*
X-1393650Y135500D01*
X-1392600Y136750D01*
X-1391900Y138250D01*
X-1391375Y140250D01*
X-1391200Y142500D01*
X-1391375Y144750D01*
X-1391900Y146750D01*
X-1392600Y148250D01*
X-1393650Y149500D01*
X-1395050Y150000D01*
G01X-1380850D02*
X-1382250Y149500D01*
X-1383300Y148250D01*
X-1384000Y146750D01*
X-1384525Y144750D01*
X-1384700Y142500D01*
X-1384525Y140250D01*
X-1384000Y138250D01*
X-1383300Y136750D01*
X-1382250Y135500D01*
X-1380850Y135000D01*
X-1379450Y135500D01*
X-1378400Y136750D01*
X-1377700Y138250D01*
X-1377175Y140250D01*
X-1377000Y142500D01*
X-1377175Y144750D01*
X-1377700Y146750D01*
X-1378400Y148250D01*
X-1379450Y149500D01*
X-1380850Y150000D01*
G01X-1366650Y135000D02*
X-1365425Y135250D01*
X-1364025Y136000D01*
X-1363150Y137250D01*
X-1362800Y139000D01*
X-1363150Y140750D01*
X-1364200Y142250D01*
X-1365775Y143000D01*
X-1367525D01*
X-1368575Y143500D01*
X-1369450Y144750D01*
X-1369800Y146500D01*
X-1369275Y148250D01*
X-1368050Y149500D01*
X-1366650Y150000D01*
X-1365250Y149500D01*
X-1364025Y148250D01*
X-1363500Y146500D01*
X-1363850Y144750D01*
X-1364725Y143500D01*
X-1365775Y143000D01*
X-1367525D01*
X-1369100Y142250D01*
X-1370150Y140750D01*
X-1370500Y139000D01*
X-1370150Y137250D01*
X-1369275Y136000D01*
X-1367875Y135250D01*
X-1366650Y135000D01*
G01X-1354025Y146750D02*
X-1353150Y150000D01*
G01X-1350875D02*
X-1351750Y146750D01*
G01X-1327900Y135000D02*
Y150000D01*
X-1324400D01*
X-1323000Y149250D01*
X-1321950Y148250D01*
X-1321075Y146750D01*
X-1320375Y145000D01*
X-1320200Y142500D01*
X-1320375Y140000D01*
X-1321075Y138250D01*
X-1321950Y136750D01*
X-1323000Y135750D01*
X-1324400Y135000D01*
X-1327900D01*
G01X-1311950Y150000D02*
X-1307750D01*
G01X-1309850D02*
Y135000D01*
G01X-1311950D02*
X-1307750D01*
G01X-1300025D02*
X-1295650Y150000D01*
X-1291275Y135000D01*
G01X-1292850Y140250D02*
X-1298450D01*
G01X-1286000Y135000D02*
Y150000D01*
X-1281450Y137500D01*
X-1276900Y150000D01*
Y135000D01*
G01X-1263750D02*
X-1270750D01*
Y150000D01*
X-1263750D01*
G01X-1266550Y142750D02*
X-1270750D01*
G01X-1253050Y150000D02*
Y135000D01*
G01X-1257075Y150000D02*
X-1249025D01*
G01X-1235350Y135000D02*
X-1242350D01*
Y150000D01*
X-1235350D01*
G01X-1238150Y142750D02*
X-1242350D01*
G01X-1228150Y135000D02*
Y150000D01*
X-1223775D01*
X-1222375Y149250D01*
X-1221500Y148250D01*
X-1221150Y146250D01*
X-1221500Y144250D01*
X-1222550Y143000D01*
X-1223775Y142250D01*
X-1228150D01*
G01X-1223775D02*
X-1221150Y135000D01*
G01X-1196250Y150000D02*
Y135000D01*
G01X-1200275Y150000D02*
X-1192225D01*
G01X-1185550Y135000D02*
Y150000D01*
X-1181175D01*
X-1179775Y149250D01*
X-1178900Y148250D01*
X-1178550Y146250D01*
X-1178900Y144250D01*
X-1179950Y143000D01*
X-1181175Y142250D01*
X-1185550D01*
G01X-1181175D02*
X-1178550Y135000D01*
G01X-1171700Y150000D02*
Y139250D01*
X-1171000Y137000D01*
X-1169600Y135500D01*
X-1167850Y135000D01*
X-1166100Y135500D01*
X-1164700Y137000D01*
X-1164000Y139250D01*
Y150000D01*
G01X-1150150Y135000D02*
X-1157150D01*
Y150000D01*
X-1150150D01*
G01X-1152950Y142750D02*
X-1157150D01*
G01X-1128750Y135000D02*
Y150000D01*
X-1124550D01*
X-1123150Y149250D01*
X-1122100Y147500D01*
X-1121750Y145500D01*
X-1122100Y143500D01*
X-1122975Y142000D01*
X-1124550Y141250D01*
X-1128750D01*
G01X-1111050Y135000D02*
X-1112450Y135250D01*
X-1113675Y136250D01*
X-1114725Y137750D01*
X-1115425Y139500D01*
X-1115775Y141500D01*
Y143500D01*
X-1115425Y145500D01*
X-1114725Y147250D01*
X-1113675Y148750D01*
X-1112450Y149750D01*
X-1111050Y150000D01*
X-1109650Y149750D01*
X-1108425Y148750D01*
X-1107375Y147250D01*
X-1106675Y145500D01*
X-1106325Y143500D01*
Y141500D01*
X-1106675Y139500D01*
X-1107375Y137750D01*
X-1108425Y136250D01*
X-1109650Y135250D01*
X-1111050Y135000D01*
G01X-1100525Y137000D02*
X-1099125Y135750D01*
X-1097550Y135000D01*
X-1096150D01*
X-1094750Y135750D01*
X-1093700Y137000D01*
X-1093175Y138750D01*
X-1093525Y140500D01*
X-1094400Y142000D01*
X-1095975Y143000D01*
X-1098075Y143500D01*
X-1099300Y144500D01*
X-1099825Y146250D01*
X-1099475Y148000D01*
X-1098600Y149250D01*
X-1097375Y150000D01*
X-1096150D01*
X-1094925Y149500D01*
X-1093875Y148250D01*
G01X-1084750Y150000D02*
X-1080550D01*
G01X-1082650D02*
Y135000D01*
G01X-1084750D02*
X-1080550D01*
G01X-1068450Y150000D02*
Y135000D01*
G01X-1072475Y150000D02*
X-1064425D01*
G01X-1056350D02*
X-1052150D01*
G01X-1054250D02*
Y135000D01*
G01X-1056350D02*
X-1052150D01*
G01X-1040050D02*
X-1041450Y135250D01*
X-1042675Y136250D01*
X-1043725Y137750D01*
X-1044425Y139500D01*
X-1044775Y141500D01*
Y143500D01*
X-1044425Y145500D01*
X-1043725Y147250D01*
X-1042675Y148750D01*
X-1041450Y149750D01*
X-1040050Y150000D01*
X-1038650Y149750D01*
X-1037425Y148750D01*
X-1036375Y147250D01*
X-1035675Y145500D01*
X-1035325Y143500D01*
Y141500D01*
X-1035675Y139500D01*
X-1036375Y137750D01*
X-1037425Y136250D01*
X-1038650Y135250D01*
X-1040050Y135000D01*
G01X-1029875D02*
Y150000D01*
X-1021825Y135000D01*
Y150000D01*
G01X-1002700D02*
X-1000250Y135000D01*
X-997450Y150000D01*
X-994650Y135000D01*
X-992200Y150000D01*
G01X-985350D02*
X-981150D01*
G01X-983250D02*
Y135000D01*
G01X-985350D02*
X-981150D01*
G01X-969050Y150000D02*
Y135000D01*
G01X-973075Y150000D02*
X-965025D01*
G01X-958525Y135000D02*
Y150000D01*
G01X-951175D02*
Y135000D01*
G01Y142500D02*
X-958525D01*
G01X-929950Y135000D02*
Y150000D01*
X-925575D01*
X-924175Y149250D01*
X-923300Y148250D01*
X-922950Y146250D01*
X-923300Y144250D01*
X-924350Y143000D01*
X-925575Y142250D01*
X-929950D01*
G01X-925575D02*
X-922950Y135000D01*
G01X-908750D02*
X-915750D01*
Y150000D01*
X-908750D01*
G01X-911550Y142750D02*
X-915750D01*
G01X-901725Y137000D02*
X-900325Y135750D01*
X-898750Y135000D01*
X-897350D01*
X-895950Y135750D01*
X-894900Y137000D01*
X-894375Y138750D01*
X-894725Y140500D01*
X-895600Y142000D01*
X-897175Y143000D01*
X-899275Y143500D01*
X-900500Y144500D01*
X-901025Y146250D01*
X-900675Y148000D01*
X-899800Y149250D01*
X-898575Y150000D01*
X-897350D01*
X-896125Y149500D01*
X-895075Y148250D01*
G01X-887350Y135000D02*
Y150000D01*
X-883150D01*
X-881750Y149250D01*
X-880700Y147500D01*
X-880350Y145500D01*
X-880700Y143500D01*
X-881575Y142000D01*
X-883150Y141250D01*
X-887350D01*
G01X-866150Y135000D02*
X-873150D01*
Y150000D01*
X-866150D01*
G01X-868950Y142750D02*
X-873150D01*
G01X-851600Y148750D02*
X-852650Y149500D01*
X-853875Y150000D01*
X-855275D01*
X-856850Y149250D01*
X-858075Y148000D01*
X-858950Y146500D01*
X-859650Y144000D01*
X-859825Y141750D01*
X-859475Y139500D01*
X-858950Y138000D01*
X-857900Y136500D01*
X-856675Y135500D01*
X-855450Y135000D01*
X-854225D01*
X-853000Y135500D01*
X-851950Y136250D01*
X-851075Y137250D01*
G01X-841250Y150000D02*
Y135000D01*
G01X-845275Y150000D02*
X-837225D01*
G01X-812850D02*
Y135000D01*
G01X-816875Y150000D02*
X-808825D01*
G01X-798650Y135000D02*
X-800050Y135250D01*
X-801275Y136250D01*
X-802325Y137750D01*
X-803025Y139500D01*
X-803375Y141500D01*
Y143500D01*
X-803025Y145500D01*
X-802325Y147250D01*
X-801275Y148750D01*
X-800050Y149750D01*
X-798650Y150000D01*
X-797250Y149750D01*
X-796025Y148750D01*
X-794975Y147250D01*
X-794275Y145500D01*
X-793925Y143500D01*
Y141500D01*
X-794275Y139500D01*
X-794975Y137750D01*
X-796025Y136250D01*
X-797250Y135250D01*
X-798650Y135000D01*
G01X-770250Y150000D02*
X-771650Y149500D01*
X-772700Y148250D01*
X-773400Y146750D01*
X-773925Y144750D01*
X-774100Y142500D01*
X-773925Y140250D01*
X-773400Y138250D01*
X-772700Y136750D01*
X-771650Y135500D01*
X-770250Y135000D01*
X-768850Y135500D01*
X-767800Y136750D01*
X-767100Y138250D01*
X-766575Y140250D01*
X-766400Y142500D01*
X-766575Y144750D01*
X-767100Y146750D01*
X-767800Y148250D01*
X-768850Y149500D01*
X-770250Y150000D01*
G01X-756400Y132250D02*
X-755700Y135500D01*
G01X-741850Y150000D02*
X-743250Y149500D01*
X-744300Y148250D01*
X-745000Y146750D01*
X-745525Y144750D01*
X-745700Y142500D01*
X-745525Y140250D01*
X-745000Y138250D01*
X-744300Y136750D01*
X-743250Y135500D01*
X-741850Y135000D01*
X-740450Y135500D01*
X-739400Y136750D01*
X-738700Y138250D01*
X-738175Y140250D01*
X-738000Y142500D01*
X-738175Y144750D01*
X-738700Y146750D01*
X-739400Y148250D01*
X-740450Y149500D01*
X-741850Y150000D01*
G01X-717300Y135000D02*
Y150000D01*
X-713800D01*
X-712400Y149250D01*
X-711350Y148250D01*
X-710475Y146750D01*
X-709775Y145000D01*
X-709600Y142500D01*
X-709775Y140000D01*
X-710475Y138250D01*
X-711350Y136750D01*
X-712400Y135750D01*
X-713800Y135000D01*
X-717300D01*
G01X-703625D02*
X-699250Y150000D01*
X-694875Y135000D01*
G01X-696450Y140250D02*
X-702050D01*
G01X-685050Y150000D02*
Y135000D01*
G01X-689075Y150000D02*
X-681025D01*
G01X-674700D02*
Y139250D01*
X-674000Y137000D01*
X-672600Y135500D01*
X-670850Y135000D01*
X-669100Y135500D01*
X-667700Y137000D01*
X-667000Y139250D01*
Y150000D01*
G01X-661200Y135000D02*
Y150000D01*
X-656650Y137500D01*
X-652100Y150000D01*
Y135000D01*
G01X-642450Y134500D02*
X-642800Y134750D01*
Y135250D01*
X-642450Y135500D01*
X-642100Y135250D01*
Y134750D01*
X-642450Y134500D01*
G01X-1636450Y180000D02*
Y165000D01*
G01X-1640475Y180000D02*
X-1632425D01*
G01X-1625750Y165000D02*
Y180000D01*
X-1621375D01*
X-1619975Y179250D01*
X-1619100Y178250D01*
X-1618750Y176250D01*
X-1619100Y174250D01*
X-1620150Y173000D01*
X-1621375Y172250D01*
X-1625750D01*
G01X-1621375D02*
X-1618750Y165000D01*
G01X-1611900Y180000D02*
Y169250D01*
X-1611200Y167000D01*
X-1609800Y165500D01*
X-1608050Y165000D01*
X-1606300Y165500D01*
X-1604900Y167000D01*
X-1604200Y169250D01*
Y180000D01*
G01X-1590350Y165000D02*
X-1597350D01*
Y180000D01*
X-1590350D01*
G01X-1593150Y172750D02*
X-1597350D01*
G01X-1568950Y165000D02*
Y180000D01*
X-1564750D01*
X-1563350Y179250D01*
X-1562300Y177500D01*
X-1561950Y175500D01*
X-1562300Y173500D01*
X-1563175Y172000D01*
X-1564750Y171250D01*
X-1568950D01*
G01X-1551250Y165000D02*
X-1552650Y165250D01*
X-1553875Y166250D01*
X-1554925Y167750D01*
X-1555625Y169500D01*
X-1555975Y171500D01*
Y173500D01*
X-1555625Y175500D01*
X-1554925Y177250D01*
X-1553875Y178750D01*
X-1552650Y179750D01*
X-1551250Y180000D01*
X-1549850Y179750D01*
X-1548625Y178750D01*
X-1547575Y177250D01*
X-1546875Y175500D01*
X-1546525Y173500D01*
Y171500D01*
X-1546875Y169500D01*
X-1547575Y167750D01*
X-1548625Y166250D01*
X-1549850Y165250D01*
X-1551250Y165000D01*
G01X-1540725Y167000D02*
X-1539325Y165750D01*
X-1537750Y165000D01*
X-1536350D01*
X-1534950Y165750D01*
X-1533900Y167000D01*
X-1533375Y168750D01*
X-1533725Y170500D01*
X-1534600Y172000D01*
X-1536175Y173000D01*
X-1538275Y173500D01*
X-1539500Y174500D01*
X-1540025Y176250D01*
X-1539675Y178000D01*
X-1538800Y179250D01*
X-1537575Y180000D01*
X-1536350D01*
X-1535125Y179500D01*
X-1534075Y178250D01*
G01X-1524950Y180000D02*
X-1520750D01*
G01X-1522850D02*
Y165000D01*
G01X-1524950D02*
X-1520750D01*
G01X-1508650Y180000D02*
Y165000D01*
G01X-1512675Y180000D02*
X-1504625D01*
G01X-1496550D02*
X-1492350D01*
G01X-1494450D02*
Y165000D01*
G01X-1496550D02*
X-1492350D01*
G01X-1480250D02*
X-1481650Y165250D01*
X-1482875Y166250D01*
X-1483925Y167750D01*
X-1484625Y169500D01*
X-1484975Y171500D01*
Y173500D01*
X-1484625Y175500D01*
X-1483925Y177250D01*
X-1482875Y178750D01*
X-1481650Y179750D01*
X-1480250Y180000D01*
X-1478850Y179750D01*
X-1477625Y178750D01*
X-1476575Y177250D01*
X-1475875Y175500D01*
X-1475525Y173500D01*
Y171500D01*
X-1475875Y169500D01*
X-1476575Y167750D01*
X-1477625Y166250D01*
X-1478850Y165250D01*
X-1480250Y165000D01*
G01X-1470075D02*
Y180000D01*
X-1462025Y165000D01*
Y180000D01*
G01X-1442025Y165000D02*
X-1437650Y180000D01*
X-1433275Y165000D01*
G01X-1434850Y170250D02*
X-1440450D01*
G01X-1423450Y180000D02*
Y165000D01*
G01X-1427475Y180000D02*
X-1419425D01*
G01X-1399600Y165000D02*
Y180000D01*
X-1395050Y167500D01*
X-1390500Y180000D01*
Y165000D01*
G01X-1385225D02*
X-1380850Y180000D01*
X-1376475Y165000D01*
G01X-1378050Y170250D02*
X-1383650D01*
G01X-1370325Y165000D02*
X-1362975Y180000D01*
G01X-1370325D02*
X-1362975Y165000D01*
G01X-1354550Y180000D02*
X-1350350D01*
G01X-1352450D02*
Y165000D01*
G01X-1354550D02*
X-1350350D01*
G01X-1342800D02*
Y180000D01*
X-1338250Y167500D01*
X-1333700Y180000D01*
Y165000D01*
G01X-1327900Y180000D02*
Y169250D01*
X-1327200Y167000D01*
X-1325800Y165500D01*
X-1324050Y165000D01*
X-1322300Y165500D01*
X-1320900Y167000D01*
X-1320200Y169250D01*
Y180000D01*
G01X-1314400Y165000D02*
Y180000D01*
X-1309850Y167500D01*
X-1305300Y180000D01*
Y165000D01*
G01X-1286000D02*
Y180000D01*
X-1281450Y167500D01*
X-1276900Y180000D01*
Y165000D01*
G01X-1271625D02*
X-1267250Y180000D01*
X-1262875Y165000D01*
G01X-1264450Y170250D02*
X-1270050D01*
G01X-1253050Y180000D02*
Y165000D01*
G01X-1257075Y180000D02*
X-1249025D01*
G01X-1235350Y165000D02*
X-1242350D01*
Y180000D01*
X-1235350D01*
G01X-1238150Y172750D02*
X-1242350D01*
G01X-1228150Y165000D02*
Y180000D01*
X-1223775D01*
X-1222375Y179250D01*
X-1221500Y178250D01*
X-1221150Y176250D01*
X-1221500Y174250D01*
X-1222550Y173000D01*
X-1223775Y172250D01*
X-1228150D01*
G01X-1223775D02*
X-1221150Y165000D01*
G01X-1212550Y180000D02*
X-1208350D01*
G01X-1210450D02*
Y165000D01*
G01X-1212550D02*
X-1208350D01*
G01X-1200625D02*
X-1196250Y180000D01*
X-1191875Y165000D01*
G01X-1193450Y170250D02*
X-1199050D01*
G01X-1185550Y180000D02*
Y165000D01*
X-1178550D01*
G01X-1149800Y178750D02*
X-1150850Y179500D01*
X-1152075Y180000D01*
X-1153475D01*
X-1155050Y179250D01*
X-1156275Y178000D01*
X-1157150Y176500D01*
X-1157850Y174000D01*
X-1158025Y171750D01*
X-1157675Y169500D01*
X-1157150Y168000D01*
X-1156100Y166500D01*
X-1154875Y165500D01*
X-1153650Y165000D01*
X-1152425D01*
X-1151200Y165500D01*
X-1150150Y166250D01*
X-1149275Y167250D01*
G01X-1139450Y165000D02*
X-1140850Y165250D01*
X-1142075Y166250D01*
X-1143125Y167750D01*
X-1143825Y169500D01*
X-1144175Y171500D01*
Y173500D01*
X-1143825Y175500D01*
X-1143125Y177250D01*
X-1142075Y178750D01*
X-1140850Y179750D01*
X-1139450Y180000D01*
X-1138050Y179750D01*
X-1136825Y178750D01*
X-1135775Y177250D01*
X-1135075Y175500D01*
X-1134725Y173500D01*
Y171500D01*
X-1135075Y169500D01*
X-1135775Y167750D01*
X-1136825Y166250D01*
X-1138050Y165250D01*
X-1139450Y165000D01*
G01X-1129275D02*
Y180000D01*
X-1121225Y165000D01*
Y180000D01*
G01X-1114900Y165000D02*
Y180000D01*
X-1111400D01*
X-1110000Y179250D01*
X-1108950Y178250D01*
X-1108075Y176750D01*
X-1107375Y175000D01*
X-1107200Y172500D01*
X-1107375Y170000D01*
X-1108075Y168250D01*
X-1108950Y166750D01*
X-1110000Y165750D01*
X-1111400Y165000D01*
X-1114900D01*
G01X-1098950Y180000D02*
X-1094750D01*
G01X-1096850D02*
Y165000D01*
G01X-1098950D02*
X-1094750D01*
G01X-1082650Y180000D02*
Y165000D01*
G01X-1086675Y180000D02*
X-1078625D01*
G01X-1070550D02*
X-1066350D01*
G01X-1068450D02*
Y165000D01*
G01X-1070550D02*
X-1066350D01*
G01X-1054250D02*
X-1055650Y165250D01*
X-1056875Y166250D01*
X-1057925Y167750D01*
X-1058625Y169500D01*
X-1058975Y171500D01*
Y173500D01*
X-1058625Y175500D01*
X-1057925Y177250D01*
X-1056875Y178750D01*
X-1055650Y179750D01*
X-1054250Y180000D01*
X-1052850Y179750D01*
X-1051625Y178750D01*
X-1050575Y177250D01*
X-1049875Y175500D01*
X-1049525Y173500D01*
Y171500D01*
X-1049875Y169500D01*
X-1050575Y167750D01*
X-1051625Y166250D01*
X-1052850Y165250D01*
X-1054250Y165000D01*
G01X-1044075D02*
Y180000D01*
X-1036025Y165000D01*
Y180000D01*
G01X-1012525Y160000D02*
X-1014275Y162500D01*
X-1015150Y165000D01*
Y175000D01*
X-1014275Y177500D01*
X-1012525Y180000D01*
G01X-1002000Y165000D02*
Y180000D01*
X-997450Y167500D01*
X-992900Y180000D01*
Y165000D01*
G01X-987800D02*
Y180000D01*
X-983250Y167500D01*
X-978700Y180000D01*
Y165000D01*
G01X-965200Y178750D02*
X-966250Y179500D01*
X-967475Y180000D01*
X-968875D01*
X-970450Y179250D01*
X-971675Y178000D01*
X-972550Y176500D01*
X-973250Y174000D01*
X-973425Y171750D01*
X-973075Y169500D01*
X-972550Y168000D01*
X-971500Y166500D01*
X-970275Y165500D01*
X-969050Y165000D01*
X-967825D01*
X-966600Y165500D01*
X-965550Y166250D01*
X-964675Y167250D01*
G01X-953975Y160000D02*
X-952225Y162500D01*
X-951350Y165000D01*
Y175000D01*
X-952225Y177500D01*
X-953975Y180000D01*
G01X-940650Y164500D02*
X-941000Y164750D01*
Y165250D01*
X-940650Y165500D01*
X-940300Y165250D01*
Y164750D01*
X-940650Y164500D01*
G01X-916275Y165000D02*
Y180000D01*
X-908225Y165000D01*
Y180000D01*
G01X-898050Y165000D02*
X-899450Y165250D01*
X-900675Y166250D01*
X-901725Y167750D01*
X-902425Y169500D01*
X-902775Y171500D01*
Y173500D01*
X-902425Y175500D01*
X-901725Y177250D01*
X-900675Y178750D01*
X-899450Y179750D01*
X-898050Y180000D01*
X-896650Y179750D01*
X-895425Y178750D01*
X-894375Y177250D01*
X-893675Y175500D01*
X-893325Y173500D01*
Y171500D01*
X-893675Y169500D01*
X-894375Y167750D01*
X-895425Y166250D01*
X-896650Y165250D01*
X-898050Y165000D01*
G01X-887875D02*
Y180000D01*
X-879825Y165000D01*
Y180000D01*
G01X-871925Y170000D02*
X-867375D01*
G01X-858950Y165000D02*
Y180000D01*
X-854750D01*
X-853350Y179250D01*
X-852300Y177500D01*
X-851950Y175500D01*
X-852300Y173500D01*
X-853175Y172000D01*
X-854750Y171250D01*
X-858950D01*
G01X-844750Y180000D02*
Y165000D01*
X-837750D01*
G01X-831425D02*
X-827050Y180000D01*
X-822675Y165000D01*
G01X-824250Y170250D02*
X-829850D01*
G01X-812850Y180000D02*
Y165000D01*
G01X-816875Y180000D02*
X-808825D01*
G01X-795150Y165000D02*
X-802150D01*
Y180000D01*
X-795150D01*
G01X-797950Y172750D02*
X-802150D01*
G01X-788300Y165000D02*
Y180000D01*
X-784800D01*
X-783400Y179250D01*
X-782350Y178250D01*
X-781475Y176750D01*
X-780775Y175000D01*
X-780600Y172500D01*
X-780775Y170000D01*
X-781475Y168250D01*
X-782350Y166750D01*
X-783400Y165750D01*
X-784800Y165000D01*
X-788300D01*
G01X-759725D02*
Y180000D01*
G01X-752375D02*
Y165000D01*
G01Y172500D02*
X-759725D01*
G01X-741850Y165000D02*
X-743250Y165250D01*
X-744475Y166250D01*
X-745525Y167750D01*
X-746225Y169500D01*
X-746575Y171500D01*
Y173500D01*
X-746225Y175500D01*
X-745525Y177250D01*
X-744475Y178750D01*
X-743250Y179750D01*
X-741850Y180000D01*
X-740450Y179750D01*
X-739225Y178750D01*
X-738175Y177250D01*
X-737475Y175500D01*
X-737125Y173500D01*
Y171500D01*
X-737475Y169500D01*
X-738175Y167750D01*
X-739225Y166250D01*
X-740450Y165250D01*
X-741850Y165000D01*
G01X-731150Y180000D02*
Y165000D01*
X-724150D01*
G01X-709950D02*
X-716950D01*
Y180000D01*
X-709950D01*
G01X-712750Y172750D02*
X-716950D01*
G01X-702925Y167000D02*
X-701525Y165750D01*
X-699950Y165000D01*
X-698550D01*
X-697150Y165750D01*
X-696100Y167000D01*
X-695575Y168750D01*
X-695925Y170500D01*
X-696800Y172000D01*
X-698375Y173000D01*
X-700475Y173500D01*
X-701700Y174500D01*
X-702225Y176250D01*
X-701875Y178000D01*
X-701000Y179250D01*
X-699775Y180000D01*
X-698550D01*
X-697325Y179500D01*
X-696275Y178250D01*
G01X-667350Y165000D02*
X-674350Y170000D01*
X-667350Y175000D01*
G01X-656650Y164500D02*
X-657000Y164750D01*
Y165250D01*
X-656650Y165500D01*
X-656300Y165250D01*
Y164750D01*
X-656650Y164500D01*
G01X-645775Y177500D02*
X-644725Y179000D01*
X-643500Y179750D01*
X-642100Y180000D01*
X-640350Y179500D01*
X-639125Y178250D01*
X-638775Y176750D01*
X-638950Y175250D01*
X-639650Y174000D01*
X-643150Y171500D01*
X-644725Y169750D01*
X-645775Y167250D01*
X-646125Y165000D01*
X-638775D01*
G01X-628250Y180000D02*
X-629650Y179500D01*
X-630700Y178250D01*
X-631400Y176750D01*
X-631925Y174750D01*
X-632100Y172500D01*
X-631925Y170250D01*
X-631400Y168250D01*
X-630700Y166750D01*
X-629650Y165500D01*
X-628250Y165000D01*
X-626850Y165500D01*
X-625800Y166750D01*
X-625100Y168250D01*
X-624575Y170250D01*
X-624400Y172500D01*
X-624575Y174750D01*
X-625100Y176750D01*
X-625800Y178250D01*
X-626850Y179500D01*
X-628250Y180000D01*
G01X-614050D02*
X-615450Y179500D01*
X-616500Y178250D01*
X-617200Y176750D01*
X-617725Y174750D01*
X-617900Y172500D01*
X-617725Y170250D01*
X-617200Y168250D01*
X-616500Y166750D01*
X-615450Y165500D01*
X-614050Y165000D01*
X-612650Y165500D01*
X-611600Y166750D01*
X-610900Y168250D01*
X-610375Y170250D01*
X-610200Y172500D01*
X-610375Y174750D01*
X-610900Y176750D01*
X-611600Y178250D01*
X-612650Y179500D01*
X-614050Y180000D01*
G01X-601425Y176750D02*
X-600550Y180000D01*
G01X-598275D02*
X-599150Y176750D01*
G01X-1693250Y195000D02*
Y210000D01*
X-1695350Y207000D01*
G01Y195000D02*
X-1691150D01*
G01X-1682900Y197250D02*
X-1681850Y196000D01*
X-1680625Y195250D01*
X-1679050Y195000D01*
X-1677475Y195500D01*
X-1676250Y196500D01*
X-1675375Y198250D01*
X-1675200Y200250D01*
X-1675550Y202250D01*
X-1676425Y203500D01*
X-1677650Y204500D01*
X-1678875Y204750D01*
X-1680100Y204500D01*
X-1681675Y203500D01*
X-1681150Y210000D01*
X-1676425D01*
G01X-1664850Y194500D02*
X-1665200Y194750D01*
Y195250D01*
X-1664850Y195500D01*
X-1664500Y195250D01*
Y194750D01*
X-1664850Y194500D01*
G01X-1640125Y195000D02*
Y210000D01*
G01X-1632775D02*
Y195000D01*
G01Y202500D02*
X-1640125D01*
G01X-1622250Y195000D02*
X-1623650Y195250D01*
X-1624875Y196250D01*
X-1625925Y197750D01*
X-1626625Y199500D01*
X-1626975Y201500D01*
Y203500D01*
X-1626625Y205500D01*
X-1625925Y207250D01*
X-1624875Y208750D01*
X-1623650Y209750D01*
X-1622250Y210000D01*
X-1620850Y209750D01*
X-1619625Y208750D01*
X-1618575Y207250D01*
X-1617875Y205500D01*
X-1617525Y203500D01*
Y201500D01*
X-1617875Y199500D01*
X-1618575Y197750D01*
X-1619625Y196250D01*
X-1620850Y195250D01*
X-1622250Y195000D01*
G01X-1611550Y210000D02*
Y195000D01*
X-1604550D01*
G01X-1590350D02*
X-1597350D01*
Y210000D01*
X-1590350D01*
G01X-1593150Y202750D02*
X-1597350D01*
G01X-1568950Y210000D02*
Y195000D01*
X-1561950D01*
G01X-1551250D02*
X-1552650Y195250D01*
X-1553875Y196250D01*
X-1554925Y197750D01*
X-1555625Y199500D01*
X-1555975Y201500D01*
Y203500D01*
X-1555625Y205500D01*
X-1554925Y207250D01*
X-1553875Y208750D01*
X-1552650Y209750D01*
X-1551250Y210000D01*
X-1549850Y209750D01*
X-1548625Y208750D01*
X-1547575Y207250D01*
X-1546875Y205500D01*
X-1546525Y203500D01*
Y201500D01*
X-1546875Y199500D01*
X-1547575Y197750D01*
X-1548625Y196250D01*
X-1549850Y195250D01*
X-1551250Y195000D01*
G01X-1533200Y208750D02*
X-1534250Y209500D01*
X-1535475Y210000D01*
X-1536875D01*
X-1538450Y209250D01*
X-1539675Y208000D01*
X-1540550Y206500D01*
X-1541250Y204000D01*
X-1541425Y201750D01*
X-1541075Y199500D01*
X-1540550Y198000D01*
X-1539500Y196500D01*
X-1538275Y195500D01*
X-1537050Y195000D01*
X-1535825D01*
X-1534600Y195500D01*
X-1533550Y196250D01*
X-1532675Y197250D01*
G01X-1527225Y195000D02*
X-1522850Y210000D01*
X-1518475Y195000D01*
G01X-1520050Y200250D02*
X-1525650D01*
G01X-1508650Y210000D02*
Y195000D01*
G01X-1512675Y210000D02*
X-1504625D01*
G01X-1496550D02*
X-1492350D01*
G01X-1494450D02*
Y195000D01*
G01X-1496550D02*
X-1492350D01*
G01X-1480250D02*
X-1481650Y195250D01*
X-1482875Y196250D01*
X-1483925Y197750D01*
X-1484625Y199500D01*
X-1484975Y201500D01*
Y203500D01*
X-1484625Y205500D01*
X-1483925Y207250D01*
X-1482875Y208750D01*
X-1481650Y209750D01*
X-1480250Y210000D01*
X-1478850Y209750D01*
X-1477625Y208750D01*
X-1476575Y207250D01*
X-1475875Y205500D01*
X-1475525Y203500D01*
Y201500D01*
X-1475875Y199500D01*
X-1476575Y197750D01*
X-1477625Y196250D01*
X-1478850Y195250D01*
X-1480250Y195000D01*
G01X-1470075D02*
Y210000D01*
X-1462025Y195000D01*
Y210000D01*
G01X-1437650D02*
Y195000D01*
G01X-1441675Y210000D02*
X-1433625D01*
G01X-1423450Y195000D02*
X-1424850Y195250D01*
X-1426075Y196250D01*
X-1427125Y197750D01*
X-1427825Y199500D01*
X-1428175Y201500D01*
Y203500D01*
X-1427825Y205500D01*
X-1427125Y207250D01*
X-1426075Y208750D01*
X-1424850Y209750D01*
X-1423450Y210000D01*
X-1422050Y209750D01*
X-1420825Y208750D01*
X-1419775Y207250D01*
X-1419075Y205500D01*
X-1418725Y203500D01*
Y201500D01*
X-1419075Y199500D01*
X-1419775Y197750D01*
X-1420825Y196250D01*
X-1422050Y195250D01*
X-1423450Y195000D01*
G01X-1412750Y210000D02*
Y195000D01*
X-1405750D01*
G01X-1391550D02*
X-1398550D01*
Y210000D01*
X-1391550D01*
G01X-1394350Y202750D02*
X-1398550D01*
G01X-1384350Y195000D02*
Y210000D01*
X-1379975D01*
X-1378575Y209250D01*
X-1377700Y208250D01*
X-1377350Y206250D01*
X-1377700Y204250D01*
X-1378750Y203000D01*
X-1379975Y202250D01*
X-1384350D01*
G01X-1379975D02*
X-1377350Y195000D01*
G01X-1371025D02*
X-1366650Y210000D01*
X-1362275Y195000D01*
G01X-1363850Y200250D02*
X-1369450D01*
G01X-1356475Y195000D02*
Y210000D01*
X-1348425Y195000D01*
Y210000D01*
G01X-1334400Y208750D02*
X-1335450Y209500D01*
X-1336675Y210000D01*
X-1338075D01*
X-1339650Y209250D01*
X-1340875Y208000D01*
X-1341750Y206500D01*
X-1342450Y204000D01*
X-1342625Y201750D01*
X-1342275Y199500D01*
X-1341750Y198000D01*
X-1340700Y196500D01*
X-1339475Y195500D01*
X-1338250Y195000D01*
X-1337025D01*
X-1335800Y195500D01*
X-1334750Y196250D01*
X-1333875Y197250D01*
G01X-1320550Y195000D02*
X-1327550D01*
Y210000D01*
X-1320550D01*
G01X-1323350Y202750D02*
X-1327550D01*
G01X-1309850Y194500D02*
X-1310200Y194750D01*
Y195250D01*
X-1309850Y195500D01*
X-1309500Y195250D01*
Y194750D01*
X-1309850Y194500D01*
G01Y201250D02*
X-1310200Y201500D01*
Y202000D01*
X-1309850Y202250D01*
X-1309500Y202000D01*
Y201500D01*
X-1309850Y201250D01*
G01X-1284950Y195000D02*
Y210000D01*
X-1280750D01*
X-1279350Y209250D01*
X-1278300Y207500D01*
X-1277950Y205500D01*
X-1278300Y203500D01*
X-1279175Y202000D01*
X-1280750Y201250D01*
X-1284950D01*
G01X-1270750Y210000D02*
Y195000D01*
X-1263750D01*
G01X-1257425D02*
X-1253050Y210000D01*
X-1248675Y195000D01*
G01X-1250250Y200250D02*
X-1255850D01*
G01X-1238850Y210000D02*
Y195000D01*
G01X-1242875Y210000D02*
X-1234825D01*
G01X-1221150Y195000D02*
X-1228150D01*
Y210000D01*
X-1221150D01*
G01X-1223950Y202750D02*
X-1228150D01*
G01X-1214300Y195000D02*
Y210000D01*
X-1210800D01*
X-1209400Y209250D01*
X-1208350Y208250D01*
X-1207475Y206750D01*
X-1206775Y205000D01*
X-1206600Y202500D01*
X-1206775Y200000D01*
X-1207475Y198250D01*
X-1208350Y196750D01*
X-1209400Y195750D01*
X-1210800Y195000D01*
X-1214300D01*
G01X-1182050Y210000D02*
Y195000D01*
G01X-1186075Y210000D02*
X-1178025D01*
G01X-1171525Y195000D02*
Y210000D01*
G01X-1164175D02*
Y195000D01*
G01Y202500D02*
X-1171525D01*
G01X-1157150Y195000D02*
Y210000D01*
X-1152775D01*
X-1151375Y209250D01*
X-1150500Y208250D01*
X-1150150Y206250D01*
X-1150500Y204250D01*
X-1151550Y203000D01*
X-1152775Y202250D01*
X-1157150D01*
G01X-1152775D02*
X-1150150Y195000D01*
G01X-1143300Y210000D02*
Y199250D01*
X-1142600Y197000D01*
X-1141200Y195500D01*
X-1139450Y195000D01*
X-1137700Y195500D01*
X-1136300Y197000D01*
X-1135600Y199250D01*
Y210000D01*
G01X-1114725Y195000D02*
Y210000D01*
G01X-1107375D02*
Y195000D01*
G01Y202500D02*
X-1114725D01*
G01X-1096850Y195000D02*
X-1098250Y195250D01*
X-1099475Y196250D01*
X-1100525Y197750D01*
X-1101225Y199500D01*
X-1101575Y201500D01*
Y203500D01*
X-1101225Y205500D01*
X-1100525Y207250D01*
X-1099475Y208750D01*
X-1098250Y209750D01*
X-1096850Y210000D01*
X-1095450Y209750D01*
X-1094225Y208750D01*
X-1093175Y207250D01*
X-1092475Y205500D01*
X-1092125Y203500D01*
Y201500D01*
X-1092475Y199500D01*
X-1093175Y197750D01*
X-1094225Y196250D01*
X-1095450Y195250D01*
X-1096850Y195000D01*
G01X-1086150Y210000D02*
Y195000D01*
X-1079150D01*
G01X-1064950D02*
X-1071950D01*
Y210000D01*
X-1064950D01*
G01X-1067750Y202750D02*
X-1071950D01*
G01X-1057925Y197000D02*
X-1056525Y195750D01*
X-1054950Y195000D01*
X-1053550D01*
X-1052150Y195750D01*
X-1051100Y197000D01*
X-1050575Y198750D01*
X-1050925Y200500D01*
X-1051800Y202000D01*
X-1053375Y203000D01*
X-1055475Y203500D01*
X-1056700Y204500D01*
X-1057225Y206250D01*
X-1056875Y208000D01*
X-1056000Y209250D01*
X-1054775Y210000D01*
X-1053550D01*
X-1052325Y209500D01*
X-1051275Y208250D01*
G01X-1029525Y197000D02*
X-1028125Y195750D01*
X-1026550Y195000D01*
X-1025150D01*
X-1023750Y195750D01*
X-1022700Y197000D01*
X-1022175Y198750D01*
X-1022525Y200500D01*
X-1023400Y202000D01*
X-1024975Y203000D01*
X-1027075Y203500D01*
X-1028300Y204500D01*
X-1028825Y206250D01*
X-1028475Y208000D01*
X-1027600Y209250D01*
X-1026375Y210000D01*
X-1025150D01*
X-1023925Y209500D01*
X-1022875Y208250D01*
G01X-1015325Y195000D02*
Y210000D01*
G01X-1007975D02*
Y195000D01*
G01Y202500D02*
X-1015325D01*
G01X-1001825Y195000D02*
X-997450Y210000D01*
X-993075Y195000D01*
G01X-994650Y200250D02*
X-1000250D01*
G01X-986750Y210000D02*
Y195000D01*
X-979750D01*
G01X-972550Y210000D02*
Y195000D01*
X-965550D01*
G01X-939250Y203000D02*
X-938550Y203750D01*
X-938025Y205000D01*
X-937675Y206750D01*
X-938025Y208250D01*
X-938725Y209250D01*
X-939950Y210000D01*
X-944675D01*
Y195000D01*
X-938900D01*
X-937675Y196000D01*
X-936975Y197500D01*
X-936625Y199250D01*
X-936975Y201000D01*
X-938025Y202500D01*
X-939250Y203000D01*
X-944675D01*
G01X-922950Y195000D02*
X-929950D01*
Y210000D01*
X-922950D01*
G01X-925750Y202750D02*
X-929950D01*
G01X-903300Y210000D02*
X-900850Y195000D01*
X-898050Y210000D01*
X-895250Y195000D01*
X-892800Y210000D01*
G01X-885950D02*
X-881750D01*
G01X-883850D02*
Y195000D01*
G01X-885950D02*
X-881750D01*
G01X-869650Y210000D02*
Y195000D01*
G01X-873675Y210000D02*
X-865625D01*
G01X-859125Y195000D02*
Y210000D01*
G01X-851775D02*
Y195000D01*
G01Y202500D02*
X-859125D01*
G01X-843350Y210000D02*
X-839150D01*
G01X-841250D02*
Y195000D01*
G01X-843350D02*
X-839150D01*
G01X-831075D02*
Y210000D01*
X-823025Y195000D01*
Y210000D01*
G01X-798650Y194500D02*
X-799000Y194750D01*
Y195250D01*
X-798650Y195500D01*
X-798300Y195250D01*
Y194750D01*
X-798650Y194500D01*
G01X-784450Y210000D02*
X-785850Y209500D01*
X-786900Y208250D01*
X-787600Y206750D01*
X-788125Y204750D01*
X-788300Y202500D01*
X-788125Y200250D01*
X-787600Y198250D01*
X-786900Y196750D01*
X-785850Y195500D01*
X-784450Y195000D01*
X-783050Y195500D01*
X-782000Y196750D01*
X-781300Y198250D01*
X-780775Y200250D01*
X-780600Y202500D01*
X-780775Y204750D01*
X-781300Y206750D01*
X-782000Y208250D01*
X-783050Y209500D01*
X-784450Y210000D01*
G01X-770250D02*
X-771650Y209500D01*
X-772700Y208250D01*
X-773400Y206750D01*
X-773925Y204750D01*
X-774100Y202500D01*
X-773925Y200250D01*
X-773400Y198250D01*
X-772700Y196750D01*
X-771650Y195500D01*
X-770250Y195000D01*
X-768850Y195500D01*
X-767800Y196750D01*
X-767100Y198250D01*
X-766575Y200250D01*
X-766400Y202500D01*
X-766575Y204750D01*
X-767100Y206750D01*
X-767800Y208250D01*
X-768850Y209500D01*
X-770250Y210000D01*
G01X-756050Y195000D02*
X-754825Y195250D01*
X-753425Y196000D01*
X-752550Y197250D01*
X-752200Y199000D01*
X-752550Y200750D01*
X-753600Y202250D01*
X-755175Y203000D01*
X-756925D01*
X-757975Y203500D01*
X-758850Y204750D01*
X-759200Y206500D01*
X-758675Y208250D01*
X-757450Y209500D01*
X-756050Y210000D01*
X-754650Y209500D01*
X-753425Y208250D01*
X-752900Y206500D01*
X-753250Y204750D01*
X-754125Y203500D01*
X-755175Y203000D01*
X-756925D01*
X-758500Y202250D01*
X-759550Y200750D01*
X-759900Y199000D01*
X-759550Y197250D01*
X-758675Y196000D01*
X-757275Y195250D01*
X-756050Y195000D01*
G01X-743425Y206750D02*
X-742550Y210000D01*
G01X-740275D02*
X-741150Y206750D01*
G01X-717300Y195000D02*
Y210000D01*
X-713800D01*
X-712400Y209250D01*
X-711350Y208250D01*
X-710475Y206750D01*
X-709775Y205000D01*
X-709600Y202500D01*
X-709775Y200000D01*
X-710475Y198250D01*
X-711350Y196750D01*
X-712400Y195750D01*
X-713800Y195000D01*
X-717300D01*
G01X-701350Y210000D02*
X-697150D01*
G01X-699250D02*
Y195000D01*
G01X-701350D02*
X-697150D01*
G01X-689425D02*
X-685050Y210000D01*
X-680675Y195000D01*
G01X-682250Y200250D02*
X-687850D01*
G01X-675400Y195000D02*
Y210000D01*
X-670850Y197500D01*
X-666300Y210000D01*
Y195000D01*
G01X-653150D02*
X-660150D01*
Y210000D01*
X-653150D01*
G01X-655950Y202750D02*
X-660150D01*
G01X-642450Y210000D02*
Y195000D01*
G01X-646475Y210000D02*
X-638425D01*
G01X-624750Y195000D02*
X-631750D01*
Y210000D01*
X-624750D01*
G01X-627550Y202750D02*
X-631750D01*
G01X-617550Y195000D02*
Y210000D01*
X-613175D01*
X-611775Y209250D01*
X-610900Y208250D01*
X-610550Y206250D01*
X-610900Y204250D01*
X-611950Y203000D01*
X-613175Y202250D01*
X-617550D01*
G01X-613175D02*
X-610550Y195000D01*
G01X-1636450Y229500D02*
X-1636800Y229750D01*
Y230250D01*
X-1636450Y230500D01*
X-1636100Y230250D01*
Y229750D01*
X-1636450Y229500D01*
G01X-1622250Y245000D02*
X-1623650Y244500D01*
X-1624700Y243250D01*
X-1625400Y241750D01*
X-1625925Y239750D01*
X-1626100Y237500D01*
X-1625925Y235250D01*
X-1625400Y233250D01*
X-1624700Y231750D01*
X-1623650Y230500D01*
X-1622250Y230000D01*
X-1620850Y230500D01*
X-1619800Y231750D01*
X-1619100Y233250D01*
X-1618575Y235250D01*
X-1618400Y237500D01*
X-1618575Y239750D01*
X-1619100Y241750D01*
X-1619800Y243250D01*
X-1620850Y244500D01*
X-1622250Y245000D01*
G01X-1608050D02*
X-1609450Y244500D01*
X-1610500Y243250D01*
X-1611200Y241750D01*
X-1611725Y239750D01*
X-1611900Y237500D01*
X-1611725Y235250D01*
X-1611200Y233250D01*
X-1610500Y231750D01*
X-1609450Y230500D01*
X-1608050Y230000D01*
X-1606650Y230500D01*
X-1605600Y231750D01*
X-1604900Y233250D01*
X-1604375Y235250D01*
X-1604200Y237500D01*
X-1604375Y239750D01*
X-1604900Y241750D01*
X-1605600Y243250D01*
X-1606650Y244500D01*
X-1608050Y245000D01*
G01X-1593850Y230000D02*
X-1592625Y230250D01*
X-1591225Y231000D01*
X-1590350Y232250D01*
X-1590000Y234000D01*
X-1590350Y235750D01*
X-1591400Y237250D01*
X-1592975Y238000D01*
X-1594725D01*
X-1595775Y238500D01*
X-1596650Y239750D01*
X-1597000Y241500D01*
X-1596475Y243250D01*
X-1595250Y244500D01*
X-1593850Y245000D01*
X-1592450Y244500D01*
X-1591225Y243250D01*
X-1590700Y241500D01*
X-1591050Y239750D01*
X-1591925Y238500D01*
X-1592975Y238000D01*
X-1594725D01*
X-1596300Y237250D01*
X-1597350Y235750D01*
X-1597700Y234000D01*
X-1597350Y232250D01*
X-1596475Y231000D01*
X-1595075Y230250D01*
X-1593850Y230000D01*
G01X-1581225Y241750D02*
X-1580350Y245000D01*
G01X-1578075D02*
X-1578950Y241750D01*
G01X-1555100Y230000D02*
Y245000D01*
X-1551600D01*
X-1550200Y244250D01*
X-1549150Y243250D01*
X-1548275Y241750D01*
X-1547575Y240000D01*
X-1547400Y237500D01*
X-1547575Y235000D01*
X-1548275Y233250D01*
X-1549150Y231750D01*
X-1550200Y230750D01*
X-1551600Y230000D01*
X-1555100D01*
G01X-1539150Y245000D02*
X-1534950D01*
G01X-1537050D02*
Y230000D01*
G01X-1539150D02*
X-1534950D01*
G01X-1527225D02*
X-1522850Y245000D01*
X-1518475Y230000D01*
G01X-1520050Y235250D02*
X-1525650D01*
G01X-1513200Y230000D02*
Y245000D01*
X-1508650Y232500D01*
X-1504100Y245000D01*
Y230000D01*
G01X-1490950D02*
X-1497950D01*
Y245000D01*
X-1490950D01*
G01X-1493750Y237750D02*
X-1497950D01*
G01X-1480250Y245000D02*
Y230000D01*
G01X-1484275Y245000D02*
X-1476225D01*
G01X-1462550Y230000D02*
X-1469550D01*
Y245000D01*
X-1462550D01*
G01X-1465350Y237750D02*
X-1469550D01*
G01X-1455350Y230000D02*
Y245000D01*
X-1450975D01*
X-1449575Y244250D01*
X-1448700Y243250D01*
X-1448350Y241250D01*
X-1448700Y239250D01*
X-1449750Y238000D01*
X-1450975Y237250D01*
X-1455350D01*
G01X-1450975D02*
X-1448350Y230000D01*
G01X-1423450Y245000D02*
Y230000D01*
G01X-1427475Y245000D02*
X-1419425D01*
G01X-1412750Y230000D02*
Y245000D01*
X-1408375D01*
X-1406975Y244250D01*
X-1406100Y243250D01*
X-1405750Y241250D01*
X-1406100Y239250D01*
X-1407150Y238000D01*
X-1408375Y237250D01*
X-1412750D01*
G01X-1408375D02*
X-1405750Y230000D01*
G01X-1398900Y245000D02*
Y234250D01*
X-1398200Y232000D01*
X-1396800Y230500D01*
X-1395050Y230000D01*
X-1393300Y230500D01*
X-1391900Y232000D01*
X-1391200Y234250D01*
Y245000D01*
G01X-1377350Y230000D02*
X-1384350D01*
Y245000D01*
X-1377350D01*
G01X-1380150Y237750D02*
X-1384350D01*
G01X-1355950Y230000D02*
Y245000D01*
X-1351750D01*
X-1350350Y244250D01*
X-1349300Y242500D01*
X-1348950Y240500D01*
X-1349300Y238500D01*
X-1350175Y237000D01*
X-1351750Y236250D01*
X-1355950D01*
G01X-1338250Y230000D02*
X-1339650Y230250D01*
X-1340875Y231250D01*
X-1341925Y232750D01*
X-1342625Y234500D01*
X-1342975Y236500D01*
Y238500D01*
X-1342625Y240500D01*
X-1341925Y242250D01*
X-1340875Y243750D01*
X-1339650Y244750D01*
X-1338250Y245000D01*
X-1336850Y244750D01*
X-1335625Y243750D01*
X-1334575Y242250D01*
X-1333875Y240500D01*
X-1333525Y238500D01*
Y236500D01*
X-1333875Y234500D01*
X-1334575Y232750D01*
X-1335625Y231250D01*
X-1336850Y230250D01*
X-1338250Y230000D01*
G01X-1327725Y232000D02*
X-1326325Y230750D01*
X-1324750Y230000D01*
X-1323350D01*
X-1321950Y230750D01*
X-1320900Y232000D01*
X-1320375Y233750D01*
X-1320725Y235500D01*
X-1321600Y237000D01*
X-1323175Y238000D01*
X-1325275Y238500D01*
X-1326500Y239500D01*
X-1327025Y241250D01*
X-1326675Y243000D01*
X-1325800Y244250D01*
X-1324575Y245000D01*
X-1323350D01*
X-1322125Y244500D01*
X-1321075Y243250D01*
G01X-1311950Y245000D02*
X-1307750D01*
G01X-1309850D02*
Y230000D01*
G01X-1311950D02*
X-1307750D01*
G01X-1295650Y245000D02*
Y230000D01*
G01X-1299675Y245000D02*
X-1291625D01*
G01X-1283550D02*
X-1279350D01*
G01X-1281450D02*
Y230000D01*
G01X-1283550D02*
X-1279350D01*
G01X-1267250D02*
X-1268650Y230250D01*
X-1269875Y231250D01*
X-1270925Y232750D01*
X-1271625Y234500D01*
X-1271975Y236500D01*
Y238500D01*
X-1271625Y240500D01*
X-1270925Y242250D01*
X-1269875Y243750D01*
X-1268650Y244750D01*
X-1267250Y245000D01*
X-1265850Y244750D01*
X-1264625Y243750D01*
X-1263575Y242250D01*
X-1262875Y240500D01*
X-1262525Y238500D01*
Y236500D01*
X-1262875Y234500D01*
X-1263575Y232750D01*
X-1264625Y231250D01*
X-1265850Y230250D01*
X-1267250Y230000D01*
G01X-1257075D02*
Y245000D01*
X-1249025Y230000D01*
Y245000D01*
G01X-1228150Y230000D02*
Y245000D01*
X-1223775D01*
X-1222375Y244250D01*
X-1221500Y243250D01*
X-1221150Y241250D01*
X-1221500Y239250D01*
X-1222550Y238000D01*
X-1223775Y237250D01*
X-1228150D01*
G01X-1223775D02*
X-1221150Y230000D01*
G01X-1206950D02*
X-1213950D01*
Y245000D01*
X-1206950D01*
G01X-1209750Y237750D02*
X-1213950D01*
G01X-1195200Y237500D02*
X-1191700D01*
Y233000D01*
X-1192750Y231500D01*
X-1193975Y230500D01*
X-1195725Y230000D01*
X-1197475Y230500D01*
X-1198700Y231500D01*
X-1199750Y233000D01*
X-1200450Y234750D01*
X-1200800Y236750D01*
Y238500D01*
X-1200450Y240000D01*
X-1199750Y241750D01*
X-1198700Y243250D01*
X-1197650Y244250D01*
X-1196250Y245000D01*
X-1195025D01*
X-1193625Y244500D01*
X-1192575Y243500D01*
G01X-1186425Y230000D02*
X-1182050Y245000D01*
X-1177675Y230000D01*
G01X-1179250Y235250D02*
X-1184850D01*
G01X-1171350Y230000D02*
Y245000D01*
X-1166975D01*
X-1165575Y244250D01*
X-1164700Y243250D01*
X-1164350Y241250D01*
X-1164700Y239250D01*
X-1165750Y238000D01*
X-1166975Y237250D01*
X-1171350D01*
G01X-1166975D02*
X-1164350Y230000D01*
G01X-1157500D02*
Y245000D01*
X-1154000D01*
X-1152600Y244250D01*
X-1151550Y243250D01*
X-1150675Y241750D01*
X-1149975Y240000D01*
X-1149800Y237500D01*
X-1149975Y235000D01*
X-1150675Y233250D01*
X-1151550Y231750D01*
X-1152600Y230750D01*
X-1154000Y230000D01*
X-1157500D01*
G01X-1142950Y245000D02*
Y230000D01*
X-1135950D01*
G01X-1121750D02*
X-1128750D01*
Y245000D01*
X-1121750D01*
G01X-1124550Y237750D02*
X-1128750D01*
G01X-1114725Y232000D02*
X-1113325Y230750D01*
X-1111750Y230000D01*
X-1110350D01*
X-1108950Y230750D01*
X-1107900Y232000D01*
X-1107375Y233750D01*
X-1107725Y235500D01*
X-1108600Y237000D01*
X-1110175Y238000D01*
X-1112275Y238500D01*
X-1113500Y239500D01*
X-1114025Y241250D01*
X-1113675Y243000D01*
X-1112800Y244250D01*
X-1111575Y245000D01*
X-1110350D01*
X-1109125Y244500D01*
X-1108075Y243250D01*
G01X-1100525Y232000D02*
X-1099125Y230750D01*
X-1097550Y230000D01*
X-1096150D01*
X-1094750Y230750D01*
X-1093700Y232000D01*
X-1093175Y233750D01*
X-1093525Y235500D01*
X-1094400Y237000D01*
X-1095975Y238000D01*
X-1098075Y238500D01*
X-1099300Y239500D01*
X-1099825Y241250D01*
X-1099475Y243000D01*
X-1098600Y244250D01*
X-1097375Y245000D01*
X-1096150D01*
X-1094925Y244500D01*
X-1093875Y243250D01*
G01X-1068450Y230000D02*
X-1069850Y230250D01*
X-1071075Y231250D01*
X-1072125Y232750D01*
X-1072825Y234500D01*
X-1073175Y236500D01*
Y238500D01*
X-1072825Y240500D01*
X-1072125Y242250D01*
X-1071075Y243750D01*
X-1069850Y244750D01*
X-1068450Y245000D01*
X-1067050Y244750D01*
X-1065825Y243750D01*
X-1064775Y242250D01*
X-1064075Y240500D01*
X-1063725Y238500D01*
Y236500D01*
X-1064075Y234500D01*
X-1064775Y232750D01*
X-1065825Y231250D01*
X-1067050Y230250D01*
X-1068450Y230000D01*
G01X-1057575D02*
Y245000D01*
X-1050925D01*
G01X-1053375Y237750D02*
X-1057575D01*
G01X-1029175Y230000D02*
Y245000D01*
X-1022525D01*
G01X-1024975Y237750D02*
X-1029175D01*
G01X-1008150Y230000D02*
X-1015150D01*
Y245000D01*
X-1008150D01*
G01X-1010950Y237750D02*
X-1015150D01*
G01X-1001825Y230000D02*
X-997450Y245000D01*
X-993075Y230000D01*
G01X-994650Y235250D02*
X-1000250D01*
G01X-983250Y245000D02*
Y230000D01*
G01X-987275Y245000D02*
X-979225D01*
G01X-972900D02*
Y234250D01*
X-972200Y232000D01*
X-970800Y230500D01*
X-969050Y230000D01*
X-967300Y230500D01*
X-965900Y232000D01*
X-965200Y234250D01*
Y245000D01*
G01X-958350Y230000D02*
Y245000D01*
X-953975D01*
X-952575Y244250D01*
X-951700Y243250D01*
X-951350Y241250D01*
X-951700Y239250D01*
X-952750Y238000D01*
X-953975Y237250D01*
X-958350D01*
G01X-953975D02*
X-951350Y230000D01*
G01X-937150D02*
X-944150D01*
Y245000D01*
X-937150D01*
G01X-939950Y237750D02*
X-944150D01*
G01X-915925Y232000D02*
X-914525Y230750D01*
X-912950Y230000D01*
X-911550D01*
X-910150Y230750D01*
X-909100Y232000D01*
X-908575Y233750D01*
X-908925Y235500D01*
X-909800Y237000D01*
X-911375Y238000D01*
X-913475Y238500D01*
X-914700Y239500D01*
X-915225Y241250D01*
X-914875Y243000D01*
X-914000Y244250D01*
X-912775Y245000D01*
X-911550D01*
X-910325Y244500D01*
X-909275Y243250D01*
G01X-900150Y245000D02*
X-895950D01*
G01X-898050D02*
Y230000D01*
G01X-900150D02*
X-895950D01*
G01X-887175Y245000D02*
X-880525D01*
X-887175Y230000D01*
X-880525D01*
G01X-866150D02*
X-873150D01*
Y245000D01*
X-866150D01*
G01X-868950Y237750D02*
X-873150D01*
G01X-842125Y225000D02*
X-843875Y227500D01*
X-844750Y230000D01*
Y240000D01*
X-843875Y242500D01*
X-842125Y245000D01*
G01X-830550Y230000D02*
Y245000D01*
X-826175D01*
X-824775Y244250D01*
X-823900Y243250D01*
X-823550Y241250D01*
X-823900Y239250D01*
X-824950Y238000D01*
X-826175Y237250D01*
X-830550D01*
G01X-826175D02*
X-823550Y230000D01*
G01X-816175D02*
Y245000D01*
X-809525D01*
G01X-811975Y237750D02*
X-816175D01*
G01X-802325Y232000D02*
X-800925Y230750D01*
X-799350Y230000D01*
X-797950D01*
X-796550Y230750D01*
X-795500Y232000D01*
X-794975Y233750D01*
X-795325Y235500D01*
X-796200Y237000D01*
X-797775Y238000D01*
X-799875Y238500D01*
X-801100Y239500D01*
X-801625Y241250D01*
X-801275Y243000D01*
X-800400Y244250D01*
X-799175Y245000D01*
X-797950D01*
X-796725Y244500D01*
X-795675Y243250D01*
G01X-783575Y225000D02*
X-781825Y227500D01*
X-780950Y230000D01*
Y240000D01*
X-781825Y242500D01*
X-783575Y245000D01*
G01X-770250Y229500D02*
X-770600Y229750D01*
Y230250D01*
X-770250Y230500D01*
X-769900Y230250D01*
Y229750D01*
X-770250Y229500D01*
G01X-1693250Y260000D02*
Y275000D01*
X-1695350Y272000D01*
G01Y260000D02*
X-1691150D01*
G01X-1676950D02*
Y275000D01*
X-1683425Y264250D01*
X-1674675D01*
G01X-1664850Y259500D02*
X-1665200Y259750D01*
Y260250D01*
X-1664850Y260500D01*
X-1664500Y260250D01*
Y259750D01*
X-1664850Y259500D01*
G01X-1639775Y260000D02*
Y275000D01*
X-1633125D01*
G01X-1635575Y267750D02*
X-1639775D01*
G01X-1618750Y260000D02*
X-1625750D01*
Y275000D01*
X-1618750D01*
G01X-1621550Y267750D02*
X-1625750D01*
G01X-1612425Y260000D02*
X-1608050Y275000D01*
X-1603675Y260000D01*
G01X-1605250Y265250D02*
X-1610850D01*
G01X-1593850Y275000D02*
Y260000D01*
G01X-1597875Y275000D02*
X-1589825D01*
G01X-1583500D02*
Y264250D01*
X-1582800Y262000D01*
X-1581400Y260500D01*
X-1579650Y260000D01*
X-1577900Y260500D01*
X-1576500Y262000D01*
X-1575800Y264250D01*
Y275000D01*
G01X-1568950Y260000D02*
Y275000D01*
X-1564575D01*
X-1563175Y274250D01*
X-1562300Y273250D01*
X-1561950Y271250D01*
X-1562300Y269250D01*
X-1563350Y268000D01*
X-1564575Y267250D01*
X-1568950D01*
G01X-1564575D02*
X-1561950Y260000D01*
G01X-1547750D02*
X-1554750D01*
Y275000D01*
X-1547750D01*
G01X-1550550Y267750D02*
X-1554750D01*
G01X-1526350Y275000D02*
Y260000D01*
X-1519350D01*
G01X-1508650D02*
X-1510050Y260250D01*
X-1511275Y261250D01*
X-1512325Y262750D01*
X-1513025Y264500D01*
X-1513375Y266500D01*
Y268500D01*
X-1513025Y270500D01*
X-1512325Y272250D01*
X-1511275Y273750D01*
X-1510050Y274750D01*
X-1508650Y275000D01*
X-1507250Y274750D01*
X-1506025Y273750D01*
X-1504975Y272250D01*
X-1504275Y270500D01*
X-1503925Y268500D01*
Y266500D01*
X-1504275Y264500D01*
X-1504975Y262750D01*
X-1506025Y261250D01*
X-1507250Y260250D01*
X-1508650Y260000D01*
G01X-1490600Y273750D02*
X-1491650Y274500D01*
X-1492875Y275000D01*
X-1494275D01*
X-1495850Y274250D01*
X-1497075Y273000D01*
X-1497950Y271500D01*
X-1498650Y269000D01*
X-1498825Y266750D01*
X-1498475Y264500D01*
X-1497950Y263000D01*
X-1496900Y261500D01*
X-1495675Y260500D01*
X-1494450Y260000D01*
X-1493225D01*
X-1492000Y260500D01*
X-1490950Y261250D01*
X-1490075Y262250D01*
G01X-1484625Y260000D02*
X-1480250Y275000D01*
X-1475875Y260000D01*
G01X-1477450Y265250D02*
X-1483050D01*
G01X-1466050Y275000D02*
Y260000D01*
G01X-1470075Y275000D02*
X-1462025D01*
G01X-1453950D02*
X-1449750D01*
G01X-1451850D02*
Y260000D01*
G01X-1453950D02*
X-1449750D01*
G01X-1437650D02*
X-1439050Y260250D01*
X-1440275Y261250D01*
X-1441325Y262750D01*
X-1442025Y264500D01*
X-1442375Y266500D01*
Y268500D01*
X-1442025Y270500D01*
X-1441325Y272250D01*
X-1440275Y273750D01*
X-1439050Y274750D01*
X-1437650Y275000D01*
X-1436250Y274750D01*
X-1435025Y273750D01*
X-1433975Y272250D01*
X-1433275Y270500D01*
X-1432925Y268500D01*
Y266500D01*
X-1433275Y264500D01*
X-1433975Y262750D01*
X-1435025Y261250D01*
X-1436250Y260250D01*
X-1437650Y260000D01*
G01X-1427475D02*
Y275000D01*
X-1419425Y260000D01*
Y275000D01*
G01X-1395050D02*
Y260000D01*
G01X-1399075Y275000D02*
X-1391025D01*
G01X-1380850Y260000D02*
X-1382250Y260250D01*
X-1383475Y261250D01*
X-1384525Y262750D01*
X-1385225Y264500D01*
X-1385575Y266500D01*
Y268500D01*
X-1385225Y270500D01*
X-1384525Y272250D01*
X-1383475Y273750D01*
X-1382250Y274750D01*
X-1380850Y275000D01*
X-1379450Y274750D01*
X-1378225Y273750D01*
X-1377175Y272250D01*
X-1376475Y270500D01*
X-1376125Y268500D01*
Y266500D01*
X-1376475Y264500D01*
X-1377175Y262750D01*
X-1378225Y261250D01*
X-1379450Y260250D01*
X-1380850Y260000D01*
G01X-1370150Y275000D02*
Y260000D01*
X-1363150D01*
G01X-1348950D02*
X-1355950D01*
Y275000D01*
X-1348950D01*
G01X-1351750Y267750D02*
X-1355950D01*
G01X-1341750Y260000D02*
Y275000D01*
X-1337375D01*
X-1335975Y274250D01*
X-1335100Y273250D01*
X-1334750Y271250D01*
X-1335100Y269250D01*
X-1336150Y268000D01*
X-1337375Y267250D01*
X-1341750D01*
G01X-1337375D02*
X-1334750Y260000D01*
G01X-1328425D02*
X-1324050Y275000D01*
X-1319675Y260000D01*
G01X-1321250Y265250D02*
X-1326850D01*
G01X-1313875Y260000D02*
Y275000D01*
X-1305825Y260000D01*
Y275000D01*
G01X-1291800Y273750D02*
X-1292850Y274500D01*
X-1294075Y275000D01*
X-1295475D01*
X-1297050Y274250D01*
X-1298275Y273000D01*
X-1299150Y271500D01*
X-1299850Y269000D01*
X-1300025Y266750D01*
X-1299675Y264500D01*
X-1299150Y263000D01*
X-1298100Y261500D01*
X-1296875Y260500D01*
X-1295650Y260000D01*
X-1294425D01*
X-1293200Y260500D01*
X-1292150Y261250D01*
X-1291275Y262250D01*
G01X-1277950Y260000D02*
X-1284950D01*
Y275000D01*
X-1277950D01*
G01X-1280750Y267750D02*
X-1284950D01*
G01X-1267250Y259500D02*
X-1267600Y259750D01*
Y260250D01*
X-1267250Y260500D01*
X-1266900Y260250D01*
Y259750D01*
X-1267250Y259500D01*
G01Y266250D02*
X-1267600Y266500D01*
Y267000D01*
X-1267250Y267250D01*
X-1266900Y267000D01*
Y266500D01*
X-1267250Y266250D01*
G01X-1243225Y260000D02*
X-1238850Y275000D01*
X-1234475Y260000D01*
G01X-1236050Y265250D02*
X-1241650D01*
G01X-1228150Y275000D02*
Y260000D01*
X-1221150D01*
G01X-1213950Y275000D02*
Y260000D01*
X-1206950D01*
G01X-1178200Y273750D02*
X-1179250Y274500D01*
X-1180475Y275000D01*
X-1181875D01*
X-1183450Y274250D01*
X-1184675Y273000D01*
X-1185550Y271500D01*
X-1186250Y269000D01*
X-1186425Y266750D01*
X-1186075Y264500D01*
X-1185550Y263000D01*
X-1184500Y261500D01*
X-1183275Y260500D01*
X-1182050Y260000D01*
X-1180825D01*
X-1179600Y260500D01*
X-1178550Y261250D01*
X-1177675Y262250D01*
G01X-1167850Y260000D02*
X-1169250Y260250D01*
X-1170475Y261250D01*
X-1171525Y262750D01*
X-1172225Y264500D01*
X-1172575Y266500D01*
Y268500D01*
X-1172225Y270500D01*
X-1171525Y272250D01*
X-1170475Y273750D01*
X-1169250Y274750D01*
X-1167850Y275000D01*
X-1166450Y274750D01*
X-1165225Y273750D01*
X-1164175Y272250D01*
X-1163475Y270500D01*
X-1163125Y268500D01*
Y266500D01*
X-1163475Y264500D01*
X-1164175Y262750D01*
X-1165225Y261250D01*
X-1166450Y260250D01*
X-1167850Y260000D01*
G01X-1157675D02*
Y275000D01*
X-1149625Y260000D01*
Y275000D01*
G01X-1143300Y260000D02*
Y275000D01*
X-1139800D01*
X-1138400Y274250D01*
X-1137350Y273250D01*
X-1136475Y271750D01*
X-1135775Y270000D01*
X-1135600Y267500D01*
X-1135775Y265000D01*
X-1136475Y263250D01*
X-1137350Y261750D01*
X-1138400Y260750D01*
X-1139800Y260000D01*
X-1143300D01*
G01X-1129100Y275000D02*
Y264250D01*
X-1128400Y262000D01*
X-1127000Y260500D01*
X-1125250Y260000D01*
X-1123500Y260500D01*
X-1122100Y262000D01*
X-1121400Y264250D01*
Y275000D01*
G01X-1107200Y273750D02*
X-1108250Y274500D01*
X-1109475Y275000D01*
X-1110875D01*
X-1112450Y274250D01*
X-1113675Y273000D01*
X-1114550Y271500D01*
X-1115250Y269000D01*
X-1115425Y266750D01*
X-1115075Y264500D01*
X-1114550Y263000D01*
X-1113500Y261500D01*
X-1112275Y260500D01*
X-1111050Y260000D01*
X-1109825D01*
X-1108600Y260500D01*
X-1107550Y261250D01*
X-1106675Y262250D01*
G01X-1096850Y275000D02*
Y260000D01*
G01X-1100875Y275000D02*
X-1092825D01*
G01X-1084750D02*
X-1080550D01*
G01X-1082650D02*
Y260000D01*
G01X-1084750D02*
X-1080550D01*
G01X-1072825Y275000D02*
X-1068450Y260000D01*
X-1064075Y275000D01*
G01X-1050750Y260000D02*
X-1057750D01*
Y275000D01*
X-1050750D01*
G01X-1053550Y267750D02*
X-1057750D01*
G01X-1029175Y260000D02*
Y275000D01*
X-1022525D01*
G01X-1024975Y267750D02*
X-1029175D01*
G01X-1008150Y260000D02*
X-1015150D01*
Y275000D01*
X-1008150D01*
G01X-1010950Y267750D02*
X-1015150D01*
G01X-1001825Y260000D02*
X-997450Y275000D01*
X-993075Y260000D01*
G01X-994650Y265250D02*
X-1000250D01*
G01X-983250Y275000D02*
Y260000D01*
G01X-987275Y275000D02*
X-979225D01*
G01X-972900D02*
Y264250D01*
X-972200Y262000D01*
X-970800Y260500D01*
X-969050Y260000D01*
X-967300Y260500D01*
X-965900Y262000D01*
X-965200Y264250D01*
Y275000D01*
G01X-958350Y260000D02*
Y275000D01*
X-953975D01*
X-952575Y274250D01*
X-951700Y273250D01*
X-951350Y271250D01*
X-951700Y269250D01*
X-952750Y268000D01*
X-953975Y267250D01*
X-958350D01*
G01X-953975D02*
X-951350Y260000D01*
G01X-937150D02*
X-944150D01*
Y275000D01*
X-937150D01*
G01X-939950Y267750D02*
X-944150D01*
G01X-930125Y262000D02*
X-928725Y260750D01*
X-927150Y260000D01*
X-925750D01*
X-924350Y260750D01*
X-923300Y262000D01*
X-922775Y263750D01*
X-923125Y265500D01*
X-924000Y267000D01*
X-925575Y268000D01*
X-927675Y268500D01*
X-928900Y269500D01*
X-929425Y271250D01*
X-929075Y273000D01*
X-928200Y274250D01*
X-926975Y275000D01*
X-925750D01*
X-924525Y274500D01*
X-923475Y273250D01*
G01X-901725Y262000D02*
X-900325Y260750D01*
X-898750Y260000D01*
X-897350D01*
X-895950Y260750D01*
X-894900Y262000D01*
X-894375Y263750D01*
X-894725Y265500D01*
X-895600Y267000D01*
X-897175Y268000D01*
X-899275Y268500D01*
X-900500Y269500D01*
X-901025Y271250D01*
X-900675Y273000D01*
X-899800Y274250D01*
X-898575Y275000D01*
X-897350D01*
X-896125Y274500D01*
X-895075Y273250D01*
G01X-887525Y260000D02*
Y275000D01*
G01X-880175D02*
Y260000D01*
G01Y267500D02*
X-887525D01*
G01X-874025Y260000D02*
X-869650Y275000D01*
X-865275Y260000D01*
G01X-866850Y265250D02*
X-872450D01*
G01X-858950Y275000D02*
Y260000D01*
X-851950D01*
G01X-844750Y275000D02*
Y260000D01*
X-837750D01*
G01X-811450Y268000D02*
X-810750Y268750D01*
X-810225Y270000D01*
X-809875Y271750D01*
X-810225Y273250D01*
X-810925Y274250D01*
X-812150Y275000D01*
X-816875D01*
Y260000D01*
X-811100D01*
X-809875Y261000D01*
X-809175Y262500D01*
X-808825Y264250D01*
X-809175Y266000D01*
X-810225Y267500D01*
X-811450Y268000D01*
X-816875D01*
G01X-795150Y260000D02*
X-802150D01*
Y275000D01*
X-795150D01*
G01X-797950Y267750D02*
X-802150D01*
G01X-775500Y275000D02*
X-773050Y260000D01*
X-770250Y275000D01*
X-767450Y260000D01*
X-765000Y275000D01*
G01X-758150D02*
X-753950D01*
G01X-756050D02*
Y260000D01*
G01X-758150D02*
X-753950D01*
G01X-741850Y275000D02*
Y260000D01*
G01X-745875Y275000D02*
X-737825D01*
G01X-731325Y260000D02*
Y275000D01*
G01X-723975D02*
Y260000D01*
G01Y267500D02*
X-731325D01*
G01X-715550Y275000D02*
X-711350D01*
G01X-713450D02*
Y260000D01*
G01X-715550D02*
X-711350D01*
G01X-703275D02*
Y275000D01*
X-695225Y260000D01*
Y275000D01*
G01X-1632600Y308750D02*
X-1633650Y309500D01*
X-1634875Y310000D01*
X-1636275D01*
X-1637850Y309250D01*
X-1639075Y308000D01*
X-1639950Y306500D01*
X-1640650Y304000D01*
X-1640825Y301750D01*
X-1640475Y299500D01*
X-1639950Y298000D01*
X-1638900Y296500D01*
X-1637675Y295500D01*
X-1636450Y295000D01*
X-1635225D01*
X-1634000Y295500D01*
X-1632950Y296250D01*
X-1632075Y297250D01*
G01X-1622250Y295000D02*
X-1623650Y295250D01*
X-1624875Y296250D01*
X-1625925Y297750D01*
X-1626625Y299500D01*
X-1626975Y301500D01*
Y303500D01*
X-1626625Y305500D01*
X-1625925Y307250D01*
X-1624875Y308750D01*
X-1623650Y309750D01*
X-1622250Y310000D01*
X-1620850Y309750D01*
X-1619625Y308750D01*
X-1618575Y307250D01*
X-1617875Y305500D01*
X-1617525Y303500D01*
Y301500D01*
X-1617875Y299500D01*
X-1618575Y297750D01*
X-1619625Y296250D01*
X-1620850Y295250D01*
X-1622250Y295000D01*
G01X-1612600D02*
Y310000D01*
X-1608050Y297500D01*
X-1603500Y310000D01*
Y295000D01*
G01X-1597350D02*
Y310000D01*
X-1593150D01*
X-1591750Y309250D01*
X-1590700Y307500D01*
X-1590350Y305500D01*
X-1590700Y303500D01*
X-1591575Y302000D01*
X-1593150Y301250D01*
X-1597350D01*
G01X-1576150Y295000D02*
X-1583150D01*
Y310000D01*
X-1576150D01*
G01X-1578950Y302750D02*
X-1583150D01*
G01X-1569475Y295000D02*
Y310000D01*
X-1561425Y295000D01*
Y310000D01*
G01X-1554925Y297000D02*
X-1553525Y295750D01*
X-1551950Y295000D01*
X-1550550D01*
X-1549150Y295750D01*
X-1548100Y297000D01*
X-1547575Y298750D01*
X-1547925Y300500D01*
X-1548800Y302000D01*
X-1550375Y303000D01*
X-1552475Y303500D01*
X-1553700Y304500D01*
X-1554225Y306250D01*
X-1553875Y308000D01*
X-1553000Y309250D01*
X-1551775Y310000D01*
X-1550550D01*
X-1549325Y309500D01*
X-1548275Y308250D01*
G01X-1541425Y295000D02*
X-1537050Y310000D01*
X-1532675Y295000D01*
G01X-1534250Y300250D02*
X-1539850D01*
G01X-1522850Y310000D02*
Y295000D01*
G01X-1526875Y310000D02*
X-1518825D01*
G01X-1505150Y295000D02*
X-1512150D01*
Y310000D01*
X-1505150D01*
G01X-1507950Y302750D02*
X-1512150D01*
G01X-1483575Y295000D02*
Y310000D01*
X-1476925D01*
G01X-1479375Y302750D02*
X-1483575D01*
G01X-1466050Y295000D02*
X-1467450Y295250D01*
X-1468675Y296250D01*
X-1469725Y297750D01*
X-1470425Y299500D01*
X-1470775Y301500D01*
Y303500D01*
X-1470425Y305500D01*
X-1469725Y307250D01*
X-1468675Y308750D01*
X-1467450Y309750D01*
X-1466050Y310000D01*
X-1464650Y309750D01*
X-1463425Y308750D01*
X-1462375Y307250D01*
X-1461675Y305500D01*
X-1461325Y303500D01*
Y301500D01*
X-1461675Y299500D01*
X-1462375Y297750D01*
X-1463425Y296250D01*
X-1464650Y295250D01*
X-1466050Y295000D01*
G01X-1455350D02*
Y310000D01*
X-1450975D01*
X-1449575Y309250D01*
X-1448700Y308250D01*
X-1448350Y306250D01*
X-1448700Y304250D01*
X-1449750Y303000D01*
X-1450975Y302250D01*
X-1455350D01*
G01X-1450975D02*
X-1448350Y295000D01*
G01X-1419950D02*
X-1426950D01*
Y310000D01*
X-1419950D01*
G01X-1422750Y302750D02*
X-1426950D01*
G01X-1409250Y310000D02*
Y295000D01*
G01X-1413275Y310000D02*
X-1405225D01*
G01X-1391200Y308750D02*
X-1392250Y309500D01*
X-1393475Y310000D01*
X-1394875D01*
X-1396450Y309250D01*
X-1397675Y308000D01*
X-1398550Y306500D01*
X-1399250Y304000D01*
X-1399425Y301750D01*
X-1399075Y299500D01*
X-1398550Y298000D01*
X-1397500Y296500D01*
X-1396275Y295500D01*
X-1395050Y295000D01*
X-1393825D01*
X-1392600Y295500D01*
X-1391550Y296250D01*
X-1390675Y297250D01*
G01X-1384525Y295000D02*
Y310000D01*
G01X-1377175D02*
Y295000D01*
G01Y302500D02*
X-1384525D01*
G01X-1355950Y295000D02*
Y310000D01*
X-1351750D01*
X-1350350Y309250D01*
X-1349300Y307500D01*
X-1348950Y305500D01*
X-1349300Y303500D01*
X-1350175Y302000D01*
X-1351750Y301250D01*
X-1355950D01*
G01X-1341750Y295000D02*
Y310000D01*
X-1337375D01*
X-1335975Y309250D01*
X-1335100Y308250D01*
X-1334750Y306250D01*
X-1335100Y304250D01*
X-1336150Y303000D01*
X-1337375Y302250D01*
X-1341750D01*
G01X-1337375D02*
X-1334750Y295000D01*
G01X-1324050D02*
X-1325450Y295250D01*
X-1326675Y296250D01*
X-1327725Y297750D01*
X-1328425Y299500D01*
X-1328775Y301500D01*
Y303500D01*
X-1328425Y305500D01*
X-1327725Y307250D01*
X-1326675Y308750D01*
X-1325450Y309750D01*
X-1324050Y310000D01*
X-1322650Y309750D01*
X-1321425Y308750D01*
X-1320375Y307250D01*
X-1319675Y305500D01*
X-1319325Y303500D01*
Y301500D01*
X-1319675Y299500D01*
X-1320375Y297750D01*
X-1321425Y296250D01*
X-1322650Y295250D01*
X-1324050Y295000D01*
G01X-1306000Y308750D02*
X-1307050Y309500D01*
X-1308275Y310000D01*
X-1309675D01*
X-1311250Y309250D01*
X-1312475Y308000D01*
X-1313350Y306500D01*
X-1314050Y304000D01*
X-1314225Y301750D01*
X-1313875Y299500D01*
X-1313350Y298000D01*
X-1312300Y296500D01*
X-1311075Y295500D01*
X-1309850Y295000D01*
X-1308625D01*
X-1307400Y295500D01*
X-1306350Y296250D01*
X-1305475Y297250D01*
G01X-1292150Y295000D02*
X-1299150D01*
Y310000D01*
X-1292150D01*
G01X-1294950Y302750D02*
X-1299150D01*
G01X-1285125Y297000D02*
X-1283725Y295750D01*
X-1282150Y295000D01*
X-1280750D01*
X-1279350Y295750D01*
X-1278300Y297000D01*
X-1277775Y298750D01*
X-1278125Y300500D01*
X-1279000Y302000D01*
X-1280575Y303000D01*
X-1282675Y303500D01*
X-1283900Y304500D01*
X-1284425Y306250D01*
X-1284075Y308000D01*
X-1283200Y309250D01*
X-1281975Y310000D01*
X-1280750D01*
X-1279525Y309500D01*
X-1278475Y308250D01*
G01X-1270925Y297000D02*
X-1269525Y295750D01*
X-1267950Y295000D01*
X-1266550D01*
X-1265150Y295750D01*
X-1264100Y297000D01*
X-1263575Y298750D01*
X-1263925Y300500D01*
X-1264800Y302000D01*
X-1266375Y303000D01*
X-1268475Y303500D01*
X-1269700Y304500D01*
X-1270225Y306250D01*
X-1269875Y308000D01*
X-1269000Y309250D01*
X-1267775Y310000D01*
X-1266550D01*
X-1265325Y309500D01*
X-1264275Y308250D01*
G01X-1253050Y294500D02*
X-1253400Y294750D01*
Y295250D01*
X-1253050Y295500D01*
X-1252700Y295250D01*
Y294750D01*
X-1253050Y294500D01*
G01X-1228675Y295000D02*
Y310000D01*
X-1220625Y295000D01*
Y310000D01*
G01X-1210450Y295000D02*
X-1211850Y295250D01*
X-1213075Y296250D01*
X-1214125Y297750D01*
X-1214825Y299500D01*
X-1215175Y301500D01*
Y303500D01*
X-1214825Y305500D01*
X-1214125Y307250D01*
X-1213075Y308750D01*
X-1211850Y309750D01*
X-1210450Y310000D01*
X-1209050Y309750D01*
X-1207825Y308750D01*
X-1206775Y307250D01*
X-1206075Y305500D01*
X-1205725Y303500D01*
Y301500D01*
X-1206075Y299500D01*
X-1206775Y297750D01*
X-1207825Y296250D01*
X-1209050Y295250D01*
X-1210450Y295000D01*
G01X-1196250Y310000D02*
Y295000D01*
G01X-1200275Y310000D02*
X-1192225D01*
G01X-1178550Y295000D02*
X-1185550D01*
Y310000D01*
X-1178550D01*
G01X-1181350Y302750D02*
X-1185550D01*
G01X-1167850Y294500D02*
X-1168200Y294750D01*
Y295250D01*
X-1167850Y295500D01*
X-1167500Y295250D01*
Y294750D01*
X-1167850Y294500D01*
G01Y301250D02*
X-1168200Y301500D01*
Y302000D01*
X-1167850Y302250D01*
X-1167500Y302000D01*
Y301500D01*
X-1167850Y301250D01*
G01X-1139450Y310000D02*
Y295000D01*
G01X-1143475Y310000D02*
X-1135425D01*
G01X-1128925Y295000D02*
Y310000D01*
G01X-1121575D02*
Y295000D01*
G01Y302500D02*
X-1128925D01*
G01X-1113150Y310000D02*
X-1108950D01*
G01X-1111050D02*
Y295000D01*
G01X-1113150D02*
X-1108950D01*
G01X-1100525Y297000D02*
X-1099125Y295750D01*
X-1097550Y295000D01*
X-1096150D01*
X-1094750Y295750D01*
X-1093700Y297000D01*
X-1093175Y298750D01*
X-1093525Y300500D01*
X-1094400Y302000D01*
X-1095975Y303000D01*
X-1098075Y303500D01*
X-1099300Y304500D01*
X-1099825Y306250D01*
X-1099475Y308000D01*
X-1098600Y309250D01*
X-1097375Y310000D01*
X-1096150D01*
X-1094925Y309500D01*
X-1093875Y308250D01*
G01X-1072825Y295000D02*
X-1068450Y310000D01*
X-1064075Y295000D01*
G01X-1065650Y300250D02*
X-1071250D01*
G01X-1057750Y295000D02*
Y310000D01*
X-1053550D01*
X-1052150Y309250D01*
X-1051100Y307500D01*
X-1050750Y305500D01*
X-1051100Y303500D01*
X-1051975Y302000D01*
X-1053550Y301250D01*
X-1057750D01*
G01X-1043550Y295000D02*
Y310000D01*
X-1039350D01*
X-1037950Y309250D01*
X-1036900Y307500D01*
X-1036550Y305500D01*
X-1036900Y303500D01*
X-1037775Y302000D01*
X-1039350Y301250D01*
X-1043550D01*
G01X-1029350Y310000D02*
Y295000D01*
X-1022350D01*
G01X-1013750Y310000D02*
X-1009550D01*
G01X-1011650D02*
Y295000D01*
G01X-1013750D02*
X-1009550D01*
G01X-993950D02*
X-1000950D01*
Y310000D01*
X-993950D01*
G01X-996750Y302750D02*
X-1000950D01*
G01X-986925Y297000D02*
X-985525Y295750D01*
X-983950Y295000D01*
X-982550D01*
X-981150Y295750D01*
X-980100Y297000D01*
X-979575Y298750D01*
X-979925Y300500D01*
X-980800Y302000D01*
X-982375Y303000D01*
X-984475Y303500D01*
X-985700Y304500D01*
X-986225Y306250D01*
X-985875Y308000D01*
X-985000Y309250D01*
X-983775Y310000D01*
X-982550D01*
X-981325Y309500D01*
X-980275Y308250D01*
G01X-954850Y310000D02*
Y295000D01*
G01X-958875Y310000D02*
X-950825D01*
G01X-940650Y295000D02*
X-942050Y295250D01*
X-943275Y296250D01*
X-944325Y297750D01*
X-945025Y299500D01*
X-945375Y301500D01*
Y303500D01*
X-945025Y305500D01*
X-944325Y307250D01*
X-943275Y308750D01*
X-942050Y309750D01*
X-940650Y310000D01*
X-939250Y309750D01*
X-938025Y308750D01*
X-936975Y307250D01*
X-936275Y305500D01*
X-935925Y303500D01*
Y301500D01*
X-936275Y299500D01*
X-936975Y297750D01*
X-938025Y296250D01*
X-939250Y295250D01*
X-940650Y295000D01*
G01X-908750D02*
X-915750D01*
Y310000D01*
X-908750D01*
G01X-911550Y302750D02*
X-915750D01*
G01X-898050Y310000D02*
Y295000D01*
G01X-902075Y310000D02*
X-894025D01*
G01X-880000Y308750D02*
X-881050Y309500D01*
X-882275Y310000D01*
X-883675D01*
X-885250Y309250D01*
X-886475Y308000D01*
X-887350Y306500D01*
X-888050Y304000D01*
X-888225Y301750D01*
X-887875Y299500D01*
X-887350Y298000D01*
X-886300Y296500D01*
X-885075Y295500D01*
X-883850Y295000D01*
X-882625D01*
X-881400Y295500D01*
X-880350Y296250D01*
X-879475Y297250D01*
G01X-873325Y295000D02*
Y310000D01*
G01X-865975D02*
Y295000D01*
G01Y302500D02*
X-873325D01*
G01X-844925Y297000D02*
X-843525Y295750D01*
X-841950Y295000D01*
X-840550D01*
X-839150Y295750D01*
X-838100Y297000D01*
X-837575Y298750D01*
X-837925Y300500D01*
X-838800Y302000D01*
X-840375Y303000D01*
X-842475Y303500D01*
X-843700Y304500D01*
X-844225Y306250D01*
X-843875Y308000D01*
X-843000Y309250D01*
X-841775Y310000D01*
X-840550D01*
X-839325Y309500D01*
X-838275Y308250D01*
G01X-829150Y310000D02*
X-824950D01*
G01X-827050D02*
Y295000D01*
G01X-829150D02*
X-824950D01*
G01X-816175Y310000D02*
X-809525D01*
X-816175Y295000D01*
X-809525D01*
G01X-795150D02*
X-802150D01*
Y310000D01*
X-795150D01*
G01X-797950Y302750D02*
X-802150D01*
G01X-788125Y297000D02*
X-786725Y295750D01*
X-785150Y295000D01*
X-783750D01*
X-782350Y295750D01*
X-781300Y297000D01*
X-780775Y298750D01*
X-781125Y300500D01*
X-782000Y302000D01*
X-783575Y303000D01*
X-785675Y303500D01*
X-786900Y304500D01*
X-787425Y306250D01*
X-787075Y308000D01*
X-786200Y309250D01*
X-784975Y310000D01*
X-783750D01*
X-782525Y309500D01*
X-781475Y308250D01*
G01X-754650Y303000D02*
X-753950Y303750D01*
X-753425Y305000D01*
X-753075Y306750D01*
X-753425Y308250D01*
X-754125Y309250D01*
X-755350Y310000D01*
X-760075D01*
Y295000D01*
X-754300D01*
X-753075Y296000D01*
X-752375Y297500D01*
X-752025Y299250D01*
X-752375Y301000D01*
X-753425Y302500D01*
X-754650Y303000D01*
X-760075D01*
G01X-738350Y295000D02*
X-745350D01*
Y310000D01*
X-738350D01*
G01X-741150Y302750D02*
X-745350D01*
G01X-730975Y295000D02*
Y310000D01*
X-724325D01*
G01X-726775Y302750D02*
X-730975D01*
G01X-713450Y295000D02*
X-714850Y295250D01*
X-716075Y296250D01*
X-717125Y297750D01*
X-717825Y299500D01*
X-718175Y301500D01*
Y303500D01*
X-717825Y305500D01*
X-717125Y307250D01*
X-716075Y308750D01*
X-714850Y309750D01*
X-713450Y310000D01*
X-712050Y309750D01*
X-710825Y308750D01*
X-709775Y307250D01*
X-709075Y305500D01*
X-708725Y303500D01*
Y301500D01*
X-709075Y299500D01*
X-709775Y297750D01*
X-710825Y296250D01*
X-712050Y295250D01*
X-713450Y295000D01*
G01X-702750D02*
Y310000D01*
X-698375D01*
X-696975Y309250D01*
X-696100Y308250D01*
X-695750Y306250D01*
X-696100Y304250D01*
X-697150Y303000D01*
X-698375Y302250D01*
X-702750D01*
G01X-698375D02*
X-695750Y295000D01*
G01X-681550D02*
X-688550D01*
Y310000D01*
X-681550D01*
G01X-684350Y302750D02*
X-688550D01*
G01X-660325Y297000D02*
X-658925Y295750D01*
X-657350Y295000D01*
X-655950D01*
X-654550Y295750D01*
X-653500Y297000D01*
X-652975Y298750D01*
X-653325Y300500D01*
X-654200Y302000D01*
X-655775Y303000D01*
X-657875Y303500D01*
X-659100Y304500D01*
X-659625Y306250D01*
X-659275Y308000D01*
X-658400Y309250D01*
X-657175Y310000D01*
X-655950D01*
X-654725Y309500D01*
X-653675Y308250D01*
G01X-642450Y295000D02*
X-643850Y295250D01*
X-645075Y296250D01*
X-646125Y297750D01*
X-646825Y299500D01*
X-647175Y301500D01*
Y303500D01*
X-646825Y305500D01*
X-646125Y307250D01*
X-645075Y308750D01*
X-643850Y309750D01*
X-642450Y310000D01*
X-641050Y309750D01*
X-639825Y308750D01*
X-638775Y307250D01*
X-638075Y305500D01*
X-637725Y303500D01*
Y301500D01*
X-638075Y299500D01*
X-638775Y297750D01*
X-639825Y296250D01*
X-641050Y295250D01*
X-642450Y295000D01*
G01X-631750Y310000D02*
Y295000D01*
X-624750D01*
G01X-617900D02*
Y310000D01*
X-614400D01*
X-613000Y309250D01*
X-611950Y308250D01*
X-611075Y306750D01*
X-610375Y305000D01*
X-610200Y302500D01*
X-610375Y300000D01*
X-611075Y298250D01*
X-611950Y296750D01*
X-613000Y295750D01*
X-614400Y295000D01*
X-617900D01*
G01X-596350D02*
X-603350D01*
Y310000D01*
X-596350D01*
G01X-599150Y302750D02*
X-603350D01*
G01X-589150Y295000D02*
Y310000D01*
X-584775D01*
X-583375Y309250D01*
X-582500Y308250D01*
X-582150Y306250D01*
X-582500Y304250D01*
X-583550Y303000D01*
X-584775Y302250D01*
X-589150D01*
G01X-584775D02*
X-582150Y295000D01*
G01X-576000D02*
Y310000D01*
X-571450Y297500D01*
X-566900Y310000D01*
Y295000D01*
G01X-561625D02*
X-557250Y310000D01*
X-552875Y295000D01*
G01X-554450Y300250D02*
X-560050D01*
G01X-546725Y297000D02*
X-545325Y295750D01*
X-543750Y295000D01*
X-542350D01*
X-540950Y295750D01*
X-539900Y297000D01*
X-539375Y298750D01*
X-539725Y300500D01*
X-540600Y302000D01*
X-542175Y303000D01*
X-544275Y303500D01*
X-545500Y304500D01*
X-546025Y306250D01*
X-545675Y308000D01*
X-544800Y309250D01*
X-543575Y310000D01*
X-542350D01*
X-541125Y309500D01*
X-540075Y308250D01*
G01X-532700Y295000D02*
Y310000D01*
G01X-526050D02*
X-532700Y300750D01*
G01X-525000Y295000D02*
X-529725Y305000D01*
G01X-514650Y294500D02*
X-515000Y294750D01*
Y295250D01*
X-514650Y295500D01*
X-514300Y295250D01*
Y294750D01*
X-514650Y294500D01*
G01X-1639775Y325000D02*
Y340000D01*
X-1633125D01*
G01X-1635575Y332750D02*
X-1639775D01*
G01X-1622250Y325000D02*
X-1623650Y325250D01*
X-1624875Y326250D01*
X-1625925Y327750D01*
X-1626625Y329500D01*
X-1626975Y331500D01*
Y333500D01*
X-1626625Y335500D01*
X-1625925Y337250D01*
X-1624875Y338750D01*
X-1623650Y339750D01*
X-1622250Y340000D01*
X-1620850Y339750D01*
X-1619625Y338750D01*
X-1618575Y337250D01*
X-1617875Y335500D01*
X-1617525Y333500D01*
Y331500D01*
X-1617875Y329500D01*
X-1618575Y327750D01*
X-1619625Y326250D01*
X-1620850Y325250D01*
X-1622250Y325000D01*
G01X-1611550Y340000D02*
Y325000D01*
X-1604550D01*
G01X-1597350Y340000D02*
Y325000D01*
X-1590350D01*
G01X-1579650D02*
X-1581050Y325250D01*
X-1582275Y326250D01*
X-1583325Y327750D01*
X-1584025Y329500D01*
X-1584375Y331500D01*
Y333500D01*
X-1584025Y335500D01*
X-1583325Y337250D01*
X-1582275Y338750D01*
X-1581050Y339750D01*
X-1579650Y340000D01*
X-1578250Y339750D01*
X-1577025Y338750D01*
X-1575975Y337250D01*
X-1575275Y335500D01*
X-1574925Y333500D01*
Y331500D01*
X-1575275Y329500D01*
X-1575975Y327750D01*
X-1577025Y326250D01*
X-1578250Y325250D01*
X-1579650Y325000D01*
G01X-1570700Y340000D02*
X-1568250Y325000D01*
X-1565450Y340000D01*
X-1562650Y325000D01*
X-1560200Y340000D01*
G01X-1553350D02*
X-1549150D01*
G01X-1551250D02*
Y325000D01*
G01X-1553350D02*
X-1549150D01*
G01X-1541075D02*
Y340000D01*
X-1533025Y325000D01*
Y340000D01*
G01X-1521800Y332500D02*
X-1518300D01*
Y328000D01*
X-1519350Y326500D01*
X-1520575Y325500D01*
X-1522325Y325000D01*
X-1524075Y325500D01*
X-1525300Y326500D01*
X-1526350Y328000D01*
X-1527050Y329750D01*
X-1527400Y331750D01*
Y333500D01*
X-1527050Y335000D01*
X-1526350Y336750D01*
X-1525300Y338250D01*
X-1524250Y339250D01*
X-1522850Y340000D01*
X-1521625D01*
X-1520225Y339500D01*
X-1519175Y338500D01*
G01X-1494450Y340000D02*
Y325000D01*
G01X-1498475Y340000D02*
X-1490425D01*
G01X-1480250Y325000D02*
X-1481650Y325250D01*
X-1482875Y326250D01*
X-1483925Y327750D01*
X-1484625Y329500D01*
X-1484975Y331500D01*
Y333500D01*
X-1484625Y335500D01*
X-1483925Y337250D01*
X-1482875Y338750D01*
X-1481650Y339750D01*
X-1480250Y340000D01*
X-1478850Y339750D01*
X-1477625Y338750D01*
X-1476575Y337250D01*
X-1475875Y335500D01*
X-1475525Y333500D01*
Y331500D01*
X-1475875Y329500D01*
X-1476575Y327750D01*
X-1477625Y326250D01*
X-1478850Y325250D01*
X-1480250Y325000D01*
G01X-1469550Y340000D02*
Y325000D01*
X-1462550D01*
G01X-1448350D02*
X-1455350D01*
Y340000D01*
X-1448350D01*
G01X-1451150Y332750D02*
X-1455350D01*
G01X-1441150Y325000D02*
Y340000D01*
X-1436775D01*
X-1435375Y339250D01*
X-1434500Y338250D01*
X-1434150Y336250D01*
X-1434500Y334250D01*
X-1435550Y333000D01*
X-1436775Y332250D01*
X-1441150D01*
G01X-1436775D02*
X-1434150Y325000D01*
G01X-1427825D02*
X-1423450Y340000D01*
X-1419075Y325000D01*
G01X-1420650Y330250D02*
X-1426250D01*
G01X-1413275Y325000D02*
Y340000D01*
X-1405225Y325000D01*
Y340000D01*
G01X-1391200Y338750D02*
X-1392250Y339500D01*
X-1393475Y340000D01*
X-1394875D01*
X-1396450Y339250D01*
X-1397675Y338000D01*
X-1398550Y336500D01*
X-1399250Y334000D01*
X-1399425Y331750D01*
X-1399075Y329500D01*
X-1398550Y328000D01*
X-1397500Y326500D01*
X-1396275Y325500D01*
X-1395050Y325000D01*
X-1393825D01*
X-1392600Y325500D01*
X-1391550Y326250D01*
X-1390675Y327250D01*
G01X-1377350Y325000D02*
X-1384350D01*
Y340000D01*
X-1377350D01*
G01X-1380150Y332750D02*
X-1384350D01*
G01X-1367000Y322250D02*
X-1366300Y325500D01*
G01X-1340175Y330000D02*
X-1335975D01*
G01X-1338250Y333250D02*
Y326750D01*
G01X-1327200Y324500D02*
X-1320900Y340000D01*
G01X-1312125Y330000D02*
X-1307575D01*
G01X-1295650Y324500D02*
X-1296000Y324750D01*
Y325250D01*
X-1295650Y325500D01*
X-1295300Y325250D01*
Y324750D01*
X-1295650Y324500D01*
G01X-1281450Y340000D02*
X-1282850Y339500D01*
X-1283900Y338250D01*
X-1284600Y336750D01*
X-1285125Y334750D01*
X-1285300Y332500D01*
X-1285125Y330250D01*
X-1284600Y328250D01*
X-1283900Y326750D01*
X-1282850Y325500D01*
X-1281450Y325000D01*
X-1280050Y325500D01*
X-1279000Y326750D01*
X-1278300Y328250D01*
X-1277775Y330250D01*
X-1277600Y332500D01*
X-1277775Y334750D01*
X-1278300Y336750D01*
X-1279000Y338250D01*
X-1280050Y339500D01*
X-1281450Y340000D01*
G01X-1267250D02*
X-1268650Y339500D01*
X-1269700Y338250D01*
X-1270400Y336750D01*
X-1270925Y334750D01*
X-1271100Y332500D01*
X-1270925Y330250D01*
X-1270400Y328250D01*
X-1269700Y326750D01*
X-1268650Y325500D01*
X-1267250Y325000D01*
X-1265850Y325500D01*
X-1264800Y326750D01*
X-1264100Y328250D01*
X-1263575Y330250D01*
X-1263400Y332500D01*
X-1263575Y334750D01*
X-1264100Y336750D01*
X-1264800Y338250D01*
X-1265850Y339500D01*
X-1267250Y340000D01*
G01X-1253050Y325000D02*
Y340000D01*
X-1255150Y337000D01*
G01Y325000D02*
X-1250950D01*
G01X-1242700Y327250D02*
X-1241650Y326000D01*
X-1240425Y325250D01*
X-1238850Y325000D01*
X-1237275Y325500D01*
X-1236050Y326500D01*
X-1235175Y328250D01*
X-1235000Y330250D01*
X-1235350Y332250D01*
X-1236225Y333500D01*
X-1237450Y334500D01*
X-1238675Y334750D01*
X-1239900Y334500D01*
X-1241475Y333500D01*
X-1240950Y340000D01*
X-1236225D01*
G01X-1226225Y336750D02*
X-1225350Y340000D01*
G01X-1223075D02*
X-1223950Y336750D01*
G01X-1210450Y324500D02*
X-1210800Y324750D01*
Y325250D01*
X-1210450Y325500D01*
X-1210100Y325250D01*
Y324750D01*
X-1210450Y324500D01*
G01X-1185550Y325000D02*
Y340000D01*
X-1181350D01*
X-1179950Y339250D01*
X-1178900Y337500D01*
X-1178550Y335500D01*
X-1178900Y333500D01*
X-1179775Y332000D01*
X-1181350Y331250D01*
X-1185550D01*
G01X-1164000Y338750D02*
X-1165050Y339500D01*
X-1166275Y340000D01*
X-1167675D01*
X-1169250Y339250D01*
X-1170475Y338000D01*
X-1171350Y336500D01*
X-1172050Y334000D01*
X-1172225Y331750D01*
X-1171875Y329500D01*
X-1171350Y328000D01*
X-1170300Y326500D01*
X-1169075Y325500D01*
X-1167850Y325000D01*
X-1166625D01*
X-1165400Y325500D01*
X-1164350Y326250D01*
X-1163475Y327250D01*
G01X-1152250Y333000D02*
X-1151550Y333750D01*
X-1151025Y335000D01*
X-1150675Y336750D01*
X-1151025Y338250D01*
X-1151725Y339250D01*
X-1152950Y340000D01*
X-1157675D01*
Y325000D01*
X-1151900D01*
X-1150675Y326000D01*
X-1149975Y327500D01*
X-1149625Y329250D01*
X-1149975Y331000D01*
X-1151025Y332500D01*
X-1152250Y333000D01*
X-1157675D01*
G01X-1129625Y340000D02*
X-1125250Y325000D01*
X-1120875Y340000D01*
G01X-1107550Y325000D02*
X-1114550D01*
Y340000D01*
X-1107550D01*
G01X-1110350Y332750D02*
X-1114550D01*
G01X-1100875Y325000D02*
Y340000D01*
X-1092825Y325000D01*
Y340000D01*
G01X-1086500Y325000D02*
Y340000D01*
X-1083000D01*
X-1081600Y339250D01*
X-1080550Y338250D01*
X-1079675Y336750D01*
X-1078975Y335000D01*
X-1078800Y332500D01*
X-1078975Y330000D01*
X-1079675Y328250D01*
X-1080550Y326750D01*
X-1081600Y325750D01*
X-1083000Y325000D01*
X-1086500D01*
G01X-1068450D02*
X-1069850Y325250D01*
X-1071075Y326250D01*
X-1072125Y327750D01*
X-1072825Y329500D01*
X-1073175Y331500D01*
Y333500D01*
X-1072825Y335500D01*
X-1072125Y337250D01*
X-1071075Y338750D01*
X-1069850Y339750D01*
X-1068450Y340000D01*
X-1067050Y339750D01*
X-1065825Y338750D01*
X-1064775Y337250D01*
X-1064075Y335500D01*
X-1063725Y333500D01*
Y331500D01*
X-1064075Y329500D01*
X-1064775Y327750D01*
X-1065825Y326250D01*
X-1067050Y325250D01*
X-1068450Y325000D01*
G01X-1057750D02*
Y340000D01*
X-1053375D01*
X-1051975Y339250D01*
X-1051100Y338250D01*
X-1050750Y336250D01*
X-1051100Y334250D01*
X-1052150Y333000D01*
X-1053375Y332250D01*
X-1057750D01*
G01X-1053375D02*
X-1050750Y325000D01*
G01X-1025850Y340000D02*
Y325000D01*
G01X-1029875Y340000D02*
X-1021825D01*
G01X-1011650Y325000D02*
X-1013050Y325250D01*
X-1014275Y326250D01*
X-1015325Y327750D01*
X-1016025Y329500D01*
X-1016375Y331500D01*
Y333500D01*
X-1016025Y335500D01*
X-1015325Y337250D01*
X-1014275Y338750D01*
X-1013050Y339750D01*
X-1011650Y340000D01*
X-1010250Y339750D01*
X-1009025Y338750D01*
X-1007975Y337250D01*
X-1007275Y335500D01*
X-1006925Y333500D01*
Y331500D01*
X-1007275Y329500D01*
X-1007975Y327750D01*
X-1009025Y326250D01*
X-1010250Y325250D01*
X-1011650Y325000D01*
G01X-987625D02*
X-983250Y340000D01*
X-978875Y325000D01*
G01X-980450Y330250D02*
X-986050D01*
G01X-972900Y325000D02*
Y340000D01*
X-969400D01*
X-968000Y339250D01*
X-966950Y338250D01*
X-966075Y336750D01*
X-965375Y335000D01*
X-965200Y332500D01*
X-965375Y330000D01*
X-966075Y328250D01*
X-966950Y326750D01*
X-968000Y325750D01*
X-969400Y325000D01*
X-972900D01*
G01X-958350Y328000D02*
X-957475Y326500D01*
X-956425Y325500D01*
X-955200Y325000D01*
X-953800Y325500D01*
X-952750Y326500D01*
X-951700Y328000D01*
X-951350Y330000D01*
Y340000D01*
G01X-944500D02*
Y329250D01*
X-943800Y327000D01*
X-942400Y325500D01*
X-940650Y325000D01*
X-938900Y325500D01*
X-937500Y327000D01*
X-936800Y329250D01*
Y340000D01*
G01X-930125Y327000D02*
X-928725Y325750D01*
X-927150Y325000D01*
X-925750D01*
X-924350Y325750D01*
X-923300Y327000D01*
X-922775Y328750D01*
X-923125Y330500D01*
X-924000Y332000D01*
X-925575Y333000D01*
X-927675Y333500D01*
X-928900Y334500D01*
X-929425Y336250D01*
X-929075Y338000D01*
X-928200Y339250D01*
X-926975Y340000D01*
X-925750D01*
X-924525Y339500D01*
X-923475Y338250D01*
G01X-912250Y340000D02*
Y325000D01*
G01X-916275Y340000D02*
X-908225D01*
G01X-888225Y325000D02*
X-883850Y340000D01*
X-879475Y325000D01*
G01X-881050Y330250D02*
X-886650D01*
G01X-873150Y325000D02*
Y340000D01*
X-868775D01*
X-867375Y339250D01*
X-866500Y338250D01*
X-866150Y336250D01*
X-866500Y334250D01*
X-867550Y333000D01*
X-868775Y332250D01*
X-873150D01*
G01X-868775D02*
X-866150Y325000D01*
G01X-855450Y340000D02*
Y325000D01*
G01X-859475Y340000D02*
X-851425D01*
G01X-846500D02*
X-844050Y325000D01*
X-841250Y340000D01*
X-838450Y325000D01*
X-836000Y340000D01*
G01X-827050Y325000D02*
X-828450Y325250D01*
X-829675Y326250D01*
X-830725Y327750D01*
X-831425Y329500D01*
X-831775Y331500D01*
Y333500D01*
X-831425Y335500D01*
X-830725Y337250D01*
X-829675Y338750D01*
X-828450Y339750D01*
X-827050Y340000D01*
X-825650Y339750D01*
X-824425Y338750D01*
X-823375Y337250D01*
X-822675Y335500D01*
X-822325Y333500D01*
Y331500D01*
X-822675Y329500D01*
X-823375Y327750D01*
X-824425Y326250D01*
X-825650Y325250D01*
X-827050Y325000D01*
G01X-816350D02*
Y340000D01*
X-811975D01*
X-810575Y339250D01*
X-809700Y338250D01*
X-809350Y336250D01*
X-809700Y334250D01*
X-810750Y333000D01*
X-811975Y332250D01*
X-816350D01*
G01X-811975D02*
X-809350Y325000D01*
G01X-802500D02*
Y340000D01*
G01X-795850D02*
X-802500Y330750D01*
G01X-794800Y325000D02*
X-799525Y335000D01*
G01X-770250Y340000D02*
Y325000D01*
G01X-774275Y340000D02*
X-766225D01*
G01X-756050Y325000D02*
X-757450Y325250D01*
X-758675Y326250D01*
X-759725Y327750D01*
X-760425Y329500D01*
X-760775Y331500D01*
Y333500D01*
X-760425Y335500D01*
X-759725Y337250D01*
X-758675Y338750D01*
X-757450Y339750D01*
X-756050Y340000D01*
X-754650Y339750D01*
X-753425Y338750D01*
X-752375Y337250D01*
X-751675Y335500D01*
X-751325Y333500D01*
Y331500D01*
X-751675Y329500D01*
X-752375Y327750D01*
X-753425Y326250D01*
X-754650Y325250D01*
X-756050Y325000D01*
G01X-1640825Y355000D02*
X-1636450Y370000D01*
X-1632075Y355000D01*
G01X-1633650Y360250D02*
X-1639250D01*
G01X-1611375Y355000D02*
Y370000D01*
X-1604725D01*
G01X-1607175Y362750D02*
X-1611375D01*
G01X-1595950Y370000D02*
X-1591750D01*
G01X-1593850D02*
Y355000D01*
G01X-1595950D02*
X-1591750D01*
G01X-1583675D02*
Y370000D01*
X-1575625Y355000D01*
Y370000D01*
G01X-1567550D02*
X-1563350D01*
G01X-1565450D02*
Y355000D01*
G01X-1567550D02*
X-1563350D01*
G01X-1554925Y357000D02*
X-1553525Y355750D01*
X-1551950Y355000D01*
X-1550550D01*
X-1549150Y355750D01*
X-1548100Y357000D01*
X-1547575Y358750D01*
X-1547925Y360500D01*
X-1548800Y362000D01*
X-1550375Y363000D01*
X-1552475Y363500D01*
X-1553700Y364500D01*
X-1554225Y366250D01*
X-1553875Y368000D01*
X-1553000Y369250D01*
X-1551775Y370000D01*
X-1550550D01*
X-1549325Y369500D01*
X-1548275Y368250D01*
G01X-1540725Y355000D02*
Y370000D01*
G01X-1533375D02*
Y355000D01*
G01Y362500D02*
X-1540725D01*
G01X-1519350Y355000D02*
X-1526350D01*
Y370000D01*
X-1519350D01*
G01X-1522150Y362750D02*
X-1526350D01*
G01X-1512500Y355000D02*
Y370000D01*
X-1509000D01*
X-1507600Y369250D01*
X-1506550Y368250D01*
X-1505675Y366750D01*
X-1504975Y365000D01*
X-1504800Y362500D01*
X-1504975Y360000D01*
X-1505675Y358250D01*
X-1506550Y356750D01*
X-1507600Y355750D01*
X-1509000Y355000D01*
X-1512500D01*
G01X-1483750D02*
Y370000D01*
X-1479550D01*
X-1478150Y369250D01*
X-1477100Y367500D01*
X-1476750Y365500D01*
X-1477100Y363500D01*
X-1477975Y362000D01*
X-1479550Y361250D01*
X-1483750D01*
G01X-1470425Y355000D02*
X-1466050Y370000D01*
X-1461675Y355000D01*
G01X-1463250Y360250D02*
X-1468850D01*
G01X-1455700Y355000D02*
Y370000D01*
X-1452200D01*
X-1450800Y369250D01*
X-1449750Y368250D01*
X-1448875Y366750D01*
X-1448175Y365000D01*
X-1448000Y362500D01*
X-1448175Y360000D01*
X-1448875Y358250D01*
X-1449750Y356750D01*
X-1450800Y355750D01*
X-1452200Y355000D01*
X-1455700D01*
G01X-1428700Y370000D02*
X-1426250Y355000D01*
X-1423450Y370000D01*
X-1420650Y355000D01*
X-1418200Y370000D01*
G01X-1411350D02*
X-1407150D01*
G01X-1409250D02*
Y355000D01*
G01X-1411350D02*
X-1407150D01*
G01X-1398900D02*
Y370000D01*
X-1395400D01*
X-1394000Y369250D01*
X-1392950Y368250D01*
X-1392075Y366750D01*
X-1391375Y365000D01*
X-1391200Y362500D01*
X-1391375Y360000D01*
X-1392075Y358250D01*
X-1392950Y356750D01*
X-1394000Y355750D01*
X-1395400Y355000D01*
X-1398900D01*
G01X-1380850Y370000D02*
Y355000D01*
G01X-1384875Y370000D02*
X-1376825D01*
G01X-1370325Y355000D02*
Y370000D01*
G01X-1362975D02*
Y355000D01*
G01Y362500D02*
X-1370325D01*
G01X-1338250Y355000D02*
X-1339650Y355250D01*
X-1340875Y356250D01*
X-1341925Y357750D01*
X-1342625Y359500D01*
X-1342975Y361500D01*
Y363500D01*
X-1342625Y365500D01*
X-1341925Y367250D01*
X-1340875Y368750D01*
X-1339650Y369750D01*
X-1338250Y370000D01*
X-1336850Y369750D01*
X-1335625Y368750D01*
X-1334575Y367250D01*
X-1333875Y365500D01*
X-1333525Y363500D01*
Y361500D01*
X-1333875Y359500D01*
X-1334575Y357750D01*
X-1335625Y356250D01*
X-1336850Y355250D01*
X-1338250Y355000D01*
G01X-1327550D02*
Y370000D01*
X-1323175D01*
X-1321775Y369250D01*
X-1320900Y368250D01*
X-1320550Y366250D01*
X-1320900Y364250D01*
X-1321950Y363000D01*
X-1323175Y362250D01*
X-1327550D01*
G01X-1323175D02*
X-1320550Y355000D01*
G01X-1299500D02*
Y370000D01*
X-1296000D01*
X-1294600Y369250D01*
X-1293550Y368250D01*
X-1292675Y366750D01*
X-1291975Y365000D01*
X-1291800Y362500D01*
X-1291975Y360000D01*
X-1292675Y358250D01*
X-1293550Y356750D01*
X-1294600Y355750D01*
X-1296000Y355000D01*
X-1299500D01*
G01X-1283550Y370000D02*
X-1279350D01*
G01X-1281450D02*
Y355000D01*
G01X-1283550D02*
X-1279350D01*
G01X-1271625D02*
X-1267250Y370000D01*
X-1262875Y355000D01*
G01X-1264450Y360250D02*
X-1270050D01*
G01X-1257600Y355000D02*
Y370000D01*
X-1253050Y357500D01*
X-1248500Y370000D01*
Y355000D01*
G01X-1235350D02*
X-1242350D01*
Y370000D01*
X-1235350D01*
G01X-1238150Y362750D02*
X-1242350D01*
G01X-1224650Y370000D02*
Y355000D01*
G01X-1228675Y370000D02*
X-1220625D01*
G01X-1206950Y355000D02*
X-1213950D01*
Y370000D01*
X-1206950D01*
G01X-1209750Y362750D02*
X-1213950D01*
G01X-1199750Y355000D02*
Y370000D01*
X-1195375D01*
X-1193975Y369250D01*
X-1193100Y368250D01*
X-1192750Y366250D01*
X-1193100Y364250D01*
X-1194150Y363000D01*
X-1195375Y362250D01*
X-1199750D01*
G01X-1195375D02*
X-1192750Y355000D01*
G01X-1171350Y370000D02*
Y355000D01*
X-1164350D01*
G01X-1150150D02*
X-1157150D01*
Y370000D01*
X-1150150D01*
G01X-1152950Y362750D02*
X-1157150D01*
G01X-1143125Y357000D02*
X-1141725Y355750D01*
X-1140150Y355000D01*
X-1138750D01*
X-1137350Y355750D01*
X-1136300Y357000D01*
X-1135775Y358750D01*
X-1136125Y360500D01*
X-1137000Y362000D01*
X-1138575Y363000D01*
X-1140675Y363500D01*
X-1141900Y364500D01*
X-1142425Y366250D01*
X-1142075Y368000D01*
X-1141200Y369250D01*
X-1139975Y370000D01*
X-1138750D01*
X-1137525Y369500D01*
X-1136475Y368250D01*
G01X-1128925Y357000D02*
X-1127525Y355750D01*
X-1125950Y355000D01*
X-1124550D01*
X-1123150Y355750D01*
X-1122100Y357000D01*
X-1121575Y358750D01*
X-1121925Y360500D01*
X-1122800Y362000D01*
X-1124375Y363000D01*
X-1126475Y363500D01*
X-1127700Y364500D01*
X-1128225Y366250D01*
X-1127875Y368000D01*
X-1127000Y369250D01*
X-1125775Y370000D01*
X-1124550D01*
X-1123325Y369500D01*
X-1122275Y368250D01*
G01X-1096850Y370000D02*
Y355000D01*
G01X-1100875Y370000D02*
X-1092825D01*
G01X-1086325Y355000D02*
Y370000D01*
G01X-1078975D02*
Y355000D01*
G01Y362500D02*
X-1086325D01*
G01X-1072825Y355000D02*
X-1068450Y370000D01*
X-1064075Y355000D01*
G01X-1065650Y360250D02*
X-1071250D01*
G01X-1058275Y355000D02*
Y370000D01*
X-1050225Y355000D01*
Y370000D01*
G01X-1025850Y355000D02*
X-1027250Y355250D01*
X-1028475Y356250D01*
X-1029525Y357750D01*
X-1030225Y359500D01*
X-1030575Y361500D01*
Y363500D01*
X-1030225Y365500D01*
X-1029525Y367250D01*
X-1028475Y368750D01*
X-1027250Y369750D01*
X-1025850Y370000D01*
X-1024450Y369750D01*
X-1023225Y368750D01*
X-1022175Y367250D01*
X-1021475Y365500D01*
X-1021125Y363500D01*
Y361500D01*
X-1021475Y359500D01*
X-1022175Y357750D01*
X-1023225Y356250D01*
X-1024450Y355250D01*
X-1025850Y355000D01*
G01X-1015150D02*
Y370000D01*
X-1010775D01*
X-1009375Y369250D01*
X-1008500Y368250D01*
X-1008150Y366250D01*
X-1008500Y364250D01*
X-1009550Y363000D01*
X-1010775Y362250D01*
X-1015150D01*
G01X-1010775D02*
X-1008150Y355000D01*
G01X-979750D02*
X-986750D01*
Y370000D01*
X-979750D01*
G01X-982550Y362750D02*
X-986750D01*
G01X-969050Y355000D02*
X-970450Y355250D01*
X-971675Y356250D01*
X-972725Y357750D01*
X-973425Y359500D01*
X-973775Y361500D01*
Y363500D01*
X-973425Y365500D01*
X-972725Y367250D01*
X-971675Y368750D01*
X-970450Y369750D01*
X-969050Y370000D01*
X-967650Y369750D01*
X-966425Y368750D01*
X-965375Y367250D01*
X-964675Y365500D01*
X-964325Y363500D01*
Y361500D01*
X-964675Y359500D01*
X-965375Y357750D01*
X-966425Y356250D01*
X-967650Y355250D01*
X-969050Y355000D01*
G01X-967650Y359000D02*
X-965550Y355000D01*
G01X-958700Y370000D02*
Y359250D01*
X-958000Y357000D01*
X-956600Y355500D01*
X-954850Y355000D01*
X-953100Y355500D01*
X-951700Y357000D01*
X-951000Y359250D01*
Y370000D01*
G01X-945025Y355000D02*
X-940650Y370000D01*
X-936275Y355000D01*
G01X-937850Y360250D02*
X-943450D01*
G01X-929950Y370000D02*
Y355000D01*
X-922950D01*
G01X-898050Y370000D02*
Y355000D01*
G01X-902075Y370000D02*
X-894025D01*
G01X-883850Y355000D02*
X-885250Y355250D01*
X-886475Y356250D01*
X-887525Y357750D01*
X-888225Y359500D01*
X-888575Y361500D01*
Y363500D01*
X-888225Y365500D01*
X-887525Y367250D01*
X-886475Y368750D01*
X-885250Y369750D01*
X-883850Y370000D01*
X-882450Y369750D01*
X-881225Y368750D01*
X-880175Y367250D01*
X-879475Y365500D01*
X-879125Y363500D01*
Y361500D01*
X-879475Y359500D01*
X-880175Y357750D01*
X-881225Y356250D01*
X-882450Y355250D01*
X-883850Y355000D01*
G01X-855450Y354500D02*
X-855800Y354750D01*
Y355250D01*
X-855450Y355500D01*
X-855100Y355250D01*
Y354750D01*
X-855450Y354500D01*
G01X-841250Y370000D02*
X-842650Y369500D01*
X-843700Y368250D01*
X-844400Y366750D01*
X-844925Y364750D01*
X-845100Y362500D01*
X-844925Y360250D01*
X-844400Y358250D01*
X-843700Y356750D01*
X-842650Y355500D01*
X-841250Y355000D01*
X-839850Y355500D01*
X-838800Y356750D01*
X-838100Y358250D01*
X-837575Y360250D01*
X-837400Y362500D01*
X-837575Y364750D01*
X-838100Y366750D01*
X-838800Y368250D01*
X-839850Y369500D01*
X-841250Y370000D01*
G01X-827050Y355000D02*
Y370000D01*
X-829150Y367000D01*
G01Y355000D02*
X-824950D01*
G01X-816700Y357250D02*
X-815650Y356000D01*
X-814425Y355250D01*
X-812850Y355000D01*
X-811275Y355500D01*
X-810050Y356500D01*
X-809175Y358250D01*
X-809000Y360250D01*
X-809350Y362250D01*
X-810225Y363500D01*
X-811450Y364500D01*
X-812675Y364750D01*
X-813900Y364500D01*
X-815475Y363500D01*
X-814950Y370000D01*
X-810225D01*
G01X-800225Y366750D02*
X-799350Y370000D01*
G01X-797075D02*
X-797950Y366750D01*
G01X-774800Y355000D02*
Y370000D01*
X-770250Y357500D01*
X-765700Y370000D01*
Y355000D01*
G01X-759900Y370000D02*
Y359250D01*
X-759200Y357000D01*
X-757800Y355500D01*
X-756050Y355000D01*
X-754300Y355500D01*
X-752900Y357000D01*
X-752200Y359250D01*
Y370000D01*
G01X-745525Y357000D02*
X-744125Y355750D01*
X-742550Y355000D01*
X-741150D01*
X-739750Y355750D01*
X-738700Y357000D01*
X-738175Y358750D01*
X-738525Y360500D01*
X-739400Y362000D01*
X-740975Y363000D01*
X-743075Y363500D01*
X-744300Y364500D01*
X-744825Y366250D01*
X-744475Y368000D01*
X-743600Y369250D01*
X-742375Y370000D01*
X-741150D01*
X-739925Y369500D01*
X-738875Y368250D01*
G01X-727650Y370000D02*
Y355000D01*
G01X-731675Y370000D02*
X-723625D01*
G01X-703100D02*
Y359250D01*
X-702400Y357000D01*
X-701000Y355500D01*
X-699250Y355000D01*
X-697500Y355500D01*
X-696100Y357000D01*
X-695400Y359250D01*
Y370000D01*
G01X-688725Y357000D02*
X-687325Y355750D01*
X-685750Y355000D01*
X-684350D01*
X-682950Y355750D01*
X-681900Y357000D01*
X-681375Y358750D01*
X-681725Y360500D01*
X-682600Y362000D01*
X-684175Y363000D01*
X-686275Y363500D01*
X-687500Y364500D01*
X-688025Y366250D01*
X-687675Y368000D01*
X-686800Y369250D01*
X-685575Y370000D01*
X-684350D01*
X-683125Y369500D01*
X-682075Y368250D01*
G01X-667350Y355000D02*
X-674350D01*
Y370000D01*
X-667350D01*
G01X-670150Y362750D02*
X-674350D01*
G01X-642450Y370000D02*
Y355000D01*
G01X-646475Y370000D02*
X-638425D01*
G01X-631925Y355000D02*
Y370000D01*
G01X-624575D02*
Y355000D01*
G01Y362500D02*
X-631925D01*
G01X-610550Y355000D02*
X-617550D01*
Y370000D01*
X-610550D01*
G01X-613350Y362750D02*
X-617550D01*
G01X-1640300Y385000D02*
Y400000D01*
X-1636800D01*
X-1635400Y399250D01*
X-1634350Y398250D01*
X-1633475Y396750D01*
X-1632775Y395000D01*
X-1632600Y392500D01*
X-1632775Y390000D01*
X-1633475Y388250D01*
X-1634350Y386750D01*
X-1635400Y385750D01*
X-1636800Y385000D01*
X-1640300D01*
G01X-1624350Y400000D02*
X-1620150D01*
G01X-1622250D02*
Y385000D01*
G01X-1624350D02*
X-1620150D01*
G01X-1612600D02*
Y400000D01*
X-1608050Y387500D01*
X-1603500Y400000D01*
Y385000D01*
G01X-1590350D02*
X-1597350D01*
Y400000D01*
X-1590350D01*
G01X-1593150Y392750D02*
X-1597350D01*
G01X-1583675Y385000D02*
Y400000D01*
X-1575625Y385000D01*
Y400000D01*
G01X-1569125Y387000D02*
X-1567725Y385750D01*
X-1566150Y385000D01*
X-1564750D01*
X-1563350Y385750D01*
X-1562300Y387000D01*
X-1561775Y388750D01*
X-1562125Y390500D01*
X-1563000Y392000D01*
X-1564575Y393000D01*
X-1566675Y393500D01*
X-1567900Y394500D01*
X-1568425Y396250D01*
X-1568075Y398000D01*
X-1567200Y399250D01*
X-1565975Y400000D01*
X-1564750D01*
X-1563525Y399500D01*
X-1562475Y398250D01*
G01X-1553350Y400000D02*
X-1549150D01*
G01X-1551250D02*
Y385000D01*
G01X-1553350D02*
X-1549150D01*
G01X-1537050D02*
X-1538450Y385250D01*
X-1539675Y386250D01*
X-1540725Y387750D01*
X-1541425Y389500D01*
X-1541775Y391500D01*
Y393500D01*
X-1541425Y395500D01*
X-1540725Y397250D01*
X-1539675Y398750D01*
X-1538450Y399750D01*
X-1537050Y400000D01*
X-1535650Y399750D01*
X-1534425Y398750D01*
X-1533375Y397250D01*
X-1532675Y395500D01*
X-1532325Y393500D01*
Y391500D01*
X-1532675Y389500D01*
X-1533375Y387750D01*
X-1534425Y386250D01*
X-1535650Y385250D01*
X-1537050Y385000D01*
G01X-1526875D02*
Y400000D01*
X-1518825Y385000D01*
Y400000D01*
G01X-1499700D02*
X-1497250Y385000D01*
X-1494450Y400000D01*
X-1491650Y385000D01*
X-1489200Y400000D01*
G01X-1482350D02*
X-1478150D01*
G01X-1480250D02*
Y385000D01*
G01X-1482350D02*
X-1478150D01*
G01X-1466050Y400000D02*
Y385000D01*
G01X-1470075Y400000D02*
X-1462025D01*
G01X-1455525Y385000D02*
Y400000D01*
G01X-1448175D02*
Y385000D01*
G01Y392500D02*
X-1455525D01*
G01X-1423450Y400000D02*
Y385000D01*
G01X-1427475Y400000D02*
X-1419425D01*
G01X-1412925Y385000D02*
Y400000D01*
G01X-1405575D02*
Y385000D01*
G01Y392500D02*
X-1412925D01*
G01X-1391550Y385000D02*
X-1398550D01*
Y400000D01*
X-1391550D01*
G01X-1394350Y392750D02*
X-1398550D01*
G01X-1369975Y385000D02*
Y400000D01*
X-1363325D01*
G01X-1365775Y392750D02*
X-1369975D01*
G01X-1352450Y385000D02*
X-1353850Y385250D01*
X-1355075Y386250D01*
X-1356125Y387750D01*
X-1356825Y389500D01*
X-1357175Y391500D01*
Y393500D01*
X-1356825Y395500D01*
X-1356125Y397250D01*
X-1355075Y398750D01*
X-1353850Y399750D01*
X-1352450Y400000D01*
X-1351050Y399750D01*
X-1349825Y398750D01*
X-1348775Y397250D01*
X-1348075Y395500D01*
X-1347725Y393500D01*
Y391500D01*
X-1348075Y389500D01*
X-1348775Y387750D01*
X-1349825Y386250D01*
X-1351050Y385250D01*
X-1352450Y385000D01*
G01X-1341750Y400000D02*
Y385000D01*
X-1334750D01*
G01X-1327550Y400000D02*
Y385000D01*
X-1320550D01*
G01X-1309850D02*
X-1311250Y385250D01*
X-1312475Y386250D01*
X-1313525Y387750D01*
X-1314225Y389500D01*
X-1314575Y391500D01*
Y393500D01*
X-1314225Y395500D01*
X-1313525Y397250D01*
X-1312475Y398750D01*
X-1311250Y399750D01*
X-1309850Y400000D01*
X-1308450Y399750D01*
X-1307225Y398750D01*
X-1306175Y397250D01*
X-1305475Y395500D01*
X-1305125Y393500D01*
Y391500D01*
X-1305475Y389500D01*
X-1306175Y387750D01*
X-1307225Y386250D01*
X-1308450Y385250D01*
X-1309850Y385000D01*
G01X-1300900Y400000D02*
X-1298450Y385000D01*
X-1295650Y400000D01*
X-1292850Y385000D01*
X-1290400Y400000D01*
G01X-1283550D02*
X-1279350D01*
G01X-1281450D02*
Y385000D01*
G01X-1283550D02*
X-1279350D01*
G01X-1271275D02*
Y400000D01*
X-1263225Y385000D01*
Y400000D01*
G01X-1252000Y392500D02*
X-1248500D01*
Y388000D01*
X-1249550Y386500D01*
X-1250775Y385500D01*
X-1252525Y385000D01*
X-1254275Y385500D01*
X-1255500Y386500D01*
X-1256550Y388000D01*
X-1257250Y389750D01*
X-1257600Y391750D01*
Y393500D01*
X-1257250Y395000D01*
X-1256550Y396750D01*
X-1255500Y398250D01*
X-1254450Y399250D01*
X-1253050Y400000D01*
X-1251825D01*
X-1250425Y399500D01*
X-1249375Y398500D01*
G01X-1221150Y385000D02*
X-1228150D01*
Y400000D01*
X-1221150D01*
G01X-1223950Y392750D02*
X-1228150D01*
G01X-1214125Y385000D02*
X-1206775Y400000D01*
G01X-1214125D02*
X-1206775Y385000D01*
G01X-1192400Y398750D02*
X-1193450Y399500D01*
X-1194675Y400000D01*
X-1196075D01*
X-1197650Y399250D01*
X-1198875Y398000D01*
X-1199750Y396500D01*
X-1200450Y394000D01*
X-1200625Y391750D01*
X-1200275Y389500D01*
X-1199750Y388000D01*
X-1198700Y386500D01*
X-1197475Y385500D01*
X-1196250Y385000D01*
X-1195025D01*
X-1193800Y385500D01*
X-1192750Y386250D01*
X-1191875Y387250D01*
G01X-1178550Y385000D02*
X-1185550D01*
Y400000D01*
X-1178550D01*
G01X-1181350Y392750D02*
X-1185550D01*
G01X-1171350Y385000D02*
Y400000D01*
X-1167150D01*
X-1165750Y399250D01*
X-1164700Y397500D01*
X-1164350Y395500D01*
X-1164700Y393500D01*
X-1165575Y392000D01*
X-1167150Y391250D01*
X-1171350D01*
G01X-1153650Y400000D02*
Y385000D01*
G01X-1157675Y400000D02*
X-1149625D01*
G01X-1141550D02*
X-1137350D01*
G01X-1139450D02*
Y385000D01*
G01X-1141550D02*
X-1137350D01*
G01X-1125250D02*
X-1126650Y385250D01*
X-1127875Y386250D01*
X-1128925Y387750D01*
X-1129625Y389500D01*
X-1129975Y391500D01*
Y393500D01*
X-1129625Y395500D01*
X-1128925Y397250D01*
X-1127875Y398750D01*
X-1126650Y399750D01*
X-1125250Y400000D01*
X-1123850Y399750D01*
X-1122625Y398750D01*
X-1121575Y397250D01*
X-1120875Y395500D01*
X-1120525Y393500D01*
Y391500D01*
X-1120875Y389500D01*
X-1121575Y387750D01*
X-1122625Y386250D01*
X-1123850Y385250D01*
X-1125250Y385000D01*
G01X-1115075D02*
Y400000D01*
X-1107025Y385000D01*
Y400000D01*
G01X-1096850Y384500D02*
X-1097200Y384750D01*
Y385250D01*
X-1096850Y385500D01*
X-1096500Y385250D01*
Y384750D01*
X-1096850Y384500D01*
G01X-1072825Y385000D02*
X-1068450Y400000D01*
X-1064075Y385000D01*
G01X-1065650Y390250D02*
X-1071250D01*
G01X-1058275Y385000D02*
Y400000D01*
X-1050225Y385000D01*
Y400000D01*
G01X-1040050Y385000D02*
Y391750D01*
X-1043550Y400000D01*
G01X-1036550D02*
X-1040050Y391750D01*
G01X-1015325Y387000D02*
X-1013925Y385750D01*
X-1012350Y385000D01*
X-1010950D01*
X-1009550Y385750D01*
X-1008500Y387000D01*
X-1007975Y388750D01*
X-1008325Y390500D01*
X-1009200Y392000D01*
X-1010775Y393000D01*
X-1012875Y393500D01*
X-1014100Y394500D01*
X-1014625Y396250D01*
X-1014275Y398000D01*
X-1013400Y399250D01*
X-1012175Y400000D01*
X-1010950D01*
X-1009725Y399500D01*
X-1008675Y398250D01*
G01X-1002000Y385000D02*
Y400000D01*
X-997450Y387500D01*
X-992900Y400000D01*
Y385000D01*
G01X-983250Y400000D02*
Y385000D01*
G01X-987275Y400000D02*
X-979225D01*
G01X-958350D02*
Y385000D01*
X-951350D01*
G01X-945025D02*
X-940650Y400000D01*
X-936275Y385000D01*
G01X-937850Y390250D02*
X-943450D01*
G01X-930475Y385000D02*
Y400000D01*
X-922425Y385000D01*
Y400000D01*
G01X-916100Y385000D02*
Y400000D01*
X-912600D01*
X-911200Y399250D01*
X-910150Y398250D01*
X-909275Y396750D01*
X-908575Y395000D01*
X-908400Y392500D01*
X-908575Y390000D01*
X-909275Y388250D01*
X-910150Y386750D01*
X-911200Y385750D01*
X-912600Y385000D01*
X-916100D01*
G01X-887350D02*
Y400000D01*
X-883150D01*
X-881750Y399250D01*
X-880700Y397500D01*
X-880350Y395500D01*
X-880700Y393500D01*
X-881575Y392000D01*
X-883150Y391250D01*
X-887350D01*
G01X-874025Y385000D02*
X-869650Y400000D01*
X-865275Y385000D01*
G01X-866850Y390250D02*
X-872450D01*
G01X-855450Y400000D02*
Y385000D01*
G01X-859475Y400000D02*
X-851425D01*
G01X-841250D02*
Y385000D01*
G01X-845275Y400000D02*
X-837225D01*
G01X-823550Y385000D02*
X-830550D01*
Y400000D01*
X-823550D01*
G01X-826350Y392750D02*
X-830550D01*
G01X-816350Y385000D02*
Y400000D01*
X-811975D01*
X-810575Y399250D01*
X-809700Y398250D01*
X-809350Y396250D01*
X-809700Y394250D01*
X-810750Y393000D01*
X-811975Y392250D01*
X-816350D01*
G01X-811975D02*
X-809350Y385000D01*
G01X-802675D02*
Y400000D01*
X-794625Y385000D01*
Y400000D01*
G01X-788125Y387000D02*
X-786725Y385750D01*
X-785150Y385000D01*
X-783750D01*
X-782350Y385750D01*
X-781300Y387000D01*
X-780775Y388750D01*
X-781125Y390500D01*
X-782000Y392000D01*
X-783575Y393000D01*
X-785675Y393500D01*
X-786900Y394500D01*
X-787425Y396250D01*
X-787075Y398000D01*
X-786200Y399250D01*
X-784975Y400000D01*
X-783750D01*
X-782525Y399500D01*
X-781475Y398250D01*
G01X-756050Y400000D02*
Y385000D01*
G01X-760075Y400000D02*
X-752025D01*
G01X-745525Y385000D02*
Y400000D01*
G01X-738175D02*
Y385000D01*
G01Y392500D02*
X-745525D01*
G01X-732025Y385000D02*
X-727650Y400000D01*
X-723275Y385000D01*
G01X-724850Y390250D02*
X-730450D01*
G01X-713450Y400000D02*
Y385000D01*
G01X-717475Y400000D02*
X-709425D01*
G01X-688725Y385000D02*
Y400000D01*
G01X-681375D02*
Y385000D01*
G01Y392500D02*
X-688725D01*
G01X-675225Y385000D02*
X-670850Y400000D01*
X-666475Y385000D01*
G01X-668050Y390250D02*
X-673650D01*
G01X-661025Y400000D02*
X-656650Y385000D01*
X-652275Y400000D01*
G01X-638950Y385000D02*
X-645950D01*
Y400000D01*
X-638950D01*
G01X-641750Y392750D02*
X-645950D01*
G01X-1637325Y410000D02*
X-1639075Y412500D01*
X-1639950Y415000D01*
Y425000D01*
X-1639075Y427500D01*
X-1637325Y430000D01*
G01X-1626625Y415000D02*
X-1622250Y430000D01*
X-1617875Y415000D01*
G01X-1619450Y420250D02*
X-1625050D01*
G01X-1612075Y415000D02*
Y430000D01*
X-1604025Y415000D01*
Y430000D01*
G01X-1593850D02*
Y415000D01*
G01X-1597875Y430000D02*
X-1589825D01*
G01X-1581750D02*
X-1577550D01*
G01X-1579650D02*
Y415000D01*
G01X-1581750D02*
X-1577550D01*
G01X-1568950D02*
Y430000D01*
X-1564750D01*
X-1563350Y429250D01*
X-1562300Y427500D01*
X-1561950Y425500D01*
X-1562300Y423500D01*
X-1563175Y422000D01*
X-1564750Y421250D01*
X-1568950D01*
G01X-1555625Y415000D02*
X-1551250Y430000D01*
X-1546875Y415000D01*
G01X-1548450Y420250D02*
X-1554050D01*
G01X-1540900Y415000D02*
Y430000D01*
X-1537400D01*
X-1536000Y429250D01*
X-1534950Y428250D01*
X-1534075Y426750D01*
X-1533375Y425000D01*
X-1533200Y422500D01*
X-1533375Y420000D01*
X-1534075Y418250D01*
X-1534950Y416750D01*
X-1536000Y415750D01*
X-1537400Y415000D01*
X-1540900D01*
G01X-1526525Y417000D02*
X-1525125Y415750D01*
X-1523550Y415000D01*
X-1522150D01*
X-1520750Y415750D01*
X-1519700Y417000D01*
X-1519175Y418750D01*
X-1519525Y420500D01*
X-1520400Y422000D01*
X-1521975Y423000D01*
X-1524075Y423500D01*
X-1525300Y424500D01*
X-1525825Y426250D01*
X-1525475Y428000D01*
X-1524600Y429250D01*
X-1523375Y430000D01*
X-1522150D01*
X-1520925Y429500D01*
X-1519875Y428250D01*
G01X-1507775Y410000D02*
X-1506025Y412500D01*
X-1505150Y415000D01*
Y425000D01*
X-1506025Y427500D01*
X-1507775Y430000D01*
G01X-1484625Y415000D02*
X-1480250Y430000D01*
X-1475875Y415000D01*
G01X-1477450Y420250D02*
X-1483050D01*
G01X-1470075Y415000D02*
Y430000D01*
X-1462025Y415000D01*
Y430000D01*
G01X-1455700Y415000D02*
Y430000D01*
X-1452200D01*
X-1450800Y429250D01*
X-1449750Y428250D01*
X-1448875Y426750D01*
X-1448175Y425000D01*
X-1448000Y422500D01*
X-1448175Y420000D01*
X-1448875Y418250D01*
X-1449750Y416750D01*
X-1450800Y415750D01*
X-1452200Y415000D01*
X-1455700D01*
G01X-1427125Y417000D02*
X-1425725Y415750D01*
X-1424150Y415000D01*
X-1422750D01*
X-1421350Y415750D01*
X-1420300Y417000D01*
X-1419775Y418750D01*
X-1420125Y420500D01*
X-1421000Y422000D01*
X-1422575Y423000D01*
X-1424675Y423500D01*
X-1425900Y424500D01*
X-1426425Y426250D01*
X-1426075Y428000D01*
X-1425200Y429250D01*
X-1423975Y430000D01*
X-1422750D01*
X-1421525Y429500D01*
X-1420475Y428250D01*
G01X-1413100Y430000D02*
Y419250D01*
X-1412400Y417000D01*
X-1411000Y415500D01*
X-1409250Y415000D01*
X-1407500Y415500D01*
X-1406100Y417000D01*
X-1405400Y419250D01*
Y430000D01*
G01X-1398550Y415000D02*
Y430000D01*
X-1394175D01*
X-1392775Y429250D01*
X-1391900Y428250D01*
X-1391550Y426250D01*
X-1391900Y424250D01*
X-1392950Y423000D01*
X-1394175Y422250D01*
X-1398550D01*
G01X-1394175D02*
X-1391550Y415000D01*
G01X-1384175D02*
Y430000D01*
X-1377525D01*
G01X-1379975Y422750D02*
X-1384175D01*
G01X-1371025Y415000D02*
X-1366650Y430000D01*
X-1362275Y415000D01*
G01X-1363850Y420250D02*
X-1369450D01*
G01X-1348600Y428750D02*
X-1349650Y429500D01*
X-1350875Y430000D01*
X-1352275D01*
X-1353850Y429250D01*
X-1355075Y428000D01*
X-1355950Y426500D01*
X-1356650Y424000D01*
X-1356825Y421750D01*
X-1356475Y419500D01*
X-1355950Y418000D01*
X-1354900Y416500D01*
X-1353675Y415500D01*
X-1352450Y415000D01*
X-1351225D01*
X-1350000Y415500D01*
X-1348950Y416250D01*
X-1348075Y417250D01*
G01X-1334750Y415000D02*
X-1341750D01*
Y430000D01*
X-1334750D01*
G01X-1337550Y422750D02*
X-1341750D01*
G01X-1314400Y415000D02*
Y430000D01*
X-1309850Y417500D01*
X-1305300Y430000D01*
Y415000D01*
G01X-1295650D02*
X-1297050Y415250D01*
X-1298275Y416250D01*
X-1299325Y417750D01*
X-1300025Y419500D01*
X-1300375Y421500D01*
Y423500D01*
X-1300025Y425500D01*
X-1299325Y427250D01*
X-1298275Y428750D01*
X-1297050Y429750D01*
X-1295650Y430000D01*
X-1294250Y429750D01*
X-1293025Y428750D01*
X-1291975Y427250D01*
X-1291275Y425500D01*
X-1290925Y423500D01*
Y421500D01*
X-1291275Y419500D01*
X-1291975Y417750D01*
X-1293025Y416250D01*
X-1294250Y415250D01*
X-1295650Y415000D01*
G01X-1285300Y430000D02*
Y419250D01*
X-1284600Y417000D01*
X-1283200Y415500D01*
X-1281450Y415000D01*
X-1279700Y415500D01*
X-1278300Y417000D01*
X-1277600Y419250D01*
Y430000D01*
G01X-1271275Y415000D02*
Y430000D01*
X-1263225Y415000D01*
Y430000D01*
G01X-1253050D02*
Y415000D01*
G01X-1257075Y430000D02*
X-1249025D01*
G01X-1228150D02*
Y415000D01*
X-1221150D01*
G01X-1214825D02*
X-1210450Y430000D01*
X-1206075Y415000D01*
G01X-1207650Y420250D02*
X-1213250D01*
G01X-1200275Y415000D02*
Y430000D01*
X-1192225Y415000D01*
Y430000D01*
G01X-1185900Y415000D02*
Y430000D01*
X-1182400D01*
X-1181000Y429250D01*
X-1179950Y428250D01*
X-1179075Y426750D01*
X-1178375Y425000D01*
X-1178200Y422500D01*
X-1178375Y420000D01*
X-1179075Y418250D01*
X-1179950Y416750D01*
X-1181000Y415750D01*
X-1182400Y415000D01*
X-1185900D01*
G01X-1157150D02*
Y430000D01*
X-1152950D01*
X-1151550Y429250D01*
X-1150500Y427500D01*
X-1150150Y425500D01*
X-1150500Y423500D01*
X-1151375Y422000D01*
X-1152950Y421250D01*
X-1157150D01*
G01X-1143825Y415000D02*
X-1139450Y430000D01*
X-1135075Y415000D01*
G01X-1136650Y420250D02*
X-1142250D01*
G01X-1125250Y430000D02*
Y415000D01*
G01X-1129275Y430000D02*
X-1121225D01*
G01X-1111050D02*
Y415000D01*
G01X-1115075Y430000D02*
X-1107025D01*
G01X-1093350Y415000D02*
X-1100350D01*
Y430000D01*
X-1093350D01*
G01X-1096150Y422750D02*
X-1100350D01*
G01X-1086150Y415000D02*
Y430000D01*
X-1081775D01*
X-1080375Y429250D01*
X-1079500Y428250D01*
X-1079150Y426250D01*
X-1079500Y424250D01*
X-1080550Y423000D01*
X-1081775Y422250D01*
X-1086150D01*
G01X-1081775D02*
X-1079150Y415000D01*
G01X-1072475D02*
Y430000D01*
X-1064425Y415000D01*
Y430000D01*
G01X-1057925Y417000D02*
X-1056525Y415750D01*
X-1054950Y415000D01*
X-1053550D01*
X-1052150Y415750D01*
X-1051100Y417000D01*
X-1050575Y418750D01*
X-1050925Y420500D01*
X-1051800Y422000D01*
X-1053375Y423000D01*
X-1055475Y423500D01*
X-1056700Y424500D01*
X-1057225Y426250D01*
X-1056875Y428000D01*
X-1056000Y429250D01*
X-1054775Y430000D01*
X-1053550D01*
X-1052325Y429500D01*
X-1051275Y428250D01*
G01X-1029525Y417000D02*
X-1028125Y415750D01*
X-1026550Y415000D01*
X-1025150D01*
X-1023750Y415750D01*
X-1022700Y417000D01*
X-1022175Y418750D01*
X-1022525Y420500D01*
X-1023400Y422000D01*
X-1024975Y423000D01*
X-1027075Y423500D01*
X-1028300Y424500D01*
X-1028825Y426250D01*
X-1028475Y428000D01*
X-1027600Y429250D01*
X-1026375Y430000D01*
X-1025150D01*
X-1023925Y429500D01*
X-1022875Y428250D01*
G01X-1015325Y415000D02*
Y430000D01*
G01X-1007975D02*
Y415000D01*
G01Y422500D02*
X-1015325D01*
G01X-1001825Y415000D02*
X-997450Y430000D01*
X-993075Y415000D01*
G01X-994650Y420250D02*
X-1000250D01*
G01X-986750Y430000D02*
Y415000D01*
X-979750D01*
G01X-972550Y430000D02*
Y415000D01*
X-965550D01*
G01X-939250Y423000D02*
X-938550Y423750D01*
X-938025Y425000D01*
X-937675Y426750D01*
X-938025Y428250D01*
X-938725Y429250D01*
X-939950Y430000D01*
X-944675D01*
Y415000D01*
X-938900D01*
X-937675Y416000D01*
X-936975Y417500D01*
X-936625Y419250D01*
X-936975Y421000D01*
X-938025Y422500D01*
X-939250Y423000D01*
X-944675D01*
G01X-922950Y415000D02*
X-929950D01*
Y430000D01*
X-922950D01*
G01X-925750Y422750D02*
X-929950D01*
G01X-899975Y420000D02*
X-895775D01*
G01X-898050Y423250D02*
Y416750D01*
G01X-887000Y414500D02*
X-880700Y430000D01*
G01X-871925Y420000D02*
X-867375D01*
G01X-844575Y427500D02*
X-843525Y429000D01*
X-842300Y429750D01*
X-840900Y430000D01*
X-839150Y429500D01*
X-837925Y428250D01*
X-837575Y426750D01*
X-837750Y425250D01*
X-838450Y424000D01*
X-841950Y421500D01*
X-843525Y419750D01*
X-844575Y417250D01*
X-844925Y415000D01*
X-837575D01*
G01X-827050Y430000D02*
X-828450Y429500D01*
X-829500Y428250D01*
X-830200Y426750D01*
X-830725Y424750D01*
X-830900Y422500D01*
X-830725Y420250D01*
X-830200Y418250D01*
X-829500Y416750D01*
X-828450Y415500D01*
X-827050Y415000D01*
X-825650Y415500D01*
X-824600Y416750D01*
X-823900Y418250D01*
X-823375Y420250D01*
X-823200Y422500D01*
X-823375Y424750D01*
X-823900Y426750D01*
X-824600Y428250D01*
X-825650Y429500D01*
X-827050Y430000D01*
G01X-816000Y414500D02*
X-809700Y430000D01*
G01X-816000D02*
X-817050Y429500D01*
X-817575Y428750D01*
X-817925Y427250D01*
X-817575Y425750D01*
X-817050Y425000D01*
X-816000Y424500D01*
X-814950Y425000D01*
X-814425Y425750D01*
X-814075Y427250D01*
X-814425Y428750D01*
X-814950Y429500D01*
X-816000Y430000D01*
G01X-809700Y420000D02*
X-810750Y419500D01*
X-811275Y418750D01*
X-811625Y417250D01*
X-811275Y415750D01*
X-810750Y415000D01*
X-809700Y414500D01*
X-808650Y415000D01*
X-808125Y415750D01*
X-807775Y417250D01*
X-808125Y418750D01*
X-808650Y419500D01*
X-809700Y420000D01*
G01X-784450Y415000D02*
X-785850Y415250D01*
X-787075Y416250D01*
X-788125Y417750D01*
X-788825Y419500D01*
X-789175Y421500D01*
Y423500D01*
X-788825Y425500D01*
X-788125Y427250D01*
X-787075Y428750D01*
X-785850Y429750D01*
X-784450Y430000D01*
X-783050Y429750D01*
X-781825Y428750D01*
X-780775Y427250D01*
X-780075Y425500D01*
X-779725Y423500D01*
Y421500D01*
X-780075Y419500D01*
X-780775Y417750D01*
X-781825Y416250D01*
X-783050Y415250D01*
X-784450Y415000D01*
G01X-773575D02*
Y430000D01*
X-766925D01*
G01X-769375Y422750D02*
X-773575D01*
G01X-741850Y430000D02*
Y415000D01*
G01X-745875Y430000D02*
X-737825D01*
G01X-731325Y415000D02*
Y430000D01*
G01X-723975D02*
Y415000D01*
G01Y422500D02*
X-731325D01*
G01X-709950Y415000D02*
X-716950D01*
Y430000D01*
X-709950D01*
G01X-712750Y422750D02*
X-716950D01*
G01X-701350Y430000D02*
X-697150D01*
G01X-699250D02*
Y415000D01*
G01X-701350D02*
X-697150D01*
G01X-688550D02*
Y430000D01*
X-684175D01*
X-682775Y429250D01*
X-681900Y428250D01*
X-681550Y426250D01*
X-681900Y424250D01*
X-682950Y423000D01*
X-684175Y422250D01*
X-688550D01*
G01X-684175D02*
X-681550Y415000D01*
G01X-652800Y428750D02*
X-653850Y429500D01*
X-655075Y430000D01*
X-656475D01*
X-658050Y429250D01*
X-659275Y428000D01*
X-660150Y426500D01*
X-660850Y424000D01*
X-661025Y421750D01*
X-660675Y419500D01*
X-660150Y418000D01*
X-659100Y416500D01*
X-657875Y415500D01*
X-656650Y415000D01*
X-655425D01*
X-654200Y415500D01*
X-653150Y416250D01*
X-652275Y417250D01*
G01X-646825Y415000D02*
X-642450Y430000D01*
X-638075Y415000D01*
G01X-639650Y420250D02*
X-645250D01*
G01X-632100Y415000D02*
Y430000D01*
X-628600D01*
X-627200Y429250D01*
X-626150Y428250D01*
X-625275Y426750D01*
X-624575Y425000D01*
X-624400Y422500D01*
X-624575Y420000D01*
X-625275Y418250D01*
X-626150Y416750D01*
X-627200Y415750D01*
X-628600Y415000D01*
X-632100D01*
G01X-1693250Y445000D02*
Y460000D01*
X-1695350Y457000D01*
G01Y445000D02*
X-1691150D01*
G01X-1682900Y448000D02*
X-1681850Y446250D01*
X-1680450Y445250D01*
X-1678875Y445000D01*
X-1677475Y445250D01*
X-1676075Y446500D01*
X-1675200Y448000D01*
X-1675025Y449500D01*
X-1675375Y451250D01*
X-1676600Y452500D01*
X-1677825Y453000D01*
X-1679400D01*
G01X-1677825D02*
X-1676775Y453750D01*
X-1675900Y455000D01*
X-1675550Y456500D01*
X-1675900Y458000D01*
X-1676775Y459250D01*
X-1678350Y460000D01*
X-1679925Y459750D01*
X-1681500Y458750D01*
G01X-1664850Y444500D02*
X-1665200Y444750D01*
Y445250D01*
X-1664850Y445500D01*
X-1664500Y445250D01*
Y444750D01*
X-1664850Y444500D01*
G01X-1639775Y445000D02*
Y460000D01*
X-1633125D01*
G01X-1635575Y452750D02*
X-1639775D01*
G01X-1618750Y445000D02*
X-1625750D01*
Y460000D01*
X-1618750D01*
G01X-1621550Y452750D02*
X-1625750D01*
G01X-1612425Y445000D02*
X-1608050Y460000D01*
X-1603675Y445000D01*
G01X-1605250Y450250D02*
X-1610850D01*
G01X-1593850Y460000D02*
Y445000D01*
G01X-1597875Y460000D02*
X-1589825D01*
G01X-1583500D02*
Y449250D01*
X-1582800Y447000D01*
X-1581400Y445500D01*
X-1579650Y445000D01*
X-1577900Y445500D01*
X-1576500Y447000D01*
X-1575800Y449250D01*
Y460000D01*
G01X-1568950Y445000D02*
Y460000D01*
X-1564575D01*
X-1563175Y459250D01*
X-1562300Y458250D01*
X-1561950Y456250D01*
X-1562300Y454250D01*
X-1563350Y453000D01*
X-1564575Y452250D01*
X-1568950D01*
G01X-1564575D02*
X-1561950Y445000D01*
G01X-1547750D02*
X-1554750D01*
Y460000D01*
X-1547750D01*
G01X-1550550Y452750D02*
X-1554750D01*
G01X-1526525Y447000D02*
X-1525125Y445750D01*
X-1523550Y445000D01*
X-1522150D01*
X-1520750Y445750D01*
X-1519700Y447000D01*
X-1519175Y448750D01*
X-1519525Y450500D01*
X-1520400Y452000D01*
X-1521975Y453000D01*
X-1524075Y453500D01*
X-1525300Y454500D01*
X-1525825Y456250D01*
X-1525475Y458000D01*
X-1524600Y459250D01*
X-1523375Y460000D01*
X-1522150D01*
X-1520925Y459500D01*
X-1519875Y458250D01*
G01X-1510750Y460000D02*
X-1506550D01*
G01X-1508650D02*
Y445000D01*
G01X-1510750D02*
X-1506550D01*
G01X-1497775Y460000D02*
X-1491125D01*
X-1497775Y445000D01*
X-1491125D01*
G01X-1476750D02*
X-1483750D01*
Y460000D01*
X-1476750D01*
G01X-1479550Y452750D02*
X-1483750D01*
G01X-1451850Y460000D02*
Y445000D01*
G01X-1455875Y460000D02*
X-1447825D01*
G01X-1437650Y445000D02*
X-1439050Y445250D01*
X-1440275Y446250D01*
X-1441325Y447750D01*
X-1442025Y449500D01*
X-1442375Y451500D01*
Y453500D01*
X-1442025Y455500D01*
X-1441325Y457250D01*
X-1440275Y458750D01*
X-1439050Y459750D01*
X-1437650Y460000D01*
X-1436250Y459750D01*
X-1435025Y458750D01*
X-1433975Y457250D01*
X-1433275Y455500D01*
X-1432925Y453500D01*
Y451500D01*
X-1433275Y449500D01*
X-1433975Y447750D01*
X-1435025Y446250D01*
X-1436250Y445250D01*
X-1437650Y445000D01*
G01X-1426950Y460000D02*
Y445000D01*
X-1419950D01*
G01X-1405750D02*
X-1412750D01*
Y460000D01*
X-1405750D01*
G01X-1408550Y452750D02*
X-1412750D01*
G01X-1398550Y445000D02*
Y460000D01*
X-1394175D01*
X-1392775Y459250D01*
X-1391900Y458250D01*
X-1391550Y456250D01*
X-1391900Y454250D01*
X-1392950Y453000D01*
X-1394175Y452250D01*
X-1398550D01*
G01X-1394175D02*
X-1391550Y445000D01*
G01X-1385225D02*
X-1380850Y460000D01*
X-1376475Y445000D01*
G01X-1378050Y450250D02*
X-1383650D01*
G01X-1370675Y445000D02*
Y460000D01*
X-1362625Y445000D01*
Y460000D01*
G01X-1348600Y458750D02*
X-1349650Y459500D01*
X-1350875Y460000D01*
X-1352275D01*
X-1353850Y459250D01*
X-1355075Y458000D01*
X-1355950Y456500D01*
X-1356650Y454000D01*
X-1356825Y451750D01*
X-1356475Y449500D01*
X-1355950Y448000D01*
X-1354900Y446500D01*
X-1353675Y445500D01*
X-1352450Y445000D01*
X-1351225D01*
X-1350000Y445500D01*
X-1348950Y446250D01*
X-1348075Y447250D01*
G01X-1334750Y445000D02*
X-1341750D01*
Y460000D01*
X-1334750D01*
G01X-1337550Y452750D02*
X-1341750D01*
G01X-1324050Y444500D02*
X-1324400Y444750D01*
Y445250D01*
X-1324050Y445500D01*
X-1323700Y445250D01*
Y444750D01*
X-1324050Y444500D01*
G01Y451250D02*
X-1324400Y451500D01*
Y452000D01*
X-1324050Y452250D01*
X-1323700Y452000D01*
Y451500D01*
X-1324050Y451250D01*
G01X-1299150Y445000D02*
Y460000D01*
X-1294950D01*
X-1293550Y459250D01*
X-1292500Y457500D01*
X-1292150Y455500D01*
X-1292500Y453500D01*
X-1293375Y452000D01*
X-1294950Y451250D01*
X-1299150D01*
G01X-1284950Y460000D02*
Y445000D01*
X-1277950D01*
G01X-1271625D02*
X-1267250Y460000D01*
X-1262875Y445000D01*
G01X-1264450Y450250D02*
X-1270050D01*
G01X-1253050Y460000D02*
Y445000D01*
G01X-1257075Y460000D02*
X-1249025D01*
G01X-1235350Y445000D02*
X-1242350D01*
Y460000D01*
X-1235350D01*
G01X-1238150Y452750D02*
X-1242350D01*
G01X-1228500Y445000D02*
Y460000D01*
X-1225000D01*
X-1223600Y459250D01*
X-1222550Y458250D01*
X-1221675Y456750D01*
X-1220975Y455000D01*
X-1220800Y452500D01*
X-1220975Y450000D01*
X-1221675Y448250D01*
X-1222550Y446750D01*
X-1223600Y445750D01*
X-1225000Y445000D01*
X-1228500D01*
G01X-1196250Y460000D02*
Y445000D01*
G01X-1200275Y460000D02*
X-1192225D01*
G01X-1185725Y445000D02*
Y460000D01*
G01X-1178375D02*
Y445000D01*
G01Y452500D02*
X-1185725D01*
G01X-1171350Y445000D02*
Y460000D01*
X-1166975D01*
X-1165575Y459250D01*
X-1164700Y458250D01*
X-1164350Y456250D01*
X-1164700Y454250D01*
X-1165750Y453000D01*
X-1166975Y452250D01*
X-1171350D01*
G01X-1166975D02*
X-1164350Y445000D01*
G01X-1157500Y460000D02*
Y449250D01*
X-1156800Y447000D01*
X-1155400Y445500D01*
X-1153650Y445000D01*
X-1151900Y445500D01*
X-1150500Y447000D01*
X-1149800Y449250D01*
Y460000D01*
G01X-1128925Y445000D02*
Y460000D01*
G01X-1121575D02*
Y445000D01*
G01Y452500D02*
X-1128925D01*
G01X-1111050Y445000D02*
X-1112450Y445250D01*
X-1113675Y446250D01*
X-1114725Y447750D01*
X-1115425Y449500D01*
X-1115775Y451500D01*
Y453500D01*
X-1115425Y455500D01*
X-1114725Y457250D01*
X-1113675Y458750D01*
X-1112450Y459750D01*
X-1111050Y460000D01*
X-1109650Y459750D01*
X-1108425Y458750D01*
X-1107375Y457250D01*
X-1106675Y455500D01*
X-1106325Y453500D01*
Y451500D01*
X-1106675Y449500D01*
X-1107375Y447750D01*
X-1108425Y446250D01*
X-1109650Y445250D01*
X-1111050Y445000D01*
G01X-1100350Y460000D02*
Y445000D01*
X-1093350D01*
G01X-1079150D02*
X-1086150D01*
Y460000D01*
X-1079150D01*
G01X-1081950Y452750D02*
X-1086150D01*
G01X-1057750Y445000D02*
Y460000D01*
X-1053550D01*
X-1052150Y459250D01*
X-1051100Y457500D01*
X-1050750Y455500D01*
X-1051100Y453500D01*
X-1051975Y452000D01*
X-1053550Y451250D01*
X-1057750D01*
G01X-1044425Y445000D02*
X-1040050Y460000D01*
X-1035675Y445000D01*
G01X-1037250Y450250D02*
X-1042850D01*
G01X-1029700Y445000D02*
Y460000D01*
X-1026200D01*
X-1024800Y459250D01*
X-1023750Y458250D01*
X-1022875Y456750D01*
X-1022175Y455000D01*
X-1022000Y452500D01*
X-1022175Y450000D01*
X-1022875Y448250D01*
X-1023750Y446750D01*
X-1024800Y445750D01*
X-1026200Y445000D01*
X-1029700D01*
G01X-1015325Y447000D02*
X-1013925Y445750D01*
X-1012350Y445000D01*
X-1010950D01*
X-1009550Y445750D01*
X-1008500Y447000D01*
X-1007975Y448750D01*
X-1008325Y450500D01*
X-1009200Y452000D01*
X-1010775Y453000D01*
X-1012875Y453500D01*
X-1014100Y454500D01*
X-1014625Y456250D01*
X-1014275Y458000D01*
X-1013400Y459250D01*
X-1012175Y460000D01*
X-1010950D01*
X-1009725Y459500D01*
X-1008675Y458250D01*
G01X-997800Y442250D02*
X-997100Y445500D01*
G01X-971150Y460000D02*
X-966950D01*
G01X-969050D02*
Y445000D01*
G01X-971150D02*
X-966950D01*
G01X-958875D02*
Y460000D01*
X-950825Y445000D01*
Y460000D01*
G01X-940650D02*
Y445000D01*
G01X-944675Y460000D02*
X-936625D01*
G01X-922950Y445000D02*
X-929950D01*
Y460000D01*
X-922950D01*
G01X-925750Y452750D02*
X-929950D01*
G01X-915750Y445000D02*
Y460000D01*
X-911375D01*
X-909975Y459250D01*
X-909100Y458250D01*
X-908750Y456250D01*
X-909100Y454250D01*
X-910150Y453000D01*
X-911375Y452250D01*
X-915750D01*
G01X-911375D02*
X-908750Y445000D01*
G01X-902075D02*
Y460000D01*
X-894025Y445000D01*
Y460000D01*
G01X-888225Y445000D02*
X-883850Y460000D01*
X-879475Y445000D01*
G01X-881050Y450250D02*
X-886650D01*
G01X-873150Y460000D02*
Y445000D01*
X-866150D01*
G01X-844750D02*
Y460000D01*
X-840550D01*
X-839150Y459250D01*
X-838100Y457500D01*
X-837750Y455500D01*
X-838100Y453500D01*
X-838975Y452000D01*
X-840550Y451250D01*
X-844750D01*
G01X-830550Y460000D02*
Y445000D01*
X-823550D01*
G01X-817225D02*
X-812850Y460000D01*
X-808475Y445000D01*
G01X-810050Y450250D02*
X-815650D01*
G01X-802675Y445000D02*
Y460000D01*
X-794625Y445000D01*
Y460000D01*
G01X-780950Y445000D02*
X-787950D01*
Y460000D01*
X-780950D01*
G01X-783750Y452750D02*
X-787950D01*
G01X-752200Y458750D02*
X-753250Y459500D01*
X-754475Y460000D01*
X-755875D01*
X-757450Y459250D01*
X-758675Y458000D01*
X-759550Y456500D01*
X-760250Y454000D01*
X-760425Y451750D01*
X-760075Y449500D01*
X-759550Y448000D01*
X-758500Y446500D01*
X-757275Y445500D01*
X-756050Y445000D01*
X-754825D01*
X-753600Y445500D01*
X-752550Y446250D01*
X-751675Y447250D01*
G01X-745350Y460000D02*
Y445000D01*
X-738350D01*
G01X-724150D02*
X-731150D01*
Y460000D01*
X-724150D01*
G01X-726950Y452750D02*
X-731150D01*
G01X-717825Y445000D02*
X-713450Y460000D01*
X-709075Y445000D01*
G01X-710650Y450250D02*
X-716250D01*
G01X-702750Y445000D02*
Y460000D01*
X-698375D01*
X-696975Y459250D01*
X-696100Y458250D01*
X-695750Y456250D01*
X-696100Y454250D01*
X-697150Y453000D01*
X-698375Y452250D01*
X-702750D01*
G01X-698375D02*
X-695750Y445000D01*
G01X-689425D02*
X-685050Y460000D01*
X-680675Y445000D01*
G01X-682250Y450250D02*
X-687850D01*
G01X-674875Y445000D02*
Y460000D01*
X-666825Y445000D01*
Y460000D01*
G01X-652800Y458750D02*
X-653850Y459500D01*
X-655075Y460000D01*
X-656475D01*
X-658050Y459250D01*
X-659275Y458000D01*
X-660150Y456500D01*
X-660850Y454000D01*
X-661025Y451750D01*
X-660675Y449500D01*
X-660150Y448000D01*
X-659100Y446500D01*
X-657875Y445500D01*
X-656650Y445000D01*
X-655425D01*
X-654200Y445500D01*
X-653150Y446250D01*
X-652275Y447250D01*
G01X-638950Y445000D02*
X-645950D01*
Y460000D01*
X-638950D01*
G01X-641750Y452750D02*
X-645950D01*
G01X-631925Y447000D02*
X-630525Y445750D01*
X-628950Y445000D01*
X-627550D01*
X-626150Y445750D01*
X-625100Y447000D01*
X-624575Y448750D01*
X-624925Y450500D01*
X-625800Y452000D01*
X-627375Y453000D01*
X-629475Y453500D01*
X-630700Y454500D01*
X-631225Y456250D01*
X-630875Y458000D01*
X-630000Y459250D01*
X-628775Y460000D01*
X-627550D01*
X-626325Y459500D01*
X-625275Y458250D01*
G01X-1632950Y480000D02*
X-1639950D01*
Y495000D01*
X-1632950D01*
G01X-1635750Y487750D02*
X-1639950D01*
G01X-1622250Y495000D02*
Y480000D01*
G01X-1626275Y495000D02*
X-1618225D01*
G01X-1604200Y493750D02*
X-1605250Y494500D01*
X-1606475Y495000D01*
X-1607875D01*
X-1609450Y494250D01*
X-1610675Y493000D01*
X-1611550Y491500D01*
X-1612250Y489000D01*
X-1612425Y486750D01*
X-1612075Y484500D01*
X-1611550Y483000D01*
X-1610500Y481500D01*
X-1609275Y480500D01*
X-1608050Y480000D01*
X-1606825D01*
X-1605600Y480500D01*
X-1604550Y481250D01*
X-1603675Y482250D01*
G01X-1597525Y480000D02*
Y495000D01*
G01X-1590175D02*
Y480000D01*
G01Y487500D02*
X-1597525D01*
G01X-1565450Y480000D02*
X-1566850Y480250D01*
X-1568075Y481250D01*
X-1569125Y482750D01*
X-1569825Y484500D01*
X-1570175Y486500D01*
Y488500D01*
X-1569825Y490500D01*
X-1569125Y492250D01*
X-1568075Y493750D01*
X-1566850Y494750D01*
X-1565450Y495000D01*
X-1564050Y494750D01*
X-1562825Y493750D01*
X-1561775Y492250D01*
X-1561075Y490500D01*
X-1560725Y488500D01*
Y486500D01*
X-1561075Y484500D01*
X-1561775Y482750D01*
X-1562825Y481250D01*
X-1564050Y480250D01*
X-1565450Y480000D01*
G01X-1555275D02*
Y495000D01*
X-1547225Y480000D01*
Y495000D01*
G01X-1526525Y482000D02*
X-1525125Y480750D01*
X-1523550Y480000D01*
X-1522150D01*
X-1520750Y480750D01*
X-1519700Y482000D01*
X-1519175Y483750D01*
X-1519525Y485500D01*
X-1520400Y487000D01*
X-1521975Y488000D01*
X-1524075Y488500D01*
X-1525300Y489500D01*
X-1525825Y491250D01*
X-1525475Y493000D01*
X-1524600Y494250D01*
X-1523375Y495000D01*
X-1522150D01*
X-1520925Y494500D01*
X-1519875Y493250D01*
G01X-1505150Y480000D02*
X-1512150D01*
Y495000D01*
X-1505150D01*
G01X-1507950Y487750D02*
X-1512150D01*
G01X-1490600Y493750D02*
X-1491650Y494500D01*
X-1492875Y495000D01*
X-1494275D01*
X-1495850Y494250D01*
X-1497075Y493000D01*
X-1497950Y491500D01*
X-1498650Y489000D01*
X-1498825Y486750D01*
X-1498475Y484500D01*
X-1497950Y483000D01*
X-1496900Y481500D01*
X-1495675Y480500D01*
X-1494450Y480000D01*
X-1493225D01*
X-1492000Y480500D01*
X-1490950Y481250D01*
X-1490075Y482250D01*
G01X-1480250Y480000D02*
X-1481650Y480250D01*
X-1482875Y481250D01*
X-1483925Y482750D01*
X-1484625Y484500D01*
X-1484975Y486500D01*
Y488500D01*
X-1484625Y490500D01*
X-1483925Y492250D01*
X-1482875Y493750D01*
X-1481650Y494750D01*
X-1480250Y495000D01*
X-1478850Y494750D01*
X-1477625Y493750D01*
X-1476575Y492250D01*
X-1475875Y490500D01*
X-1475525Y488500D01*
Y486500D01*
X-1475875Y484500D01*
X-1476575Y482750D01*
X-1477625Y481250D01*
X-1478850Y480250D01*
X-1480250Y480000D01*
G01X-1470075D02*
Y495000D01*
X-1462025Y480000D01*
Y495000D01*
G01X-1455700Y480000D02*
Y495000D01*
X-1452200D01*
X-1450800Y494250D01*
X-1449750Y493250D01*
X-1448875Y491750D01*
X-1448175Y490000D01*
X-1448000Y487500D01*
X-1448175Y485000D01*
X-1448875Y483250D01*
X-1449750Y481750D01*
X-1450800Y480750D01*
X-1452200Y480000D01*
X-1455700D01*
G01X-1442025D02*
X-1437650Y495000D01*
X-1433275Y480000D01*
G01X-1434850Y485250D02*
X-1440450D01*
G01X-1426950Y480000D02*
Y495000D01*
X-1422575D01*
X-1421175Y494250D01*
X-1420300Y493250D01*
X-1419950Y491250D01*
X-1420300Y489250D01*
X-1421350Y488000D01*
X-1422575Y487250D01*
X-1426950D01*
G01X-1422575D02*
X-1419950Y480000D01*
G01X-1409250D02*
Y486750D01*
X-1412750Y495000D01*
G01X-1405750D02*
X-1409250Y486750D01*
G01X-1381725Y475000D02*
X-1383475Y477500D01*
X-1384350Y480000D01*
Y490000D01*
X-1383475Y492500D01*
X-1381725Y495000D01*
G01X-1365250Y488000D02*
X-1364550Y488750D01*
X-1364025Y490000D01*
X-1363675Y491750D01*
X-1364025Y493250D01*
X-1364725Y494250D01*
X-1365950Y495000D01*
X-1370675D01*
Y480000D01*
X-1364900D01*
X-1363675Y481000D01*
X-1362975Y482500D01*
X-1362625Y484250D01*
X-1362975Y486000D01*
X-1364025Y487500D01*
X-1365250Y488000D01*
X-1370675D01*
G01X-1352450Y480000D02*
X-1353850Y480250D01*
X-1355075Y481250D01*
X-1356125Y482750D01*
X-1356825Y484500D01*
X-1357175Y486500D01*
Y488500D01*
X-1356825Y490500D01*
X-1356125Y492250D01*
X-1355075Y493750D01*
X-1353850Y494750D01*
X-1352450Y495000D01*
X-1351050Y494750D01*
X-1349825Y493750D01*
X-1348775Y492250D01*
X-1348075Y490500D01*
X-1347725Y488500D01*
Y486500D01*
X-1348075Y484500D01*
X-1348775Y482750D01*
X-1349825Y481250D01*
X-1351050Y480250D01*
X-1352450Y480000D01*
G01X-1338250Y495000D02*
Y480000D01*
G01X-1342275Y495000D02*
X-1334225D01*
G01X-1324050D02*
Y480000D01*
G01X-1328075Y495000D02*
X-1320025D01*
G01X-1309850Y480000D02*
X-1311250Y480250D01*
X-1312475Y481250D01*
X-1313525Y482750D01*
X-1314225Y484500D01*
X-1314575Y486500D01*
Y488500D01*
X-1314225Y490500D01*
X-1313525Y492250D01*
X-1312475Y493750D01*
X-1311250Y494750D01*
X-1309850Y495000D01*
X-1308450Y494750D01*
X-1307225Y493750D01*
X-1306175Y492250D01*
X-1305475Y490500D01*
X-1305125Y488500D01*
Y486500D01*
X-1305475Y484500D01*
X-1306175Y482750D01*
X-1307225Y481250D01*
X-1308450Y480250D01*
X-1309850Y480000D01*
G01X-1300200D02*
Y495000D01*
X-1295650Y482500D01*
X-1291100Y495000D01*
Y480000D01*
G01X-1280575Y475000D02*
X-1278825Y477500D01*
X-1277950Y480000D01*
Y490000D01*
X-1278825Y492500D01*
X-1280575Y495000D01*
G01X-1256725Y482000D02*
X-1255325Y480750D01*
X-1253750Y480000D01*
X-1252350D01*
X-1250950Y480750D01*
X-1249900Y482000D01*
X-1249375Y483750D01*
X-1249725Y485500D01*
X-1250600Y487000D01*
X-1252175Y488000D01*
X-1254275Y488500D01*
X-1255500Y489500D01*
X-1256025Y491250D01*
X-1255675Y493000D01*
X-1254800Y494250D01*
X-1253575Y495000D01*
X-1252350D01*
X-1251125Y494500D01*
X-1250075Y493250D01*
G01X-1240950Y495000D02*
X-1236750D01*
G01X-1238850D02*
Y480000D01*
G01X-1240950D02*
X-1236750D01*
G01X-1228500D02*
Y495000D01*
X-1225000D01*
X-1223600Y494250D01*
X-1222550Y493250D01*
X-1221675Y491750D01*
X-1220975Y490000D01*
X-1220800Y487500D01*
X-1220975Y485000D01*
X-1221675Y483250D01*
X-1222550Y481750D01*
X-1223600Y480750D01*
X-1225000Y480000D01*
X-1228500D01*
G01X-1206950D02*
X-1213950D01*
Y495000D01*
X-1206950D01*
G01X-1209750Y487750D02*
X-1213950D01*
G01X-1186425Y480000D02*
X-1182050Y495000D01*
X-1177675Y480000D01*
G01X-1179250Y485250D02*
X-1184850D01*
G01X-1173100Y495000D02*
X-1170650Y480000D01*
X-1167850Y495000D01*
X-1165050Y480000D01*
X-1162600Y495000D01*
G01X-1158025Y480000D02*
X-1153650Y495000D01*
X-1149275Y480000D01*
G01X-1150850Y485250D02*
X-1156450D01*
G01X-1139450Y480000D02*
Y486750D01*
X-1142950Y495000D01*
G01X-1135950D02*
X-1139450Y486750D01*
G01X-1114375Y480000D02*
Y495000D01*
X-1107725D01*
G01X-1110175Y487750D02*
X-1114375D01*
G01X-1100350Y480000D02*
Y495000D01*
X-1095975D01*
X-1094575Y494250D01*
X-1093700Y493250D01*
X-1093350Y491250D01*
X-1093700Y489250D01*
X-1094750Y488000D01*
X-1095975Y487250D01*
X-1100350D01*
G01X-1095975D02*
X-1093350Y480000D01*
G01X-1082650D02*
X-1084050Y480250D01*
X-1085275Y481250D01*
X-1086325Y482750D01*
X-1087025Y484500D01*
X-1087375Y486500D01*
Y488500D01*
X-1087025Y490500D01*
X-1086325Y492250D01*
X-1085275Y493750D01*
X-1084050Y494750D01*
X-1082650Y495000D01*
X-1081250Y494750D01*
X-1080025Y493750D01*
X-1078975Y492250D01*
X-1078275Y490500D01*
X-1077925Y488500D01*
Y486500D01*
X-1078275Y484500D01*
X-1078975Y482750D01*
X-1080025Y481250D01*
X-1081250Y480250D01*
X-1082650Y480000D01*
G01X-1073000D02*
Y495000D01*
X-1068450Y482500D01*
X-1063900Y495000D01*
Y480000D01*
G01X-1044425D02*
X-1040050Y495000D01*
X-1035675Y480000D01*
G01X-1037250Y485250D02*
X-1042850D01*
G01X-1029350Y495000D02*
Y480000D01*
X-1022350D01*
G01X-1015150Y495000D02*
Y480000D01*
X-1008150D01*
G01X-981850Y488000D02*
X-981150Y488750D01*
X-980625Y490000D01*
X-980275Y491750D01*
X-980625Y493250D01*
X-981325Y494250D01*
X-982550Y495000D01*
X-987275D01*
Y480000D01*
X-981500D01*
X-980275Y481000D01*
X-979575Y482500D01*
X-979225Y484250D01*
X-979575Y486000D01*
X-980625Y487500D01*
X-981850Y488000D01*
X-987275D01*
G01X-969050Y480000D02*
X-970450Y480250D01*
X-971675Y481250D01*
X-972725Y482750D01*
X-973425Y484500D01*
X-973775Y486500D01*
Y488500D01*
X-973425Y490500D01*
X-972725Y492250D01*
X-971675Y493750D01*
X-970450Y494750D01*
X-969050Y495000D01*
X-967650Y494750D01*
X-966425Y493750D01*
X-965375Y492250D01*
X-964675Y490500D01*
X-964325Y488500D01*
Y486500D01*
X-964675Y484500D01*
X-965375Y482750D01*
X-966425Y481250D01*
X-967650Y480250D01*
X-969050Y480000D01*
G01X-959225D02*
X-954850Y495000D01*
X-950475Y480000D01*
G01X-952050Y485250D02*
X-957650D01*
G01X-944150Y480000D02*
Y495000D01*
X-939775D01*
X-938375Y494250D01*
X-937500Y493250D01*
X-937150Y491250D01*
X-937500Y489250D01*
X-938550Y488000D01*
X-939775Y487250D01*
X-944150D01*
G01X-939775D02*
X-937150Y480000D01*
G01X-930300D02*
Y495000D01*
X-926800D01*
X-925400Y494250D01*
X-924350Y493250D01*
X-923475Y491750D01*
X-922775Y490000D01*
X-922600Y487500D01*
X-922775Y485000D01*
X-923475Y483250D01*
X-924350Y481750D01*
X-925400Y480750D01*
X-926800Y480000D01*
X-930300D01*
G01X-901375D02*
Y495000D01*
X-894725D01*
G01X-897175Y487750D02*
X-901375D01*
G01X-880350Y480000D02*
X-887350D01*
Y495000D01*
X-880350D01*
G01X-883150Y487750D02*
X-887350D01*
G01X-874025Y480000D02*
X-869650Y495000D01*
X-865275Y480000D01*
G01X-866850Y485250D02*
X-872450D01*
G01X-855450Y495000D02*
Y480000D01*
G01X-859475Y495000D02*
X-851425D01*
G01X-845100D02*
Y484250D01*
X-844400Y482000D01*
X-843000Y480500D01*
X-841250Y480000D01*
X-839500Y480500D01*
X-838100Y482000D01*
X-837400Y484250D01*
Y495000D01*
G01X-830550Y480000D02*
Y495000D01*
X-826175D01*
X-824775Y494250D01*
X-823900Y493250D01*
X-823550Y491250D01*
X-823900Y489250D01*
X-824950Y488000D01*
X-826175Y487250D01*
X-830550D01*
G01X-826175D02*
X-823550Y480000D01*
G01X-809350D02*
X-816350D01*
Y495000D01*
X-809350D01*
G01X-812150Y487750D02*
X-816350D01*
G01X-802325Y482000D02*
X-800925Y480750D01*
X-799350Y480000D01*
X-797950D01*
X-796550Y480750D01*
X-795500Y482000D01*
X-794975Y483750D01*
X-795325Y485500D01*
X-796200Y487000D01*
X-797775Y488000D01*
X-799875Y488500D01*
X-801100Y489500D01*
X-801625Y491250D01*
X-801275Y493000D01*
X-800400Y494250D01*
X-799175Y495000D01*
X-797950D01*
X-796725Y494500D01*
X-795675Y493250D01*
G01X-784450Y479500D02*
X-784800Y479750D01*
Y480250D01*
X-784450Y480500D01*
X-784100Y480250D01*
Y479750D01*
X-784450Y479500D01*
G01X-1693250Y510000D02*
Y525000D01*
X-1695350Y522000D01*
G01Y510000D02*
X-1691150D01*
G01X-1682375Y522500D02*
X-1681325Y524000D01*
X-1680100Y524750D01*
X-1678700Y525000D01*
X-1676950Y524500D01*
X-1675725Y523250D01*
X-1675375Y521750D01*
X-1675550Y520250D01*
X-1676250Y519000D01*
X-1679750Y516500D01*
X-1681325Y514750D01*
X-1682375Y512250D01*
X-1682725Y510000D01*
X-1675375D01*
G01X-1640825Y525000D02*
X-1636450Y510000D01*
X-1632075Y525000D01*
G01X-1618750Y510000D02*
X-1625750D01*
Y525000D01*
X-1618750D01*
G01X-1621550Y517750D02*
X-1625750D01*
G01X-1612075Y510000D02*
Y525000D01*
X-1604025Y510000D01*
Y525000D01*
G01X-1597700Y510000D02*
Y525000D01*
X-1594200D01*
X-1592800Y524250D01*
X-1591750Y523250D01*
X-1590875Y521750D01*
X-1590175Y520000D01*
X-1590000Y517500D01*
X-1590175Y515000D01*
X-1590875Y513250D01*
X-1591750Y511750D01*
X-1592800Y510750D01*
X-1594200Y510000D01*
X-1597700D01*
G01X-1579650D02*
X-1581050Y510250D01*
X-1582275Y511250D01*
X-1583325Y512750D01*
X-1584025Y514500D01*
X-1584375Y516500D01*
Y518500D01*
X-1584025Y520500D01*
X-1583325Y522250D01*
X-1582275Y523750D01*
X-1581050Y524750D01*
X-1579650Y525000D01*
X-1578250Y524750D01*
X-1577025Y523750D01*
X-1575975Y522250D01*
X-1575275Y520500D01*
X-1574925Y518500D01*
Y516500D01*
X-1575275Y514500D01*
X-1575975Y512750D01*
X-1577025Y511250D01*
X-1578250Y510250D01*
X-1579650Y510000D01*
G01X-1568950D02*
Y525000D01*
X-1564575D01*
X-1563175Y524250D01*
X-1562300Y523250D01*
X-1561950Y521250D01*
X-1562300Y519250D01*
X-1563350Y518000D01*
X-1564575Y517250D01*
X-1568950D01*
G01X-1564575D02*
X-1561950Y510000D01*
G01X-1541600D02*
Y525000D01*
X-1537050Y512500D01*
X-1532500Y525000D01*
Y510000D01*
G01X-1527225D02*
X-1522850Y525000D01*
X-1518475Y510000D01*
G01X-1520050Y515250D02*
X-1525650D01*
G01X-1512150Y510000D02*
Y525000D01*
X-1507775D01*
X-1506375Y524250D01*
X-1505500Y523250D01*
X-1505150Y521250D01*
X-1505500Y519250D01*
X-1506550Y518000D01*
X-1507775Y517250D01*
X-1512150D01*
G01X-1507775D02*
X-1505150Y510000D01*
G01X-1498300D02*
Y525000D01*
G01X-1491650D02*
X-1498300Y515750D01*
G01X-1490600Y510000D02*
X-1495325Y520000D01*
G01X-1482350Y525000D02*
X-1478150D01*
G01X-1480250D02*
Y510000D01*
G01X-1482350D02*
X-1478150D01*
G01X-1470075D02*
Y525000D01*
X-1462025Y510000D01*
Y525000D01*
G01X-1450800Y517500D02*
X-1447300D01*
Y513000D01*
X-1448350Y511500D01*
X-1449575Y510500D01*
X-1451325Y510000D01*
X-1453075Y510500D01*
X-1454300Y511500D01*
X-1455350Y513000D01*
X-1456050Y514750D01*
X-1456400Y516750D01*
Y518500D01*
X-1456050Y520000D01*
X-1455350Y521750D01*
X-1454300Y523250D01*
X-1453250Y524250D01*
X-1451850Y525000D01*
X-1450625D01*
X-1449225Y524500D01*
X-1448175Y523500D01*
G01X-1437650Y509500D02*
X-1438000Y509750D01*
Y510250D01*
X-1437650Y510500D01*
X-1437300Y510250D01*
Y509750D01*
X-1437650Y509500D01*
G01Y516250D02*
X-1438000Y516500D01*
Y517000D01*
X-1437650Y517250D01*
X-1437300Y517000D01*
Y516500D01*
X-1437650Y516250D01*
G01X-1413625Y525000D02*
X-1409250Y510000D01*
X-1404875Y525000D01*
G01X-1391550Y510000D02*
X-1398550D01*
Y525000D01*
X-1391550D01*
G01X-1394350Y517750D02*
X-1398550D01*
G01X-1384875Y510000D02*
Y525000D01*
X-1376825Y510000D01*
Y525000D01*
G01X-1370500Y510000D02*
Y525000D01*
X-1367000D01*
X-1365600Y524250D01*
X-1364550Y523250D01*
X-1363675Y521750D01*
X-1362975Y520000D01*
X-1362800Y517500D01*
X-1362975Y515000D01*
X-1363675Y513250D01*
X-1364550Y511750D01*
X-1365600Y510750D01*
X-1367000Y510000D01*
X-1370500D01*
G01X-1352450D02*
X-1353850Y510250D01*
X-1355075Y511250D01*
X-1356125Y512750D01*
X-1356825Y514500D01*
X-1357175Y516500D01*
Y518500D01*
X-1356825Y520500D01*
X-1356125Y522250D01*
X-1355075Y523750D01*
X-1353850Y524750D01*
X-1352450Y525000D01*
X-1351050Y524750D01*
X-1349825Y523750D01*
X-1348775Y522250D01*
X-1348075Y520500D01*
X-1347725Y518500D01*
Y516500D01*
X-1348075Y514500D01*
X-1348775Y512750D01*
X-1349825Y511250D01*
X-1351050Y510250D01*
X-1352450Y510000D01*
G01X-1341750D02*
Y525000D01*
X-1337375D01*
X-1335975Y524250D01*
X-1335100Y523250D01*
X-1334750Y521250D01*
X-1335100Y519250D01*
X-1336150Y518000D01*
X-1337375Y517250D01*
X-1341750D01*
G01X-1337375D02*
X-1334750Y510000D01*
G01X-1313350Y525000D02*
Y510000D01*
X-1306350D01*
G01X-1295650D02*
X-1297050Y510250D01*
X-1298275Y511250D01*
X-1299325Y512750D01*
X-1300025Y514500D01*
X-1300375Y516500D01*
Y518500D01*
X-1300025Y520500D01*
X-1299325Y522250D01*
X-1298275Y523750D01*
X-1297050Y524750D01*
X-1295650Y525000D01*
X-1294250Y524750D01*
X-1293025Y523750D01*
X-1291975Y522250D01*
X-1291275Y520500D01*
X-1290925Y518500D01*
Y516500D01*
X-1291275Y514500D01*
X-1291975Y512750D01*
X-1293025Y511250D01*
X-1294250Y510250D01*
X-1295650Y510000D01*
G01X-1280400Y517500D02*
X-1276900D01*
Y513000D01*
X-1277950Y511500D01*
X-1279175Y510500D01*
X-1280925Y510000D01*
X-1282675Y510500D01*
X-1283900Y511500D01*
X-1284950Y513000D01*
X-1285650Y514750D01*
X-1286000Y516750D01*
Y518500D01*
X-1285650Y520000D01*
X-1284950Y521750D01*
X-1283900Y523250D01*
X-1282850Y524250D01*
X-1281450Y525000D01*
X-1280225D01*
X-1278825Y524500D01*
X-1277775Y523500D01*
G01X-1267250Y510000D02*
X-1268650Y510250D01*
X-1269875Y511250D01*
X-1270925Y512750D01*
X-1271625Y514500D01*
X-1271975Y516500D01*
Y518500D01*
X-1271625Y520500D01*
X-1270925Y522250D01*
X-1269875Y523750D01*
X-1268650Y524750D01*
X-1267250Y525000D01*
X-1265850Y524750D01*
X-1264625Y523750D01*
X-1263575Y522250D01*
X-1262875Y520500D01*
X-1262525Y518500D01*
Y516500D01*
X-1262875Y514500D01*
X-1263575Y512750D01*
X-1264625Y511250D01*
X-1265850Y510250D01*
X-1267250Y510000D01*
G01X-1253400Y507250D02*
X-1252700Y510500D01*
G01X-1228500Y525000D02*
Y514250D01*
X-1227800Y512000D01*
X-1226400Y510500D01*
X-1224650Y510000D01*
X-1222900Y510500D01*
X-1221500Y512000D01*
X-1220800Y514250D01*
Y525000D01*
G01X-1213950D02*
Y510000D01*
X-1206950D01*
G01X-1186600D02*
Y525000D01*
X-1182050Y512500D01*
X-1177500Y525000D01*
Y510000D01*
G01X-1172225D02*
X-1167850Y525000D01*
X-1163475Y510000D01*
G01X-1165050Y515250D02*
X-1170650D01*
G01X-1157150Y510000D02*
Y525000D01*
X-1152775D01*
X-1151375Y524250D01*
X-1150500Y523250D01*
X-1150150Y521250D01*
X-1150500Y519250D01*
X-1151550Y518000D01*
X-1152775Y517250D01*
X-1157150D01*
G01X-1152775D02*
X-1150150Y510000D01*
G01X-1143300D02*
Y525000D01*
G01X-1136650D02*
X-1143300Y515750D01*
G01X-1135600Y510000D02*
X-1140325Y520000D01*
G01X-1127350Y525000D02*
X-1123150D01*
G01X-1125250D02*
Y510000D01*
G01X-1127350D02*
X-1123150D01*
G01X-1115075D02*
Y525000D01*
X-1107025Y510000D01*
Y525000D01*
G01X-1095800Y517500D02*
X-1092300D01*
Y513000D01*
X-1093350Y511500D01*
X-1094575Y510500D01*
X-1096325Y510000D01*
X-1098075Y510500D01*
X-1099300Y511500D01*
X-1100350Y513000D01*
X-1101050Y514750D01*
X-1101400Y516750D01*
Y518500D01*
X-1101050Y520000D01*
X-1100350Y521750D01*
X-1099300Y523250D01*
X-1098250Y524250D01*
X-1096850Y525000D01*
X-1095625D01*
X-1094225Y524500D01*
X-1093175Y523500D01*
G01X-1072825Y510000D02*
X-1068450Y525000D01*
X-1064075Y510000D01*
G01X-1065650Y515250D02*
X-1071250D01*
G01X-1058275Y510000D02*
Y525000D01*
X-1050225Y510000D01*
Y525000D01*
G01X-1043900Y510000D02*
Y525000D01*
X-1040400D01*
X-1039000Y524250D01*
X-1037950Y523250D01*
X-1037075Y521750D01*
X-1036375Y520000D01*
X-1036200Y517500D01*
X-1036375Y515000D01*
X-1037075Y513250D01*
X-1037950Y511750D01*
X-1039000Y510750D01*
X-1040400Y510000D01*
X-1043900D01*
G01X-1015500D02*
Y525000D01*
X-1012000D01*
X-1010600Y524250D01*
X-1009550Y523250D01*
X-1008675Y521750D01*
X-1007975Y520000D01*
X-1007800Y517500D01*
X-1007975Y515000D01*
X-1008675Y513250D01*
X-1009550Y511750D01*
X-1010600Y510750D01*
X-1012000Y510000D01*
X-1015500D01*
G01X-1001825D02*
X-997450Y525000D01*
X-993075Y510000D01*
G01X-994650Y515250D02*
X-1000250D01*
G01X-983250Y525000D02*
Y510000D01*
G01X-987275Y525000D02*
X-979225D01*
G01X-965550Y510000D02*
X-972550D01*
Y525000D01*
X-965550D01*
G01X-968350Y517750D02*
X-972550D01*
G01X-951000Y523750D02*
X-952050Y524500D01*
X-953275Y525000D01*
X-954675D01*
X-956250Y524250D01*
X-957475Y523000D01*
X-958350Y521500D01*
X-959050Y519000D01*
X-959225Y516750D01*
X-958875Y514500D01*
X-958350Y513000D01*
X-957300Y511500D01*
X-956075Y510500D01*
X-954850Y510000D01*
X-953625D01*
X-952400Y510500D01*
X-951350Y511250D01*
X-950475Y512250D01*
G01X-940650Y510000D02*
X-942050Y510250D01*
X-943275Y511250D01*
X-944325Y512750D01*
X-945025Y514500D01*
X-945375Y516500D01*
Y518500D01*
X-945025Y520500D01*
X-944325Y522250D01*
X-943275Y523750D01*
X-942050Y524750D01*
X-940650Y525000D01*
X-939250Y524750D01*
X-938025Y523750D01*
X-936975Y522250D01*
X-936275Y520500D01*
X-935925Y518500D01*
Y516500D01*
X-936275Y514500D01*
X-936975Y512750D01*
X-938025Y511250D01*
X-939250Y510250D01*
X-940650Y510000D01*
G01X-930300D02*
Y525000D01*
X-926800D01*
X-925400Y524250D01*
X-924350Y523250D01*
X-923475Y521750D01*
X-922775Y520000D01*
X-922600Y517500D01*
X-922775Y515000D01*
X-923475Y513250D01*
X-924350Y511750D01*
X-925400Y510750D01*
X-926800Y510000D01*
X-930300D01*
G01X-908750D02*
X-915750D01*
Y525000D01*
X-908750D01*
G01X-911550Y517750D02*
X-915750D01*
G01X-884725Y505000D02*
X-886475Y507500D01*
X-887350Y510000D01*
Y520000D01*
X-886475Y522500D01*
X-884725Y525000D01*
G01X-867550Y510000D02*
Y525000D01*
X-874025Y514250D01*
X-865275D01*
G01X-859300Y510000D02*
Y525000D01*
X-855800D01*
X-854400Y524250D01*
X-853350Y523250D01*
X-852475Y521750D01*
X-851775Y520000D01*
X-851600Y517500D01*
X-851775Y515000D01*
X-852475Y513250D01*
X-853350Y511750D01*
X-854400Y510750D01*
X-855800Y510000D01*
X-859300D01*
G01X-843350Y525000D02*
X-839150D01*
G01X-841250D02*
Y510000D01*
G01X-843350D02*
X-839150D01*
G01X-826000Y517500D02*
X-822500D01*
Y513000D01*
X-823550Y511500D01*
X-824775Y510500D01*
X-826525Y510000D01*
X-828275Y510500D01*
X-829500Y511500D01*
X-830550Y513000D01*
X-831250Y514750D01*
X-831600Y516750D01*
Y518500D01*
X-831250Y520000D01*
X-830550Y521750D01*
X-829500Y523250D01*
X-828450Y524250D01*
X-827050Y525000D01*
X-825825D01*
X-824425Y524500D01*
X-823375Y523500D01*
G01X-814950Y525000D02*
X-810750D01*
G01X-812850D02*
Y510000D01*
G01X-814950D02*
X-810750D01*
G01X-798650Y525000D02*
Y510000D01*
G01X-802675Y525000D02*
X-794625D01*
G01X-775500D02*
X-773050Y510000D01*
X-770250Y525000D01*
X-767450Y510000D01*
X-765000Y525000D01*
G01X-761300D02*
X-758850Y510000D01*
X-756050Y525000D01*
X-753250Y510000D01*
X-750800Y525000D01*
G01X-741850Y510000D02*
Y516750D01*
X-745350Y525000D01*
G01X-738350D02*
X-741850Y516750D01*
G01X-727650Y510000D02*
Y516750D01*
X-731150Y525000D01*
G01X-724150D02*
X-727650Y516750D01*
G01X-712575Y505000D02*
X-710825Y507500D01*
X-709950Y510000D01*
Y520000D01*
X-710825Y522500D01*
X-712575Y525000D01*
G01X-699250D02*
Y510000D01*
G01X-703275Y525000D02*
X-695225D01*
G01X-685050Y510000D02*
X-686450Y510250D01*
X-687675Y511250D01*
X-688725Y512750D01*
X-689425Y514500D01*
X-689775Y516500D01*
Y518500D01*
X-689425Y520500D01*
X-688725Y522250D01*
X-687675Y523750D01*
X-686450Y524750D01*
X-685050Y525000D01*
X-683650Y524750D01*
X-682425Y523750D01*
X-681375Y522250D01*
X-680675Y520500D01*
X-680325Y518500D01*
Y516500D01*
X-680675Y514500D01*
X-681375Y512750D01*
X-682425Y511250D01*
X-683650Y510250D01*
X-685050Y510000D01*
G01X-655250Y518000D02*
X-654550Y518750D01*
X-654025Y520000D01*
X-653675Y521750D01*
X-654025Y523250D01*
X-654725Y524250D01*
X-655950Y525000D01*
X-660675D01*
Y510000D01*
X-654900D01*
X-653675Y511000D01*
X-652975Y512500D01*
X-652625Y514250D01*
X-652975Y516000D01*
X-654025Y517500D01*
X-655250Y518000D01*
X-660675D01*
G01X-638950Y510000D02*
X-645950D01*
Y525000D01*
X-638950D01*
G01X-641750Y517750D02*
X-645950D01*
G01X-616150Y525000D02*
X-611950D01*
G01X-614050D02*
Y510000D01*
G01X-616150D02*
X-611950D01*
G01X-603875D02*
Y525000D01*
X-595825Y510000D01*
Y525000D01*
G01X-1638550Y560000D02*
X-1634350D01*
G01X-1636450D02*
Y545000D01*
G01X-1638550D02*
X-1634350D01*
G01X-1625750D02*
Y560000D01*
X-1621550D01*
X-1620150Y559250D01*
X-1619100Y557500D01*
X-1618750Y555500D01*
X-1619100Y553500D01*
X-1619975Y552000D01*
X-1621550Y551250D01*
X-1625750D01*
G01X-1604200Y558750D02*
X-1605250Y559500D01*
X-1606475Y560000D01*
X-1607875D01*
X-1609450Y559250D01*
X-1610675Y558000D01*
X-1611550Y556500D01*
X-1612250Y554000D01*
X-1612425Y551750D01*
X-1612075Y549500D01*
X-1611550Y548000D01*
X-1610500Y546500D01*
X-1609275Y545500D01*
X-1608050Y545000D01*
X-1606825D01*
X-1605600Y545500D01*
X-1604550Y546250D01*
X-1603675Y547250D01*
G01X-1596125Y550000D02*
X-1591575D01*
G01X-1579650Y560000D02*
Y545000D01*
G01X-1583675Y560000D02*
X-1575625D01*
G01X-1570000Y545000D02*
Y560000D01*
X-1565450Y547500D01*
X-1560900Y560000D01*
Y545000D01*
G01X-1553525Y550000D02*
X-1548975D01*
G01X-1540375Y551250D02*
X-1539150Y553000D01*
X-1538100Y554000D01*
X-1536700Y554500D01*
X-1535475Y554000D01*
X-1534600Y553000D01*
X-1533900Y551500D01*
X-1533725Y549750D01*
X-1533900Y548250D01*
X-1534600Y546750D01*
X-1535650Y545500D01*
X-1536875Y545000D01*
X-1538275Y545500D01*
X-1539500Y547000D01*
X-1540200Y549250D01*
X-1540375Y551750D01*
X-1540025Y555000D01*
X-1539500Y556750D01*
X-1538625Y558500D01*
X-1537400Y559750D01*
X-1536175Y560000D01*
X-1534950Y559500D01*
X-1534075Y558250D01*
G01X-1526700Y547250D02*
X-1525650Y546000D01*
X-1524425Y545250D01*
X-1522850Y545000D01*
X-1521275Y545500D01*
X-1520050Y546500D01*
X-1519175Y548250D01*
X-1519000Y550250D01*
X-1519350Y552250D01*
X-1520225Y553500D01*
X-1521450Y554500D01*
X-1522675Y554750D01*
X-1523900Y554500D01*
X-1525475Y553500D01*
X-1524950Y560000D01*
X-1520225D01*
G01X-1508650D02*
X-1510050Y559500D01*
X-1511100Y558250D01*
X-1511800Y556750D01*
X-1512325Y554750D01*
X-1512500Y552500D01*
X-1512325Y550250D01*
X-1511800Y548250D01*
X-1511100Y546750D01*
X-1510050Y545500D01*
X-1508650Y545000D01*
X-1507250Y545500D01*
X-1506200Y546750D01*
X-1505500Y548250D01*
X-1504975Y550250D01*
X-1504800Y552500D01*
X-1504975Y554750D01*
X-1505500Y556750D01*
X-1506200Y558250D01*
X-1507250Y559500D01*
X-1508650Y560000D01*
G01X-1480250D02*
Y545000D01*
G01X-1484275Y560000D02*
X-1476225D01*
G01X-1462550Y545000D02*
X-1469550D01*
Y560000D01*
X-1462550D01*
G01X-1465350Y552750D02*
X-1469550D01*
G01X-1455525Y547000D02*
X-1454125Y545750D01*
X-1452550Y545000D01*
X-1451150D01*
X-1449750Y545750D01*
X-1448700Y547000D01*
X-1448175Y548750D01*
X-1448525Y550500D01*
X-1449400Y552000D01*
X-1450975Y553000D01*
X-1453075Y553500D01*
X-1454300Y554500D01*
X-1454825Y556250D01*
X-1454475Y558000D01*
X-1453600Y559250D01*
X-1452375Y560000D01*
X-1451150D01*
X-1449925Y559500D01*
X-1448875Y558250D01*
G01X-1437650Y560000D02*
Y545000D01*
G01X-1441675Y560000D02*
X-1433625D01*
G01X-1413800Y545000D02*
Y560000D01*
X-1409250Y547500D01*
X-1404700Y560000D01*
Y545000D01*
G01X-1391550D02*
X-1398550D01*
Y560000D01*
X-1391550D01*
G01X-1394350Y552750D02*
X-1398550D01*
G01X-1380850Y560000D02*
Y545000D01*
G01X-1384875Y560000D02*
X-1376825D01*
G01X-1370325Y545000D02*
Y560000D01*
G01X-1362975D02*
Y545000D01*
G01Y552500D02*
X-1370325D01*
G01X-1352450Y545000D02*
X-1353850Y545250D01*
X-1355075Y546250D01*
X-1356125Y547750D01*
X-1356825Y549500D01*
X-1357175Y551500D01*
Y553500D01*
X-1356825Y555500D01*
X-1356125Y557250D01*
X-1355075Y558750D01*
X-1353850Y559750D01*
X-1352450Y560000D01*
X-1351050Y559750D01*
X-1349825Y558750D01*
X-1348775Y557250D01*
X-1348075Y555500D01*
X-1347725Y553500D01*
Y551500D01*
X-1348075Y549500D01*
X-1348775Y547750D01*
X-1349825Y546250D01*
X-1351050Y545250D01*
X-1352450Y545000D01*
G01X-1342100D02*
Y560000D01*
X-1338600D01*
X-1337200Y559250D01*
X-1336150Y558250D01*
X-1335275Y556750D01*
X-1334575Y555000D01*
X-1334400Y552500D01*
X-1334575Y550000D01*
X-1335275Y548250D01*
X-1336150Y546750D01*
X-1337200Y545750D01*
X-1338600Y545000D01*
X-1342100D01*
G01X-1313175Y557500D02*
X-1312125Y559000D01*
X-1310900Y559750D01*
X-1309500Y560000D01*
X-1307750Y559500D01*
X-1306525Y558250D01*
X-1306175Y556750D01*
X-1306350Y555250D01*
X-1307050Y554000D01*
X-1310550Y551500D01*
X-1312125Y549750D01*
X-1313175Y547250D01*
X-1313525Y545000D01*
X-1306175D01*
G01X-1295650Y544500D02*
X-1296000Y544750D01*
Y545250D01*
X-1295650Y545500D01*
X-1295300Y545250D01*
Y544750D01*
X-1295650Y544500D01*
G01X-1279350Y545000D02*
Y560000D01*
X-1285825Y549250D01*
X-1277075D01*
G01X-1267250Y544500D02*
X-1267600Y544750D01*
Y545250D01*
X-1267250Y545500D01*
X-1266900Y545250D01*
Y544750D01*
X-1267250Y544500D01*
G01X-1256375Y557500D02*
X-1255325Y559000D01*
X-1254100Y559750D01*
X-1252700Y560000D01*
X-1250950Y559500D01*
X-1249725Y558250D01*
X-1249375Y556750D01*
X-1249550Y555250D01*
X-1250250Y554000D01*
X-1253750Y551500D01*
X-1255325Y549750D01*
X-1256375Y547250D01*
X-1256725Y545000D01*
X-1249375D01*
G01X-1242175Y557500D02*
X-1241125Y559000D01*
X-1239900Y559750D01*
X-1238500Y560000D01*
X-1236750Y559500D01*
X-1235525Y558250D01*
X-1235175Y556750D01*
X-1235350Y555250D01*
X-1236050Y554000D01*
X-1239550Y551500D01*
X-1241125Y549750D01*
X-1242175Y547250D01*
X-1242525Y545000D01*
X-1235175D01*
G01X-1224650Y544500D02*
X-1225000Y544750D01*
Y545250D01*
X-1224650Y545500D01*
X-1224300Y545250D01*
Y544750D01*
X-1224650Y544500D01*
G01X-1693250Y575000D02*
Y590000D01*
X-1695350Y587000D01*
G01Y575000D02*
X-1691150D01*
G01X-1679050D02*
Y590000D01*
X-1681150Y587000D01*
G01Y575000D02*
X-1676950D01*
G01X-1664850Y574500D02*
X-1665200Y574750D01*
Y575250D01*
X-1664850Y575500D01*
X-1664500Y575250D01*
Y574750D01*
X-1664850Y574500D01*
G01X-1641000Y575000D02*
Y590000D01*
X-1636450Y577500D01*
X-1631900Y590000D01*
Y575000D01*
G01X-1626625D02*
X-1622250Y590000D01*
X-1617875Y575000D01*
G01X-1619450Y580250D02*
X-1625050D01*
G01X-1611725Y575000D02*
X-1604375Y590000D01*
G01X-1611725D02*
X-1604375Y575000D01*
G01X-1595950Y590000D02*
X-1591750D01*
G01X-1593850D02*
Y575000D01*
G01X-1595950D02*
X-1591750D01*
G01X-1584200D02*
Y590000D01*
X-1579650Y577500D01*
X-1575100Y590000D01*
Y575000D01*
G01X-1569300Y590000D02*
Y579250D01*
X-1568600Y577000D01*
X-1567200Y575500D01*
X-1565450Y575000D01*
X-1563700Y575500D01*
X-1562300Y577000D01*
X-1561600Y579250D01*
Y590000D01*
G01X-1555800Y575000D02*
Y590000D01*
X-1551250Y577500D01*
X-1546700Y590000D01*
Y575000D01*
G01X-1521450Y583000D02*
X-1520750Y583750D01*
X-1520225Y585000D01*
X-1519875Y586750D01*
X-1520225Y588250D01*
X-1520925Y589250D01*
X-1522150Y590000D01*
X-1526875D01*
Y575000D01*
X-1521100D01*
X-1519875Y576000D01*
X-1519175Y577500D01*
X-1518825Y579250D01*
X-1519175Y581000D01*
X-1520225Y582500D01*
X-1521450Y583000D01*
X-1526875D01*
G01X-1508650Y575000D02*
X-1510050Y575250D01*
X-1511275Y576250D01*
X-1512325Y577750D01*
X-1513025Y579500D01*
X-1513375Y581500D01*
Y583500D01*
X-1513025Y585500D01*
X-1512325Y587250D01*
X-1511275Y588750D01*
X-1510050Y589750D01*
X-1508650Y590000D01*
X-1507250Y589750D01*
X-1506025Y588750D01*
X-1504975Y587250D01*
X-1504275Y585500D01*
X-1503925Y583500D01*
Y581500D01*
X-1504275Y579500D01*
X-1504975Y577750D01*
X-1506025Y576250D01*
X-1507250Y575250D01*
X-1508650Y575000D01*
G01X-1498825D02*
X-1494450Y590000D01*
X-1490075Y575000D01*
G01X-1491650Y580250D02*
X-1497250D01*
G01X-1483750Y575000D02*
Y590000D01*
X-1479375D01*
X-1477975Y589250D01*
X-1477100Y588250D01*
X-1476750Y586250D01*
X-1477100Y584250D01*
X-1478150Y583000D01*
X-1479375Y582250D01*
X-1483750D01*
G01X-1479375D02*
X-1476750Y575000D01*
G01X-1469900D02*
Y590000D01*
X-1466400D01*
X-1465000Y589250D01*
X-1463950Y588250D01*
X-1463075Y586750D01*
X-1462375Y585000D01*
X-1462200Y582500D01*
X-1462375Y580000D01*
X-1463075Y578250D01*
X-1463950Y576750D01*
X-1465000Y575750D01*
X-1466400Y575000D01*
X-1469900D01*
G01X-1442900Y590000D02*
X-1440450Y575000D01*
X-1437650Y590000D01*
X-1434850Y575000D01*
X-1432400Y590000D01*
G01X-1427825Y575000D02*
X-1423450Y590000D01*
X-1419075Y575000D01*
G01X-1420650Y580250D02*
X-1426250D01*
G01X-1412750Y575000D02*
Y590000D01*
X-1408375D01*
X-1406975Y589250D01*
X-1406100Y588250D01*
X-1405750Y586250D01*
X-1406100Y584250D01*
X-1407150Y583000D01*
X-1408375Y582250D01*
X-1412750D01*
G01X-1408375D02*
X-1405750Y575000D01*
G01X-1398550D02*
Y590000D01*
X-1394350D01*
X-1392950Y589250D01*
X-1391900Y587500D01*
X-1391550Y585500D01*
X-1391900Y583500D01*
X-1392775Y582000D01*
X-1394350Y581250D01*
X-1398550D01*
G01X-1385225Y575000D02*
X-1380850Y590000D01*
X-1376475Y575000D01*
G01X-1378050Y580250D02*
X-1383650D01*
G01X-1365600Y582500D02*
X-1362100D01*
Y578000D01*
X-1363150Y576500D01*
X-1364375Y575500D01*
X-1366125Y575000D01*
X-1367875Y575500D01*
X-1369100Y576500D01*
X-1370150Y578000D01*
X-1370850Y579750D01*
X-1371200Y581750D01*
Y583500D01*
X-1370850Y585000D01*
X-1370150Y586750D01*
X-1369100Y588250D01*
X-1368050Y589250D01*
X-1366650Y590000D01*
X-1365425D01*
X-1364025Y589500D01*
X-1362975Y588500D01*
G01X-1348950Y575000D02*
X-1355950D01*
Y590000D01*
X-1348950D01*
G01X-1351750Y582750D02*
X-1355950D01*
G01X-1326150Y590000D02*
X-1321950D01*
G01X-1324050D02*
Y575000D01*
G01X-1326150D02*
X-1321950D01*
G01X-1313875D02*
Y590000D01*
X-1305825Y575000D01*
Y590000D01*
G01X-1285825Y575000D02*
X-1281450Y590000D01*
X-1277075Y575000D01*
G01X-1278650Y580250D02*
X-1284250D01*
G01X-1271275Y575000D02*
Y590000D01*
X-1263225Y575000D01*
Y590000D01*
G01X-1253050Y575000D02*
Y581750D01*
X-1256550Y590000D01*
G01X-1249550D02*
X-1253050Y581750D01*
G01X-1228500Y575000D02*
Y590000D01*
X-1225000D01*
X-1223600Y589250D01*
X-1222550Y588250D01*
X-1221675Y586750D01*
X-1220975Y585000D01*
X-1220800Y582500D01*
X-1220975Y580000D01*
X-1221675Y578250D01*
X-1222550Y576750D01*
X-1223600Y575750D01*
X-1225000Y575000D01*
X-1228500D01*
G01X-1212550Y590000D02*
X-1208350D01*
G01X-1210450D02*
Y575000D01*
G01X-1212550D02*
X-1208350D01*
G01X-1199750D02*
Y590000D01*
X-1195375D01*
X-1193975Y589250D01*
X-1193100Y588250D01*
X-1192750Y586250D01*
X-1193100Y584250D01*
X-1194150Y583000D01*
X-1195375Y582250D01*
X-1199750D01*
G01X-1195375D02*
X-1192750Y575000D01*
G01X-1178550D02*
X-1185550D01*
Y590000D01*
X-1178550D01*
G01X-1181350Y582750D02*
X-1185550D01*
G01X-1164000Y588750D02*
X-1165050Y589500D01*
X-1166275Y590000D01*
X-1167675D01*
X-1169250Y589250D01*
X-1170475Y588000D01*
X-1171350Y586500D01*
X-1172050Y584000D01*
X-1172225Y581750D01*
X-1171875Y579500D01*
X-1171350Y578000D01*
X-1170300Y576500D01*
X-1169075Y575500D01*
X-1167850Y575000D01*
X-1166625D01*
X-1165400Y575500D01*
X-1164350Y576250D01*
X-1163475Y577250D01*
G01X-1153650Y590000D02*
Y575000D01*
G01X-1157675Y590000D02*
X-1149625D01*
G01X-1141550D02*
X-1137350D01*
G01X-1139450D02*
Y575000D01*
G01X-1141550D02*
X-1137350D01*
G01X-1125250D02*
X-1126650Y575250D01*
X-1127875Y576250D01*
X-1128925Y577750D01*
X-1129625Y579500D01*
X-1129975Y581500D01*
Y583500D01*
X-1129625Y585500D01*
X-1128925Y587250D01*
X-1127875Y588750D01*
X-1126650Y589750D01*
X-1125250Y590000D01*
X-1123850Y589750D01*
X-1122625Y588750D01*
X-1121575Y587250D01*
X-1120875Y585500D01*
X-1120525Y583500D01*
Y581500D01*
X-1120875Y579500D01*
X-1121575Y577750D01*
X-1122625Y576250D01*
X-1123850Y575250D01*
X-1125250Y575000D01*
G01X-1115075D02*
Y590000D01*
X-1107025Y575000D01*
Y590000D01*
G01X-1082650D02*
Y575000D01*
G01X-1086675Y590000D02*
X-1078625D01*
G01X-1068450Y575000D02*
X-1069850Y575250D01*
X-1071075Y576250D01*
X-1072125Y577750D01*
X-1072825Y579500D01*
X-1073175Y581500D01*
Y583500D01*
X-1072825Y585500D01*
X-1072125Y587250D01*
X-1071075Y588750D01*
X-1069850Y589750D01*
X-1068450Y590000D01*
X-1067050Y589750D01*
X-1065825Y588750D01*
X-1064775Y587250D01*
X-1064075Y585500D01*
X-1063725Y583500D01*
Y581500D01*
X-1064075Y579500D01*
X-1064775Y577750D01*
X-1065825Y576250D01*
X-1067050Y575250D01*
X-1068450Y575000D01*
G01X-1038650Y583000D02*
X-1037950Y583750D01*
X-1037425Y585000D01*
X-1037075Y586750D01*
X-1037425Y588250D01*
X-1038125Y589250D01*
X-1039350Y590000D01*
X-1044075D01*
Y575000D01*
X-1038300D01*
X-1037075Y576000D01*
X-1036375Y577500D01*
X-1036025Y579250D01*
X-1036375Y581000D01*
X-1037425Y582500D01*
X-1038650Y583000D01*
X-1044075D01*
G01X-1022350Y575000D02*
X-1029350D01*
Y590000D01*
X-1022350D01*
G01X-1025150Y582750D02*
X-1029350D01*
G01X-997450Y574500D02*
X-997800Y574750D01*
Y575250D01*
X-997450Y575500D01*
X-997100Y575250D01*
Y574750D01*
X-997450Y574500D01*
G01X-983250Y590000D02*
X-984650Y589500D01*
X-985700Y588250D01*
X-986400Y586750D01*
X-986925Y584750D01*
X-987100Y582500D01*
X-986925Y580250D01*
X-986400Y578250D01*
X-985700Y576750D01*
X-984650Y575500D01*
X-983250Y575000D01*
X-981850Y575500D01*
X-980800Y576750D01*
X-980100Y578250D01*
X-979575Y580250D01*
X-979400Y582500D01*
X-979575Y584750D01*
X-980100Y586750D01*
X-980800Y588250D01*
X-981850Y589500D01*
X-983250Y590000D01*
G01X-969050D02*
X-970450Y589500D01*
X-971500Y588250D01*
X-972200Y586750D01*
X-972725Y584750D01*
X-972900Y582500D01*
X-972725Y580250D01*
X-972200Y578250D01*
X-971500Y576750D01*
X-970450Y575500D01*
X-969050Y575000D01*
X-967650Y575500D01*
X-966600Y576750D01*
X-965900Y578250D01*
X-965375Y580250D01*
X-965200Y582500D01*
X-965375Y584750D01*
X-965900Y586750D01*
X-966600Y588250D01*
X-967650Y589500D01*
X-969050Y590000D01*
G01X-955200Y575000D02*
X-954850Y578250D01*
X-954325Y581000D01*
X-953625Y583500D01*
X-952750Y586250D01*
X-951350Y590000D01*
X-958350D01*
G01X-944500Y577250D02*
X-943450Y576000D01*
X-942225Y575250D01*
X-940650Y575000D01*
X-939075Y575500D01*
X-937850Y576500D01*
X-936975Y578250D01*
X-936800Y580250D01*
X-937150Y582250D01*
X-938025Y583500D01*
X-939250Y584500D01*
X-940475Y584750D01*
X-941700Y584500D01*
X-943275Y583500D01*
X-942750Y590000D01*
X-938025D01*
G01X-928025Y586750D02*
X-927150Y590000D01*
G01X-924875D02*
X-925750Y586750D01*
G01X-915400Y574500D02*
X-909100Y590000D01*
G01X-900150D02*
X-895950D01*
G01X-898050D02*
Y575000D01*
G01X-900150D02*
X-895950D01*
G01X-887875D02*
Y590000D01*
X-879825Y575000D01*
Y590000D01*
G01X-865800Y588750D02*
X-866850Y589500D01*
X-868075Y590000D01*
X-869475D01*
X-871050Y589250D01*
X-872275Y588000D01*
X-873150Y586500D01*
X-873850Y584000D01*
X-874025Y581750D01*
X-873675Y579500D01*
X-873150Y578000D01*
X-872100Y576500D01*
X-870875Y575500D01*
X-869650Y575000D01*
X-868425D01*
X-867200Y575500D01*
X-866150Y576250D01*
X-865275Y577250D01*
G01X-859125Y575000D02*
Y590000D01*
G01X-851775D02*
Y575000D01*
G01Y582500D02*
X-859125D01*
G01X-841600Y572250D02*
X-840900Y575500D01*
G01X-817225Y575000D02*
X-812850Y590000D01*
X-808475Y575000D01*
G01X-810050Y580250D02*
X-815650D01*
G01X-802325Y577000D02*
X-800925Y575750D01*
X-799350Y575000D01*
X-797950D01*
X-796550Y575750D01*
X-795500Y577000D01*
X-794975Y578750D01*
X-795325Y580500D01*
X-796200Y582000D01*
X-797775Y583000D01*
X-799875Y583500D01*
X-801100Y584500D01*
X-801625Y586250D01*
X-801275Y588000D01*
X-800400Y589250D01*
X-799175Y590000D01*
X-797950D01*
X-796725Y589500D01*
X-795675Y588250D01*
G01X-774800Y575000D02*
Y590000D01*
X-770250Y577500D01*
X-765700Y590000D01*
Y575000D01*
G01X-752550D02*
X-759550D01*
Y590000D01*
X-752550D01*
G01X-755350Y582750D02*
X-759550D01*
G01X-746225Y575000D02*
X-741850Y590000D01*
X-737475Y575000D01*
G01X-739050Y580250D02*
X-744650D01*
G01X-731325Y577000D02*
X-729925Y575750D01*
X-728350Y575000D01*
X-726950D01*
X-725550Y575750D01*
X-724500Y577000D01*
X-723975Y578750D01*
X-724325Y580500D01*
X-725200Y582000D01*
X-726775Y583000D01*
X-728875Y583500D01*
X-730100Y584500D01*
X-730625Y586250D01*
X-730275Y588000D01*
X-729400Y589250D01*
X-728175Y590000D01*
X-726950D01*
X-725725Y589500D01*
X-724675Y588250D01*
G01X-717300Y590000D02*
Y579250D01*
X-716600Y577000D01*
X-715200Y575500D01*
X-713450Y575000D01*
X-711700Y575500D01*
X-710300Y577000D01*
X-709600Y579250D01*
Y590000D01*
G01X-702750Y575000D02*
Y590000D01*
X-698375D01*
X-696975Y589250D01*
X-696100Y588250D01*
X-695750Y586250D01*
X-696100Y584250D01*
X-697150Y583000D01*
X-698375Y582250D01*
X-702750D01*
G01X-698375D02*
X-695750Y575000D01*
G01X-681550D02*
X-688550D01*
Y590000D01*
X-681550D01*
G01X-684350Y582750D02*
X-688550D01*
G01X-674700Y575000D02*
Y590000D01*
X-671200D01*
X-669800Y589250D01*
X-668750Y588250D01*
X-667875Y586750D01*
X-667175Y585000D01*
X-667000Y582500D01*
X-667175Y580000D01*
X-667875Y578250D01*
X-668750Y576750D01*
X-669800Y575750D01*
X-671200Y575000D01*
X-674700D01*
G01X-641050Y583000D02*
X-640350Y583750D01*
X-639825Y585000D01*
X-639475Y586750D01*
X-639825Y588250D01*
X-640525Y589250D01*
X-641750Y590000D01*
X-646475D01*
Y575000D01*
X-640700D01*
X-639475Y576000D01*
X-638775Y577500D01*
X-638425Y579250D01*
X-638775Y581000D01*
X-639825Y582500D01*
X-641050Y583000D01*
X-646475D01*
G01X-628250Y575000D02*
Y581750D01*
X-631750Y590000D01*
G01X-624750D02*
X-628250Y581750D01*
G01X-1693250Y610000D02*
Y625000D01*
X-1695350Y622000D01*
G01Y610000D02*
X-1691150D01*
G01X-1679050Y625000D02*
X-1680450Y624500D01*
X-1681500Y623250D01*
X-1682200Y621750D01*
X-1682725Y619750D01*
X-1682900Y617500D01*
X-1682725Y615250D01*
X-1682200Y613250D01*
X-1681500Y611750D01*
X-1680450Y610500D01*
X-1679050Y610000D01*
X-1677650Y610500D01*
X-1676600Y611750D01*
X-1675900Y613250D01*
X-1675375Y615250D01*
X-1675200Y617500D01*
X-1675375Y619750D01*
X-1675900Y621750D01*
X-1676600Y623250D01*
X-1677650Y624500D01*
X-1679050Y625000D01*
G01X-1664850Y609500D02*
X-1665200Y609750D01*
Y610250D01*
X-1664850Y610500D01*
X-1664500Y610250D01*
Y609750D01*
X-1664850Y609500D01*
G01X-1632600Y623750D02*
X-1633650Y624500D01*
X-1634875Y625000D01*
X-1636275D01*
X-1637850Y624250D01*
X-1639075Y623000D01*
X-1639950Y621500D01*
X-1640650Y619000D01*
X-1640825Y616750D01*
X-1640475Y614500D01*
X-1639950Y613000D01*
X-1638900Y611500D01*
X-1637675Y610500D01*
X-1636450Y610000D01*
X-1635225D01*
X-1634000Y610500D01*
X-1632950Y611250D01*
X-1632075Y612250D01*
G01X-1622250Y610000D02*
X-1623650Y610250D01*
X-1624875Y611250D01*
X-1625925Y612750D01*
X-1626625Y614500D01*
X-1626975Y616500D01*
Y618500D01*
X-1626625Y620500D01*
X-1625925Y622250D01*
X-1624875Y623750D01*
X-1623650Y624750D01*
X-1622250Y625000D01*
X-1620850Y624750D01*
X-1619625Y623750D01*
X-1618575Y622250D01*
X-1617875Y620500D01*
X-1617525Y618500D01*
Y616500D01*
X-1617875Y614500D01*
X-1618575Y612750D01*
X-1619625Y611250D01*
X-1620850Y610250D01*
X-1622250Y610000D01*
G01X-1611550D02*
Y625000D01*
X-1607350D01*
X-1605950Y624250D01*
X-1604900Y622500D01*
X-1604550Y620500D01*
X-1604900Y618500D01*
X-1605775Y617000D01*
X-1607350Y616250D01*
X-1611550D01*
G01X-1597350Y610000D02*
Y625000D01*
X-1593150D01*
X-1591750Y624250D01*
X-1590700Y622500D01*
X-1590350Y620500D01*
X-1590700Y618500D01*
X-1591575Y617000D01*
X-1593150Y616250D01*
X-1597350D01*
G01X-1576150Y610000D02*
X-1583150D01*
Y625000D01*
X-1576150D01*
G01X-1578950Y617750D02*
X-1583150D01*
G01X-1568950Y610000D02*
Y625000D01*
X-1564575D01*
X-1563175Y624250D01*
X-1562300Y623250D01*
X-1561950Y621250D01*
X-1562300Y619250D01*
X-1563350Y618000D01*
X-1564575Y617250D01*
X-1568950D01*
G01X-1564575D02*
X-1561950Y610000D01*
G01X-1539150Y625000D02*
X-1534950D01*
G01X-1537050D02*
Y610000D01*
G01X-1539150D02*
X-1534950D01*
G01X-1526875D02*
Y625000D01*
X-1518825Y610000D01*
Y625000D01*
G01X-1498125Y610000D02*
Y625000D01*
G01X-1490775D02*
Y610000D01*
G01Y617500D02*
X-1498125D01*
G01X-1480250Y610000D02*
X-1481650Y610250D01*
X-1482875Y611250D01*
X-1483925Y612750D01*
X-1484625Y614500D01*
X-1484975Y616500D01*
Y618500D01*
X-1484625Y620500D01*
X-1483925Y622250D01*
X-1482875Y623750D01*
X-1481650Y624750D01*
X-1480250Y625000D01*
X-1478850Y624750D01*
X-1477625Y623750D01*
X-1476575Y622250D01*
X-1475875Y620500D01*
X-1475525Y618500D01*
Y616500D01*
X-1475875Y614500D01*
X-1476575Y612750D01*
X-1477625Y611250D01*
X-1478850Y610250D01*
X-1480250Y610000D01*
G01X-1469550Y625000D02*
Y610000D01*
X-1462550D01*
G01X-1448350D02*
X-1455350D01*
Y625000D01*
X-1448350D01*
G01X-1451150Y617750D02*
X-1455350D01*
G01X-1441325Y612000D02*
X-1439925Y610750D01*
X-1438350Y610000D01*
X-1436950D01*
X-1435550Y610750D01*
X-1434500Y612000D01*
X-1433975Y613750D01*
X-1434325Y615500D01*
X-1435200Y617000D01*
X-1436775Y618000D01*
X-1438875Y618500D01*
X-1440100Y619500D01*
X-1440625Y621250D01*
X-1440275Y623000D01*
X-1439400Y624250D01*
X-1438175Y625000D01*
X-1436950D01*
X-1435725Y624500D01*
X-1434675Y623250D01*
G01X-1412925Y612000D02*
X-1411525Y610750D01*
X-1409950Y610000D01*
X-1408550D01*
X-1407150Y610750D01*
X-1406100Y612000D01*
X-1405575Y613750D01*
X-1405925Y615500D01*
X-1406800Y617000D01*
X-1408375Y618000D01*
X-1410475Y618500D01*
X-1411700Y619500D01*
X-1412225Y621250D01*
X-1411875Y623000D01*
X-1411000Y624250D01*
X-1409775Y625000D01*
X-1408550D01*
X-1407325Y624500D01*
X-1406275Y623250D01*
G01X-1398725Y610000D02*
Y625000D01*
G01X-1391375D02*
Y610000D01*
G01Y617500D02*
X-1398725D01*
G01X-1385225Y610000D02*
X-1380850Y625000D01*
X-1376475Y610000D01*
G01X-1378050Y615250D02*
X-1383650D01*
G01X-1370150Y625000D02*
Y610000D01*
X-1363150D01*
G01X-1355950Y625000D02*
Y610000D01*
X-1348950D01*
G01X-1322650Y618000D02*
X-1321950Y618750D01*
X-1321425Y620000D01*
X-1321075Y621750D01*
X-1321425Y623250D01*
X-1322125Y624250D01*
X-1323350Y625000D01*
X-1328075D01*
Y610000D01*
X-1322300D01*
X-1321075Y611000D01*
X-1320375Y612500D01*
X-1320025Y614250D01*
X-1320375Y616000D01*
X-1321425Y617500D01*
X-1322650Y618000D01*
X-1328075D01*
G01X-1306350Y610000D02*
X-1313350D01*
Y625000D01*
X-1306350D01*
G01X-1309150Y617750D02*
X-1313350D01*
G01X-1284950Y610000D02*
Y625000D01*
X-1280750D01*
X-1279350Y624250D01*
X-1278300Y622500D01*
X-1277950Y620500D01*
X-1278300Y618500D01*
X-1279175Y617000D01*
X-1280750Y616250D01*
X-1284950D01*
G01X-1263750Y610000D02*
X-1270750D01*
Y625000D01*
X-1263750D01*
G01X-1266550Y617750D02*
X-1270750D01*
G01X-1256550Y610000D02*
Y625000D01*
X-1252175D01*
X-1250775Y624250D01*
X-1249900Y623250D01*
X-1249550Y621250D01*
X-1249900Y619250D01*
X-1250950Y618000D01*
X-1252175Y617250D01*
X-1256550D01*
G01X-1252175D02*
X-1249550Y610000D01*
G01X-1226750Y625000D02*
X-1222550D01*
G01X-1224650D02*
Y610000D01*
G01X-1226750D02*
X-1222550D01*
G01X-1213950D02*
Y625000D01*
X-1209750D01*
X-1208350Y624250D01*
X-1207300Y622500D01*
X-1206950Y620500D01*
X-1207300Y618500D01*
X-1208175Y617000D01*
X-1209750Y616250D01*
X-1213950D01*
G01X-1192400Y623750D02*
X-1193450Y624500D01*
X-1194675Y625000D01*
X-1196075D01*
X-1197650Y624250D01*
X-1198875Y623000D01*
X-1199750Y621500D01*
X-1200450Y619000D01*
X-1200625Y616750D01*
X-1200275Y614500D01*
X-1199750Y613000D01*
X-1198700Y611500D01*
X-1197475Y610500D01*
X-1196250Y610000D01*
X-1195025D01*
X-1193800Y610500D01*
X-1192750Y611250D01*
X-1191875Y612250D01*
G01X-1184325Y615000D02*
X-1179775D01*
G01X-1171175Y616250D02*
X-1169950Y618000D01*
X-1168900Y619000D01*
X-1167500Y619500D01*
X-1166275Y619000D01*
X-1165400Y618000D01*
X-1164700Y616500D01*
X-1164525Y614750D01*
X-1164700Y613250D01*
X-1165400Y611750D01*
X-1166450Y610500D01*
X-1167675Y610000D01*
X-1169075Y610500D01*
X-1170300Y612000D01*
X-1171000Y614250D01*
X-1171175Y616750D01*
X-1170825Y620000D01*
X-1170300Y621750D01*
X-1169425Y623500D01*
X-1168200Y624750D01*
X-1166975Y625000D01*
X-1165750Y624500D01*
X-1164875Y623250D01*
G01X-1153650Y625000D02*
X-1155050Y624500D01*
X-1156100Y623250D01*
X-1156800Y621750D01*
X-1157325Y619750D01*
X-1157500Y617500D01*
X-1157325Y615250D01*
X-1156800Y613250D01*
X-1156100Y611750D01*
X-1155050Y610500D01*
X-1153650Y610000D01*
X-1152250Y610500D01*
X-1151200Y611750D01*
X-1150500Y613250D01*
X-1149975Y615250D01*
X-1149800Y617500D01*
X-1149975Y619750D01*
X-1150500Y621750D01*
X-1151200Y623250D01*
X-1152250Y624500D01*
X-1153650Y625000D01*
G01X-1139450Y610000D02*
Y625000D01*
X-1141550Y622000D01*
G01Y610000D02*
X-1137350D01*
G01X-1128575Y622500D02*
X-1127525Y624000D01*
X-1126300Y624750D01*
X-1124900Y625000D01*
X-1123150Y624500D01*
X-1121925Y623250D01*
X-1121575Y621750D01*
X-1121750Y620250D01*
X-1122450Y619000D01*
X-1125950Y616500D01*
X-1127525Y614750D01*
X-1128575Y612250D01*
X-1128925Y610000D01*
X-1121575D01*
G01X-1111925Y605000D02*
X-1113675Y607500D01*
X-1114550Y610000D01*
Y620000D01*
X-1113675Y622500D01*
X-1111925Y625000D01*
G01X-1100350D02*
Y610000D01*
X-1093350D01*
G01X-1087025D02*
X-1082650Y625000D01*
X-1078275Y610000D01*
G01X-1079850Y615250D02*
X-1085450D01*
G01X-1068450Y625000D02*
Y610000D01*
G01X-1072475Y625000D02*
X-1064425D01*
G01X-1050750Y610000D02*
X-1057750D01*
Y625000D01*
X-1050750D01*
G01X-1053550Y617750D02*
X-1057750D01*
G01X-1043725Y612000D02*
X-1042325Y610750D01*
X-1040750Y610000D01*
X-1039350D01*
X-1037950Y610750D01*
X-1036900Y612000D01*
X-1036375Y613750D01*
X-1036725Y615500D01*
X-1037600Y617000D01*
X-1039175Y618000D01*
X-1041275Y618500D01*
X-1042500Y619500D01*
X-1043025Y621250D01*
X-1042675Y623000D01*
X-1041800Y624250D01*
X-1040575Y625000D01*
X-1039350D01*
X-1038125Y624500D01*
X-1037075Y623250D01*
G01X-1025850Y625000D02*
Y610000D01*
G01X-1029875Y625000D02*
X-1021825D01*
G01X-1000950Y610000D02*
Y625000D01*
X-996575D01*
X-995175Y624250D01*
X-994300Y623250D01*
X-993950Y621250D01*
X-994300Y619250D01*
X-995350Y618000D01*
X-996575Y617250D01*
X-1000950D01*
G01X-996575D02*
X-993950Y610000D01*
G01X-979750D02*
X-986750D01*
Y625000D01*
X-979750D01*
G01X-982550Y617750D02*
X-986750D01*
G01X-973425Y625000D02*
X-969050Y610000D01*
X-964675Y625000D01*
G01X-956950D02*
X-952750D01*
G01X-954850D02*
Y610000D01*
G01X-956950D02*
X-952750D01*
G01X-944325Y612000D02*
X-942925Y610750D01*
X-941350Y610000D01*
X-939950D01*
X-938550Y610750D01*
X-937500Y612000D01*
X-936975Y613750D01*
X-937325Y615500D01*
X-938200Y617000D01*
X-939775Y618000D01*
X-941875Y618500D01*
X-943100Y619500D01*
X-943625Y621250D01*
X-943275Y623000D01*
X-942400Y624250D01*
X-941175Y625000D01*
X-939950D01*
X-938725Y624500D01*
X-937675Y623250D01*
G01X-928550Y625000D02*
X-924350D01*
G01X-926450D02*
Y610000D01*
G01X-928550D02*
X-924350D01*
G01X-912250D02*
X-913650Y610250D01*
X-914875Y611250D01*
X-915925Y612750D01*
X-916625Y614500D01*
X-916975Y616500D01*
Y618500D01*
X-916625Y620500D01*
X-915925Y622250D01*
X-914875Y623750D01*
X-913650Y624750D01*
X-912250Y625000D01*
X-910850Y624750D01*
X-909625Y623750D01*
X-908575Y622250D01*
X-907875Y620500D01*
X-907525Y618500D01*
Y616500D01*
X-907875Y614500D01*
X-908575Y612750D01*
X-909625Y611250D01*
X-910850Y610250D01*
X-912250Y610000D01*
G01X-902075D02*
Y625000D01*
X-894025Y610000D01*
Y625000D01*
G01X-882975Y605000D02*
X-881225Y607500D01*
X-880350Y610000D01*
Y620000D01*
X-881225Y622500D01*
X-882975Y625000D01*
G01X-870000Y607250D02*
X-869300Y610500D01*
G01X-837400Y623750D02*
X-838450Y624500D01*
X-839675Y625000D01*
X-841075D01*
X-842650Y624250D01*
X-843875Y623000D01*
X-844750Y621500D01*
X-845450Y619000D01*
X-845625Y616750D01*
X-845275Y614500D01*
X-844750Y613000D01*
X-843700Y611500D01*
X-842475Y610500D01*
X-841250Y610000D01*
X-840025D01*
X-838800Y610500D01*
X-837750Y611250D01*
X-836875Y612250D01*
G01X-830550Y625000D02*
Y610000D01*
X-823550D01*
G01X-817225D02*
X-812850Y625000D01*
X-808475Y610000D01*
G01X-810050Y615250D02*
X-815650D01*
G01X-802325Y612000D02*
X-800925Y610750D01*
X-799350Y610000D01*
X-797950D01*
X-796550Y610750D01*
X-795500Y612000D01*
X-794975Y613750D01*
X-795325Y615500D01*
X-796200Y617000D01*
X-797775Y618000D01*
X-799875Y618500D01*
X-801100Y619500D01*
X-801625Y621250D01*
X-801275Y623000D01*
X-800400Y624250D01*
X-799175Y625000D01*
X-797950D01*
X-796725Y624500D01*
X-795675Y623250D01*
G01X-788125Y612000D02*
X-786725Y610750D01*
X-785150Y610000D01*
X-783750D01*
X-782350Y610750D01*
X-781300Y612000D01*
X-780775Y613750D01*
X-781125Y615500D01*
X-782000Y617000D01*
X-783575Y618000D01*
X-785675Y618500D01*
X-786900Y619500D01*
X-787425Y621250D01*
X-787075Y623000D01*
X-786200Y624250D01*
X-784975Y625000D01*
X-783750D01*
X-782525Y624500D01*
X-781475Y623250D01*
G01X-759375Y622500D02*
X-758325Y624000D01*
X-757100Y624750D01*
X-755700Y625000D01*
X-753950Y624500D01*
X-752725Y623250D01*
X-752375Y621750D01*
X-752550Y620250D01*
X-753250Y619000D01*
X-756750Y616500D01*
X-758325Y614750D01*
X-759375Y612250D01*
X-759725Y610000D01*
X-752375D01*
G01X-741850Y609500D02*
X-742200Y609750D01*
Y610250D01*
X-741850Y610500D01*
X-741500Y610250D01*
Y609750D01*
X-741850Y609500D01*
G01X-1682025Y646750D02*
X-1680800Y645500D01*
X-1679400Y645000D01*
X-1678000Y645500D01*
X-1676775Y647000D01*
X-1675900Y649250D01*
X-1675550Y651500D01*
Y654250D01*
X-1675900Y656500D01*
X-1676775Y658500D01*
X-1677825Y659500D01*
X-1679050Y660000D01*
X-1680450Y659500D01*
X-1681500Y658500D01*
X-1682200Y657000D01*
X-1682550Y655000D01*
X-1682200Y653250D01*
X-1681325Y651500D01*
X-1680275Y650500D01*
X-1679050Y650250D01*
X-1677650Y650750D01*
X-1676600Y652000D01*
X-1675550Y654250D01*
G01X-1636450Y644500D02*
X-1636800Y644750D01*
Y645250D01*
X-1636450Y645500D01*
X-1636100Y645250D01*
Y644750D01*
X-1636450Y644500D01*
G01X-1622250Y660000D02*
X-1623650Y659500D01*
X-1624700Y658250D01*
X-1625400Y656750D01*
X-1625925Y654750D01*
X-1626100Y652500D01*
X-1625925Y650250D01*
X-1625400Y648250D01*
X-1624700Y646750D01*
X-1623650Y645500D01*
X-1622250Y645000D01*
X-1620850Y645500D01*
X-1619800Y646750D01*
X-1619100Y648250D01*
X-1618575Y650250D01*
X-1618400Y652500D01*
X-1618575Y654750D01*
X-1619100Y656750D01*
X-1619800Y658250D01*
X-1620850Y659500D01*
X-1622250Y660000D01*
G01X-1608050D02*
X-1609450Y659500D01*
X-1610500Y658250D01*
X-1611200Y656750D01*
X-1611725Y654750D01*
X-1611900Y652500D01*
X-1611725Y650250D01*
X-1611200Y648250D01*
X-1610500Y646750D01*
X-1609450Y645500D01*
X-1608050Y645000D01*
X-1606650Y645500D01*
X-1605600Y646750D01*
X-1604900Y648250D01*
X-1604375Y650250D01*
X-1604200Y652500D01*
X-1604375Y654750D01*
X-1604900Y656750D01*
X-1605600Y658250D01*
X-1606650Y659500D01*
X-1608050Y660000D01*
G01X-1593850Y645000D02*
Y660000D01*
X-1595950Y657000D01*
G01Y645000D02*
X-1591750D01*
G01X-1581225Y656750D02*
X-1580350Y660000D01*
G01X-1578075D02*
X-1578950Y656750D01*
G01X-1555100Y645000D02*
Y660000D01*
X-1551600D01*
X-1550200Y659250D01*
X-1549150Y658250D01*
X-1548275Y656750D01*
X-1547575Y655000D01*
X-1547400Y652500D01*
X-1547575Y650000D01*
X-1548275Y648250D01*
X-1549150Y646750D01*
X-1550200Y645750D01*
X-1551600Y645000D01*
X-1555100D01*
G01X-1540550D02*
Y660000D01*
X-1536175D01*
X-1534775Y659250D01*
X-1533900Y658250D01*
X-1533550Y656250D01*
X-1533900Y654250D01*
X-1534950Y653000D01*
X-1536175Y652250D01*
X-1540550D01*
G01X-1536175D02*
X-1533550Y645000D01*
G01X-1524950Y660000D02*
X-1520750D01*
G01X-1522850D02*
Y645000D01*
G01X-1524950D02*
X-1520750D01*
G01X-1512150Y660000D02*
Y645000D01*
X-1505150D01*
G01X-1497950Y660000D02*
Y645000D01*
X-1490950D01*
G01X-1464650Y653000D02*
X-1463950Y653750D01*
X-1463425Y655000D01*
X-1463075Y656750D01*
X-1463425Y658250D01*
X-1464125Y659250D01*
X-1465350Y660000D01*
X-1470075D01*
Y645000D01*
X-1464300D01*
X-1463075Y646000D01*
X-1462375Y647500D01*
X-1462025Y649250D01*
X-1462375Y651000D01*
X-1463425Y652500D01*
X-1464650Y653000D01*
X-1470075D01*
G01X-1455350Y645000D02*
Y660000D01*
X-1450975D01*
X-1449575Y659250D01*
X-1448700Y658250D01*
X-1448350Y656250D01*
X-1448700Y654250D01*
X-1449750Y653000D01*
X-1450975Y652250D01*
X-1455350D01*
G01X-1450975D02*
X-1448350Y645000D01*
G01X-1434150D02*
X-1441150D01*
Y660000D01*
X-1434150D01*
G01X-1436950Y652750D02*
X-1441150D01*
G01X-1427825Y645000D02*
X-1423450Y660000D01*
X-1419075Y645000D01*
G01X-1420650Y650250D02*
X-1426250D01*
G01X-1413100Y645000D02*
Y660000D01*
G01X-1406450D02*
X-1413100Y650750D01*
G01X-1405400Y645000D02*
X-1410125Y655000D01*
G01X-1395050Y645000D02*
X-1396450Y645250D01*
X-1397675Y646250D01*
X-1398725Y647750D01*
X-1399425Y649500D01*
X-1399775Y651500D01*
Y653500D01*
X-1399425Y655500D01*
X-1398725Y657250D01*
X-1397675Y658750D01*
X-1396450Y659750D01*
X-1395050Y660000D01*
X-1393650Y659750D01*
X-1392425Y658750D01*
X-1391375Y657250D01*
X-1390675Y655500D01*
X-1390325Y653500D01*
Y651500D01*
X-1390675Y649500D01*
X-1391375Y647750D01*
X-1392425Y646250D01*
X-1393650Y645250D01*
X-1395050Y645000D01*
G01X-1384700Y660000D02*
Y649250D01*
X-1384000Y647000D01*
X-1382600Y645500D01*
X-1380850Y645000D01*
X-1379100Y645500D01*
X-1377700Y647000D01*
X-1377000Y649250D01*
Y660000D01*
G01X-1366650D02*
Y645000D01*
G01X-1370675Y660000D02*
X-1362625D01*
G01X-1342625Y645000D02*
X-1338250Y660000D01*
X-1333875Y645000D01*
G01X-1335450Y650250D02*
X-1341050D01*
G01X-1327550Y660000D02*
Y645000D01*
X-1320550D01*
G01X-1313350Y660000D02*
Y645000D01*
X-1306350D01*
G01X-1295650D02*
X-1297050Y645250D01*
X-1298275Y646250D01*
X-1299325Y647750D01*
X-1300025Y649500D01*
X-1300375Y651500D01*
Y653500D01*
X-1300025Y655500D01*
X-1299325Y657250D01*
X-1298275Y658750D01*
X-1297050Y659750D01*
X-1295650Y660000D01*
X-1294250Y659750D01*
X-1293025Y658750D01*
X-1291975Y657250D01*
X-1291275Y655500D01*
X-1290925Y653500D01*
Y651500D01*
X-1291275Y649500D01*
X-1291975Y647750D01*
X-1293025Y646250D01*
X-1294250Y645250D01*
X-1295650Y645000D01*
G01X-1286700Y660000D02*
X-1284250Y645000D01*
X-1281450Y660000D01*
X-1278650Y645000D01*
X-1276200Y660000D01*
G01X-1263750Y645000D02*
X-1270750D01*
Y660000D01*
X-1263750D01*
G01X-1266550Y652750D02*
X-1270750D01*
G01X-1256900Y645000D02*
Y660000D01*
X-1253400D01*
X-1252000Y659250D01*
X-1250950Y658250D01*
X-1250075Y656750D01*
X-1249375Y655000D01*
X-1249200Y652500D01*
X-1249375Y650000D01*
X-1250075Y648250D01*
X-1250950Y646750D01*
X-1252000Y645750D01*
X-1253400Y645000D01*
X-1256900D01*
G01X-1238850Y644500D02*
X-1239200Y644750D01*
Y645250D01*
X-1238850Y645500D01*
X-1238500Y645250D01*
Y644750D01*
X-1238850Y644500D01*
G01X-1640300Y680000D02*
Y695000D01*
X-1636800D01*
X-1635400Y694250D01*
X-1634350Y693250D01*
X-1633475Y691750D01*
X-1632775Y690000D01*
X-1632600Y687500D01*
X-1632775Y685000D01*
X-1633475Y683250D01*
X-1634350Y681750D01*
X-1635400Y680750D01*
X-1636800Y680000D01*
X-1640300D01*
G01X-1624350Y695000D02*
X-1620150D01*
G01X-1622250D02*
Y680000D01*
G01X-1624350D02*
X-1620150D01*
G01X-1612600D02*
Y695000D01*
X-1608050Y682500D01*
X-1603500Y695000D01*
Y680000D01*
G01X-1590350D02*
X-1597350D01*
Y695000D01*
X-1590350D01*
G01X-1593150Y687750D02*
X-1597350D01*
G01X-1583675Y680000D02*
Y695000D01*
X-1575625Y680000D01*
Y695000D01*
G01X-1569125Y682000D02*
X-1567725Y680750D01*
X-1566150Y680000D01*
X-1564750D01*
X-1563350Y680750D01*
X-1562300Y682000D01*
X-1561775Y683750D01*
X-1562125Y685500D01*
X-1563000Y687000D01*
X-1564575Y688000D01*
X-1566675Y688500D01*
X-1567900Y689500D01*
X-1568425Y691250D01*
X-1568075Y693000D01*
X-1567200Y694250D01*
X-1565975Y695000D01*
X-1564750D01*
X-1563525Y694500D01*
X-1562475Y693250D01*
G01X-1553350Y695000D02*
X-1549150D01*
G01X-1551250D02*
Y680000D01*
G01X-1553350D02*
X-1549150D01*
G01X-1537050D02*
X-1538450Y680250D01*
X-1539675Y681250D01*
X-1540725Y682750D01*
X-1541425Y684500D01*
X-1541775Y686500D01*
Y688500D01*
X-1541425Y690500D01*
X-1540725Y692250D01*
X-1539675Y693750D01*
X-1538450Y694750D01*
X-1537050Y695000D01*
X-1535650Y694750D01*
X-1534425Y693750D01*
X-1533375Y692250D01*
X-1532675Y690500D01*
X-1532325Y688500D01*
Y686500D01*
X-1532675Y684500D01*
X-1533375Y682750D01*
X-1534425Y681250D01*
X-1535650Y680250D01*
X-1537050Y680000D01*
G01X-1526875D02*
Y695000D01*
X-1518825Y680000D01*
Y695000D01*
G01X-1512325Y682000D02*
X-1510925Y680750D01*
X-1509350Y680000D01*
X-1507950D01*
X-1506550Y680750D01*
X-1505500Y682000D01*
X-1504975Y683750D01*
X-1505325Y685500D01*
X-1506200Y687000D01*
X-1507775Y688000D01*
X-1509875Y688500D01*
X-1511100Y689500D01*
X-1511625Y691250D01*
X-1511275Y693000D01*
X-1510400Y694250D01*
X-1509175Y695000D01*
X-1507950D01*
X-1506725Y694500D01*
X-1505675Y693250D01*
G01X-1484625Y680000D02*
X-1480250Y695000D01*
X-1475875Y680000D01*
G01X-1477450Y685250D02*
X-1483050D01*
G01X-1469550Y680000D02*
Y695000D01*
X-1465175D01*
X-1463775Y694250D01*
X-1462900Y693250D01*
X-1462550Y691250D01*
X-1462900Y689250D01*
X-1463950Y688000D01*
X-1465175Y687250D01*
X-1469550D01*
G01X-1465175D02*
X-1462550Y680000D01*
G01X-1448350D02*
X-1455350D01*
Y695000D01*
X-1448350D01*
G01X-1451150Y687750D02*
X-1455350D01*
G01X-1425550Y695000D02*
X-1421350D01*
G01X-1423450D02*
Y680000D01*
G01X-1425550D02*
X-1421350D01*
G01X-1413275D02*
Y695000D01*
X-1405225Y680000D01*
Y695000D01*
G01X-1385400Y680000D02*
Y695000D01*
X-1380850Y682500D01*
X-1376300Y695000D01*
Y680000D01*
G01X-1368750Y695000D02*
X-1364550D01*
G01X-1366650D02*
Y680000D01*
G01X-1368750D02*
X-1364550D01*
G01X-1355950Y695000D02*
Y680000D01*
X-1348950D01*
G01X-1341750Y695000D02*
Y680000D01*
X-1334750D01*
G01X-1326150Y695000D02*
X-1321950D01*
G01X-1324050D02*
Y680000D01*
G01X-1326150D02*
X-1321950D01*
G01X-1314400D02*
Y695000D01*
X-1309850Y682500D01*
X-1305300Y695000D01*
Y680000D01*
G01X-1292150D02*
X-1299150D01*
Y695000D01*
X-1292150D01*
G01X-1294950Y687750D02*
X-1299150D01*
G01X-1281450Y695000D02*
Y680000D01*
G01X-1285475Y695000D02*
X-1277425D01*
G01X-1263750Y680000D02*
X-1270750D01*
Y695000D01*
X-1263750D01*
G01X-1266550Y687750D02*
X-1270750D01*
G01X-1256550Y680000D02*
Y695000D01*
X-1252175D01*
X-1250775Y694250D01*
X-1249900Y693250D01*
X-1249550Y691250D01*
X-1249900Y689250D01*
X-1250950Y688000D01*
X-1252175Y687250D01*
X-1256550D01*
G01X-1252175D02*
X-1249550Y680000D01*
G01X-1242525Y682000D02*
X-1241125Y680750D01*
X-1239550Y680000D01*
X-1238150D01*
X-1236750Y680750D01*
X-1235700Y682000D01*
X-1235175Y683750D01*
X-1235525Y685500D01*
X-1236400Y687000D01*
X-1237975Y688000D01*
X-1240075Y688500D01*
X-1241300Y689500D01*
X-1241825Y691250D01*
X-1241475Y693000D01*
X-1240600Y694250D01*
X-1239375Y695000D01*
X-1238150D01*
X-1236925Y694500D01*
X-1235875Y693250D01*
G01X-1214825Y680000D02*
X-1210450Y695000D01*
X-1206075Y680000D01*
G01X-1207650Y685250D02*
X-1213250D01*
G01X-1200275Y680000D02*
Y695000D01*
X-1192225Y680000D01*
Y695000D01*
G01X-1185900Y680000D02*
Y695000D01*
X-1182400D01*
X-1181000Y694250D01*
X-1179950Y693250D01*
X-1179075Y691750D01*
X-1178375Y690000D01*
X-1178200Y687500D01*
X-1178375Y685000D01*
X-1179075Y683250D01*
X-1179950Y681750D01*
X-1181000Y680750D01*
X-1182400Y680000D01*
X-1185900D01*
G01X-1155750Y695000D02*
X-1151550D01*
G01X-1153650D02*
Y680000D01*
G01X-1155750D02*
X-1151550D01*
G01X-1143475D02*
Y695000D01*
X-1135425Y680000D01*
Y695000D01*
G01X-1121400Y693750D02*
X-1122450Y694500D01*
X-1123675Y695000D01*
X-1125075D01*
X-1126650Y694250D01*
X-1127875Y693000D01*
X-1128750Y691500D01*
X-1129450Y689000D01*
X-1129625Y686750D01*
X-1129275Y684500D01*
X-1128750Y683000D01*
X-1127700Y681500D01*
X-1126475Y680500D01*
X-1125250Y680000D01*
X-1124025D01*
X-1122800Y680500D01*
X-1121750Y681250D01*
X-1120875Y682250D01*
G01X-1114725Y680000D02*
Y695000D01*
G01X-1107375D02*
Y680000D01*
G01Y687500D02*
X-1114725D01*
G01X-1093350Y680000D02*
X-1100350D01*
Y695000D01*
X-1093350D01*
G01X-1096150Y687750D02*
X-1100350D01*
G01X-1086325Y682000D02*
X-1084925Y680750D01*
X-1083350Y680000D01*
X-1081950D01*
X-1080550Y680750D01*
X-1079500Y682000D01*
X-1078975Y683750D01*
X-1079325Y685500D01*
X-1080200Y687000D01*
X-1081775Y688000D01*
X-1083875Y688500D01*
X-1085100Y689500D01*
X-1085625Y691250D01*
X-1085275Y693000D01*
X-1084400Y694250D01*
X-1083175Y695000D01*
X-1081950D01*
X-1080725Y694500D01*
X-1079675Y693250D01*
G01X-1068450Y679500D02*
X-1068800Y679750D01*
Y680250D01*
X-1068450Y680500D01*
X-1068100Y680250D01*
Y679750D01*
X-1068450Y679500D01*
G01X-1679050Y710000D02*
X-1677825Y710250D01*
X-1676425Y711000D01*
X-1675550Y712250D01*
X-1675200Y714000D01*
X-1675550Y715750D01*
X-1676600Y717250D01*
X-1678175Y718000D01*
X-1679925D01*
X-1680975Y718500D01*
X-1681850Y719750D01*
X-1682200Y721500D01*
X-1681675Y723250D01*
X-1680450Y724500D01*
X-1679050Y725000D01*
X-1677650Y724500D01*
X-1676425Y723250D01*
X-1675900Y721500D01*
X-1676250Y719750D01*
X-1677125Y718500D01*
X-1678175Y718000D01*
X-1679925D01*
X-1681500Y717250D01*
X-1682550Y715750D01*
X-1682900Y714000D01*
X-1682550Y712250D01*
X-1681675Y711000D01*
X-1680275Y710250D01*
X-1679050Y710000D01*
G01X-1664850Y709500D02*
X-1665200Y709750D01*
Y710250D01*
X-1664850Y710500D01*
X-1664500Y710250D01*
Y709750D01*
X-1664850Y709500D01*
G01X-1640825Y710000D02*
X-1636450Y725000D01*
X-1632075Y710000D01*
G01X-1633650Y715250D02*
X-1639250D01*
G01X-1625750Y725000D02*
Y710000D01*
X-1618750D01*
G01X-1611550Y725000D02*
Y710000D01*
X-1604550D01*
G01X-1583325D02*
Y725000D01*
G01X-1575975D02*
Y710000D01*
G01Y717500D02*
X-1583325D01*
G01X-1565450Y710000D02*
X-1566850Y710250D01*
X-1568075Y711250D01*
X-1569125Y712750D01*
X-1569825Y714500D01*
X-1570175Y716500D01*
Y718500D01*
X-1569825Y720500D01*
X-1569125Y722250D01*
X-1568075Y723750D01*
X-1566850Y724750D01*
X-1565450Y725000D01*
X-1564050Y724750D01*
X-1562825Y723750D01*
X-1561775Y722250D01*
X-1561075Y720500D01*
X-1560725Y718500D01*
Y716500D01*
X-1561075Y714500D01*
X-1561775Y712750D01*
X-1562825Y711250D01*
X-1564050Y710250D01*
X-1565450Y710000D01*
G01X-1554750Y725000D02*
Y710000D01*
X-1547750D01*
G01X-1533550D02*
X-1540550D01*
Y725000D01*
X-1533550D01*
G01X-1536350Y717750D02*
X-1540550D01*
G01X-1512325Y712000D02*
X-1510925Y710750D01*
X-1509350Y710000D01*
X-1507950D01*
X-1506550Y710750D01*
X-1505500Y712000D01*
X-1504975Y713750D01*
X-1505325Y715500D01*
X-1506200Y717000D01*
X-1507775Y718000D01*
X-1509875Y718500D01*
X-1511100Y719500D01*
X-1511625Y721250D01*
X-1511275Y723000D01*
X-1510400Y724250D01*
X-1509175Y725000D01*
X-1507950D01*
X-1506725Y724500D01*
X-1505675Y723250D01*
G01X-1496550Y725000D02*
X-1492350D01*
G01X-1494450D02*
Y710000D01*
G01X-1496550D02*
X-1492350D01*
G01X-1483575Y725000D02*
X-1476925D01*
X-1483575Y710000D01*
X-1476925D01*
G01X-1462550D02*
X-1469550D01*
Y725000D01*
X-1462550D01*
G01X-1465350Y717750D02*
X-1469550D01*
G01X-1455525Y712000D02*
X-1454125Y710750D01*
X-1452550Y710000D01*
X-1451150D01*
X-1449750Y710750D01*
X-1448700Y712000D01*
X-1448175Y713750D01*
X-1448525Y715500D01*
X-1449400Y717000D01*
X-1450975Y718000D01*
X-1453075Y718500D01*
X-1454300Y719500D01*
X-1454825Y721250D01*
X-1454475Y723000D01*
X-1453600Y724250D01*
X-1452375Y725000D01*
X-1451150D01*
X-1449925Y724500D01*
X-1448875Y723250D01*
G01X-1425550Y725000D02*
X-1421350D01*
G01X-1423450D02*
Y710000D01*
G01X-1425550D02*
X-1421350D01*
G01X-1413275D02*
Y725000D01*
X-1405225Y710000D01*
Y725000D01*
G01X-1384525Y710000D02*
Y725000D01*
G01X-1377175D02*
Y710000D01*
G01Y717500D02*
X-1384525D01*
G01X-1366650Y710000D02*
X-1368050Y710250D01*
X-1369275Y711250D01*
X-1370325Y712750D01*
X-1371025Y714500D01*
X-1371375Y716500D01*
Y718500D01*
X-1371025Y720500D01*
X-1370325Y722250D01*
X-1369275Y723750D01*
X-1368050Y724750D01*
X-1366650Y725000D01*
X-1365250Y724750D01*
X-1364025Y723750D01*
X-1362975Y722250D01*
X-1362275Y720500D01*
X-1361925Y718500D01*
Y716500D01*
X-1362275Y714500D01*
X-1362975Y712750D01*
X-1364025Y711250D01*
X-1365250Y710250D01*
X-1366650Y710000D01*
G01X-1355950Y725000D02*
Y710000D01*
X-1348950D01*
G01X-1334750D02*
X-1341750D01*
Y725000D01*
X-1334750D01*
G01X-1337550Y717750D02*
X-1341750D01*
G01X-1306000Y723750D02*
X-1307050Y724500D01*
X-1308275Y725000D01*
X-1309675D01*
X-1311250Y724250D01*
X-1312475Y723000D01*
X-1313350Y721500D01*
X-1314050Y719000D01*
X-1314225Y716750D01*
X-1313875Y714500D01*
X-1313350Y713000D01*
X-1312300Y711500D01*
X-1311075Y710500D01*
X-1309850Y710000D01*
X-1308625D01*
X-1307400Y710500D01*
X-1306350Y711250D01*
X-1305475Y712250D01*
G01X-1299325Y710000D02*
Y725000D01*
G01X-1291975D02*
Y710000D01*
G01Y717500D02*
X-1299325D01*
G01X-1285825Y710000D02*
X-1281450Y725000D01*
X-1277075Y710000D01*
G01X-1278650Y715250D02*
X-1284250D01*
G01X-1270750Y710000D02*
Y725000D01*
X-1266375D01*
X-1264975Y724250D01*
X-1264100Y723250D01*
X-1263750Y721250D01*
X-1264100Y719250D01*
X-1265150Y718000D01*
X-1266375Y717250D01*
X-1270750D01*
G01X-1266375D02*
X-1263750Y710000D01*
G01X-1253050Y725000D02*
Y710000D01*
G01X-1257075Y725000D02*
X-1249025D01*
G01X-1229025Y710000D02*
X-1224650Y725000D01*
X-1220275Y710000D01*
G01X-1221850Y715250D02*
X-1227450D01*
G01X-1213950Y710000D02*
Y725000D01*
X-1209575D01*
X-1208175Y724250D01*
X-1207300Y723250D01*
X-1206950Y721250D01*
X-1207300Y719250D01*
X-1208350Y718000D01*
X-1209575Y717250D01*
X-1213950D01*
G01X-1209575D02*
X-1206950Y710000D01*
G01X-1192750D02*
X-1199750D01*
Y725000D01*
X-1192750D01*
G01X-1195550Y717750D02*
X-1199750D01*
G01X-1171175Y710000D02*
Y725000D01*
X-1164525D01*
G01X-1166975Y717750D02*
X-1171175D01*
G01X-1155750Y725000D02*
X-1151550D01*
G01X-1153650D02*
Y710000D01*
G01X-1155750D02*
X-1151550D01*
G01X-1143475D02*
Y725000D01*
X-1135425Y710000D01*
Y725000D01*
G01X-1127350D02*
X-1123150D01*
G01X-1125250D02*
Y710000D01*
G01X-1127350D02*
X-1123150D01*
G01X-1114725Y712000D02*
X-1113325Y710750D01*
X-1111750Y710000D01*
X-1110350D01*
X-1108950Y710750D01*
X-1107900Y712000D01*
X-1107375Y713750D01*
X-1107725Y715500D01*
X-1108600Y717000D01*
X-1110175Y718000D01*
X-1112275Y718500D01*
X-1113500Y719500D01*
X-1114025Y721250D01*
X-1113675Y723000D01*
X-1112800Y724250D01*
X-1111575Y725000D01*
X-1110350D01*
X-1109125Y724500D01*
X-1108075Y723250D01*
G01X-1100525Y710000D02*
Y725000D01*
G01X-1093175D02*
Y710000D01*
G01Y717500D02*
X-1100525D01*
G01X-1079150Y710000D02*
X-1086150D01*
Y725000D01*
X-1079150D01*
G01X-1081950Y717750D02*
X-1086150D01*
G01X-1072300Y710000D02*
Y725000D01*
X-1068800D01*
X-1067400Y724250D01*
X-1066350Y723250D01*
X-1065475Y721750D01*
X-1064775Y720000D01*
X-1064600Y717500D01*
X-1064775Y715000D01*
X-1065475Y713250D01*
X-1066350Y711750D01*
X-1067400Y710750D01*
X-1068800Y710000D01*
X-1072300D01*
G01X-1043725D02*
Y725000D01*
G01X-1036375D02*
Y710000D01*
G01Y717500D02*
X-1043725D01*
G01X-1025850Y710000D02*
X-1027250Y710250D01*
X-1028475Y711250D01*
X-1029525Y712750D01*
X-1030225Y714500D01*
X-1030575Y716500D01*
Y718500D01*
X-1030225Y720500D01*
X-1029525Y722250D01*
X-1028475Y723750D01*
X-1027250Y724750D01*
X-1025850Y725000D01*
X-1024450Y724750D01*
X-1023225Y723750D01*
X-1022175Y722250D01*
X-1021475Y720500D01*
X-1021125Y718500D01*
Y716500D01*
X-1021475Y714500D01*
X-1022175Y712750D01*
X-1023225Y711250D01*
X-1024450Y710250D01*
X-1025850Y710000D01*
G01X-1015150Y725000D02*
Y710000D01*
X-1008150D01*
G01X-993950D02*
X-1000950D01*
Y725000D01*
X-993950D01*
G01X-996750Y717750D02*
X-1000950D01*
G01X-972725Y712000D02*
X-971325Y710750D01*
X-969750Y710000D01*
X-968350D01*
X-966950Y710750D01*
X-965900Y712000D01*
X-965375Y713750D01*
X-965725Y715500D01*
X-966600Y717000D01*
X-968175Y718000D01*
X-970275Y718500D01*
X-971500Y719500D01*
X-972025Y721250D01*
X-971675Y723000D01*
X-970800Y724250D01*
X-969575Y725000D01*
X-968350D01*
X-967125Y724500D01*
X-966075Y723250D01*
G01X-956950Y725000D02*
X-952750D01*
G01X-954850D02*
Y710000D01*
G01X-956950D02*
X-952750D01*
G01X-943975Y725000D02*
X-937325D01*
X-943975Y710000D01*
X-937325D01*
G01X-922950D02*
X-929950D01*
Y725000D01*
X-922950D01*
G01X-925750Y717750D02*
X-929950D01*
G01X-915925Y712000D02*
X-914525Y710750D01*
X-912950Y710000D01*
X-911550D01*
X-910150Y710750D01*
X-909100Y712000D01*
X-908575Y713750D01*
X-908925Y715500D01*
X-909800Y717000D01*
X-911375Y718000D01*
X-913475Y718500D01*
X-914700Y719500D01*
X-915225Y721250D01*
X-914875Y723000D01*
X-914000Y724250D01*
X-912775Y725000D01*
X-911550D01*
X-910325Y724500D01*
X-909275Y723250D01*
G01X-888225Y710000D02*
X-883850Y725000D01*
X-879475Y710000D01*
G01X-881050Y715250D02*
X-886650D01*
G01X-872975Y710000D02*
Y725000D01*
X-866325D01*
G01X-868775Y717750D02*
X-872975D01*
G01X-855450Y725000D02*
Y710000D01*
G01X-859475Y725000D02*
X-851425D01*
G01X-837750Y710000D02*
X-844750D01*
Y725000D01*
X-837750D01*
G01X-840550Y717750D02*
X-844750D01*
G01X-830550Y710000D02*
Y725000D01*
X-826175D01*
X-824775Y724250D01*
X-823900Y723250D01*
X-823550Y721250D01*
X-823900Y719250D01*
X-824950Y718000D01*
X-826175Y717250D01*
X-830550D01*
G01X-826175D02*
X-823550Y710000D01*
G01X-802150D02*
Y725000D01*
X-797950D01*
X-796550Y724250D01*
X-795500Y722500D01*
X-795150Y720500D01*
X-795500Y718500D01*
X-796375Y717000D01*
X-797950Y716250D01*
X-802150D01*
G01X-787950Y725000D02*
Y710000D01*
X-780950D01*
G01X-774625D02*
X-770250Y725000D01*
X-765875Y710000D01*
G01X-767450Y715250D02*
X-773050D01*
G01X-756050Y725000D02*
Y710000D01*
G01X-760075Y725000D02*
X-752025D01*
G01X-743950D02*
X-739750D01*
G01X-741850D02*
Y710000D01*
G01X-743950D02*
X-739750D01*
G01X-731675D02*
Y725000D01*
X-723625Y710000D01*
Y725000D01*
G01X-712400Y717500D02*
X-708900D01*
Y713000D01*
X-709950Y711500D01*
X-711175Y710500D01*
X-712925Y710000D01*
X-714675Y710500D01*
X-715900Y711500D01*
X-716950Y713000D01*
X-717650Y714750D01*
X-718000Y716750D01*
Y718500D01*
X-717650Y720000D01*
X-716950Y721750D01*
X-715900Y723250D01*
X-714850Y724250D01*
X-713450Y725000D01*
X-712225D01*
X-710825Y724500D01*
X-709775Y723500D01*
G01X-699250Y709500D02*
X-699600Y709750D01*
Y710250D01*
X-699250Y710500D01*
X-698900Y710250D01*
Y709750D01*
X-699250Y709500D01*
G01X-1636450Y760000D02*
Y745000D01*
G01X-1640475Y760000D02*
X-1632425D01*
G01X-1625750Y745000D02*
Y760000D01*
X-1621375D01*
X-1619975Y759250D01*
X-1619100Y758250D01*
X-1618750Y756250D01*
X-1619100Y754250D01*
X-1620150Y753000D01*
X-1621375Y752250D01*
X-1625750D01*
G01X-1621375D02*
X-1618750Y745000D01*
G01X-1612425D02*
X-1608050Y760000D01*
X-1603675Y745000D01*
G01X-1605250Y750250D02*
X-1610850D01*
G01X-1590000Y758750D02*
X-1591050Y759500D01*
X-1592275Y760000D01*
X-1593675D01*
X-1595250Y759250D01*
X-1596475Y758000D01*
X-1597350Y756500D01*
X-1598050Y754000D01*
X-1598225Y751750D01*
X-1597875Y749500D01*
X-1597350Y748000D01*
X-1596300Y746500D01*
X-1595075Y745500D01*
X-1593850Y745000D01*
X-1592625D01*
X-1591400Y745500D01*
X-1590350Y746250D01*
X-1589475Y747250D01*
G01X-1576150Y745000D02*
X-1583150D01*
Y760000D01*
X-1576150D01*
G01X-1578950Y752750D02*
X-1583150D01*
G01X-1556500Y760000D02*
X-1554050Y745000D01*
X-1551250Y760000D01*
X-1548450Y745000D01*
X-1546000Y760000D01*
G01X-1539150D02*
X-1534950D01*
G01X-1537050D02*
Y745000D01*
G01X-1539150D02*
X-1534950D01*
G01X-1526700D02*
Y760000D01*
X-1523200D01*
X-1521800Y759250D01*
X-1520750Y758250D01*
X-1519875Y756750D01*
X-1519175Y755000D01*
X-1519000Y752500D01*
X-1519175Y750000D01*
X-1519875Y748250D01*
X-1520750Y746750D01*
X-1521800Y745750D01*
X-1523200Y745000D01*
X-1526700D01*
G01X-1508650Y760000D02*
Y745000D01*
G01X-1512675Y760000D02*
X-1504625D01*
G01X-1498125Y745000D02*
Y760000D01*
G01X-1490775D02*
Y745000D01*
G01Y752500D02*
X-1498125D01*
G01X-1464650Y753000D02*
X-1463950Y753750D01*
X-1463425Y755000D01*
X-1463075Y756750D01*
X-1463425Y758250D01*
X-1464125Y759250D01*
X-1465350Y760000D01*
X-1470075D01*
Y745000D01*
X-1464300D01*
X-1463075Y746000D01*
X-1462375Y747500D01*
X-1462025Y749250D01*
X-1462375Y751000D01*
X-1463425Y752500D01*
X-1464650Y753000D01*
X-1470075D01*
G01X-1451850Y745000D02*
Y751750D01*
X-1455350Y760000D01*
G01X-1448350D02*
X-1451850Y751750D01*
G01X-1428000Y745000D02*
Y760000D01*
X-1423450Y747500D01*
X-1418900Y760000D01*
Y745000D01*
G01X-1409250D02*
X-1410650Y745250D01*
X-1411875Y746250D01*
X-1412925Y747750D01*
X-1413625Y749500D01*
X-1413975Y751500D01*
Y753500D01*
X-1413625Y755500D01*
X-1412925Y757250D01*
X-1411875Y758750D01*
X-1410650Y759750D01*
X-1409250Y760000D01*
X-1407850Y759750D01*
X-1406625Y758750D01*
X-1405575Y757250D01*
X-1404875Y755500D01*
X-1404525Y753500D01*
Y751500D01*
X-1404875Y749500D01*
X-1405575Y747750D01*
X-1406625Y746250D01*
X-1407850Y745250D01*
X-1409250Y745000D01*
G01X-1398550D02*
Y760000D01*
X-1394175D01*
X-1392775Y759250D01*
X-1391900Y758250D01*
X-1391550Y756250D01*
X-1391900Y754250D01*
X-1392950Y753000D01*
X-1394175Y752250D01*
X-1398550D01*
G01X-1394175D02*
X-1391550Y745000D01*
G01X-1377350D02*
X-1384350D01*
Y760000D01*
X-1377350D01*
G01X-1380150Y752750D02*
X-1384350D01*
G01X-1352450Y760000D02*
Y745000D01*
G01X-1356475Y760000D02*
X-1348425D01*
G01X-1341925Y745000D02*
Y760000D01*
G01X-1334575D02*
Y745000D01*
G01Y752500D02*
X-1341925D01*
G01X-1328425Y745000D02*
X-1324050Y760000D01*
X-1319675Y745000D01*
G01X-1321250Y750250D02*
X-1326850D01*
G01X-1313875Y745000D02*
Y760000D01*
X-1305825Y745000D01*
Y760000D01*
G01X-1284775Y757500D02*
X-1283725Y759000D01*
X-1282500Y759750D01*
X-1281100Y760000D01*
X-1279350Y759500D01*
X-1278125Y758250D01*
X-1277775Y756750D01*
X-1277950Y755250D01*
X-1278650Y754000D01*
X-1282150Y751500D01*
X-1283725Y749750D01*
X-1284775Y747250D01*
X-1285125Y745000D01*
X-1277775D01*
G01X-1271100Y747250D02*
X-1270050Y746000D01*
X-1268825Y745250D01*
X-1267250Y745000D01*
X-1265675Y745500D01*
X-1264450Y746500D01*
X-1263575Y748250D01*
X-1263400Y750250D01*
X-1263750Y752250D01*
X-1264625Y753500D01*
X-1265850Y754500D01*
X-1267075Y754750D01*
X-1268300Y754500D01*
X-1269875Y753500D01*
X-1269350Y760000D01*
X-1264625D01*
G01X-1256200Y744500D02*
X-1249900Y760000D01*
G01X-1256200D02*
X-1257250Y759500D01*
X-1257775Y758750D01*
X-1258125Y757250D01*
X-1257775Y755750D01*
X-1257250Y755000D01*
X-1256200Y754500D01*
X-1255150Y755000D01*
X-1254625Y755750D01*
X-1254275Y757250D01*
X-1254625Y758750D01*
X-1255150Y759500D01*
X-1256200Y760000D01*
G01X-1249900Y750000D02*
X-1250950Y749500D01*
X-1251475Y748750D01*
X-1251825Y747250D01*
X-1251475Y745750D01*
X-1250950Y745000D01*
X-1249900Y744500D01*
X-1248850Y745000D01*
X-1248325Y745750D01*
X-1247975Y747250D01*
X-1248325Y748750D01*
X-1248850Y749500D01*
X-1249900Y750000D01*
G01X-1228500Y760000D02*
Y749250D01*
X-1227800Y747000D01*
X-1226400Y745500D01*
X-1224650Y745000D01*
X-1222900Y745500D01*
X-1221500Y747000D01*
X-1220800Y749250D01*
Y760000D01*
G01X-1214475Y745000D02*
Y760000D01*
X-1206425Y745000D01*
Y760000D01*
G01X-1199750D02*
Y745000D01*
X-1192750D01*
G01X-1178550D02*
X-1185550D01*
Y760000D01*
X-1178550D01*
G01X-1181350Y752750D02*
X-1185550D01*
G01X-1171525Y747000D02*
X-1170125Y745750D01*
X-1168550Y745000D01*
X-1167150D01*
X-1165750Y745750D01*
X-1164700Y747000D01*
X-1164175Y748750D01*
X-1164525Y750500D01*
X-1165400Y752000D01*
X-1166975Y753000D01*
X-1169075Y753500D01*
X-1170300Y754500D01*
X-1170825Y756250D01*
X-1170475Y758000D01*
X-1169600Y759250D01*
X-1168375Y760000D01*
X-1167150D01*
X-1165925Y759500D01*
X-1164875Y758250D01*
G01X-1157325Y747000D02*
X-1155925Y745750D01*
X-1154350Y745000D01*
X-1152950D01*
X-1151550Y745750D01*
X-1150500Y747000D01*
X-1149975Y748750D01*
X-1150325Y750500D01*
X-1151200Y752000D01*
X-1152775Y753000D01*
X-1154875Y753500D01*
X-1156100Y754500D01*
X-1156625Y756250D01*
X-1156275Y758000D01*
X-1155400Y759250D01*
X-1154175Y760000D01*
X-1152950D01*
X-1151725Y759500D01*
X-1150675Y758250D01*
G01X-1125250Y745000D02*
X-1126650Y745250D01*
X-1127875Y746250D01*
X-1128925Y747750D01*
X-1129625Y749500D01*
X-1129975Y751500D01*
Y753500D01*
X-1129625Y755500D01*
X-1128925Y757250D01*
X-1127875Y758750D01*
X-1126650Y759750D01*
X-1125250Y760000D01*
X-1123850Y759750D01*
X-1122625Y758750D01*
X-1121575Y757250D01*
X-1120875Y755500D01*
X-1120525Y753500D01*
Y751500D01*
X-1120875Y749500D01*
X-1121575Y747750D01*
X-1122625Y746250D01*
X-1123850Y745250D01*
X-1125250Y745000D01*
G01X-1111050Y760000D02*
Y745000D01*
G01X-1115075Y760000D02*
X-1107025D01*
G01X-1100525Y745000D02*
Y760000D01*
G01X-1093175D02*
Y745000D01*
G01Y752500D02*
X-1100525D01*
G01X-1079150Y745000D02*
X-1086150D01*
Y760000D01*
X-1079150D01*
G01X-1081950Y752750D02*
X-1086150D01*
G01X-1071950Y745000D02*
Y760000D01*
X-1067575D01*
X-1066175Y759250D01*
X-1065300Y758250D01*
X-1064950Y756250D01*
X-1065300Y754250D01*
X-1066350Y753000D01*
X-1067575Y752250D01*
X-1071950D01*
G01X-1067575D02*
X-1064950Y745000D01*
G01X-1059500Y760000D02*
X-1057050Y745000D01*
X-1054250Y760000D01*
X-1051450Y745000D01*
X-1049000Y760000D01*
G01X-1042150D02*
X-1037950D01*
G01X-1040050D02*
Y745000D01*
G01X-1042150D02*
X-1037950D01*
G01X-1029525Y747000D02*
X-1028125Y745750D01*
X-1026550Y745000D01*
X-1025150D01*
X-1023750Y745750D01*
X-1022700Y747000D01*
X-1022175Y748750D01*
X-1022525Y750500D01*
X-1023400Y752000D01*
X-1024975Y753000D01*
X-1027075Y753500D01*
X-1028300Y754500D01*
X-1028825Y756250D01*
X-1028475Y758000D01*
X-1027600Y759250D01*
X-1026375Y760000D01*
X-1025150D01*
X-1023925Y759500D01*
X-1022875Y758250D01*
G01X-1008150Y745000D02*
X-1015150D01*
Y760000D01*
X-1008150D01*
G01X-1010950Y752750D02*
X-1015150D01*
G01X-986925Y747000D02*
X-985525Y745750D01*
X-983950Y745000D01*
X-982550D01*
X-981150Y745750D01*
X-980100Y747000D01*
X-979575Y748750D01*
X-979925Y750500D01*
X-980800Y752000D01*
X-982375Y753000D01*
X-984475Y753500D01*
X-985700Y754500D01*
X-986225Y756250D01*
X-985875Y758000D01*
X-985000Y759250D01*
X-983775Y760000D01*
X-982550D01*
X-981325Y759500D01*
X-980275Y758250D01*
G01X-972550Y745000D02*
Y760000D01*
X-968350D01*
X-966950Y759250D01*
X-965900Y757500D01*
X-965550Y755500D01*
X-965900Y753500D01*
X-966775Y752000D01*
X-968350Y751250D01*
X-972550D01*
G01X-951350Y745000D02*
X-958350D01*
Y760000D01*
X-951350D01*
G01X-954150Y752750D02*
X-958350D01*
G01X-936800Y758750D02*
X-937850Y759500D01*
X-939075Y760000D01*
X-940475D01*
X-942050Y759250D01*
X-943275Y758000D01*
X-944150Y756500D01*
X-944850Y754000D01*
X-945025Y751750D01*
X-944675Y749500D01*
X-944150Y748000D01*
X-943100Y746500D01*
X-941875Y745500D01*
X-940650Y745000D01*
X-939425D01*
X-938200Y745500D01*
X-937150Y746250D01*
X-936275Y747250D01*
G01X-928550Y760000D02*
X-924350D01*
G01X-926450D02*
Y745000D01*
G01X-928550D02*
X-924350D01*
G01X-915575D02*
Y760000D01*
X-908925D01*
G01X-911375Y752750D02*
X-915575D01*
G01X-900150Y760000D02*
X-895950D01*
G01X-898050D02*
Y745000D01*
G01X-900150D02*
X-895950D01*
G01X-880350D02*
X-887350D01*
Y760000D01*
X-880350D01*
G01X-883150Y752750D02*
X-887350D01*
G01X-873500Y745000D02*
Y760000D01*
X-870000D01*
X-868600Y759250D01*
X-867550Y758250D01*
X-866675Y756750D01*
X-865975Y755000D01*
X-865800Y752500D01*
X-865975Y750000D01*
X-866675Y748250D01*
X-867550Y746750D01*
X-868600Y745750D01*
X-870000Y745000D01*
X-873500D01*
G01X-855450Y744500D02*
X-855800Y744750D01*
Y745250D01*
X-855450Y745500D01*
X-855100Y745250D01*
Y744750D01*
X-855450Y744500D01*
G01X-1679400Y775000D02*
X-1679050Y778250D01*
X-1678525Y781000D01*
X-1677825Y783500D01*
X-1676950Y786250D01*
X-1675550Y790000D01*
X-1682550D01*
G01X-1664850Y774500D02*
X-1665200Y774750D01*
Y775250D01*
X-1664850Y775500D01*
X-1664500Y775250D01*
Y774750D01*
X-1664850Y774500D01*
G01X-1635050Y783000D02*
X-1634350Y783750D01*
X-1633825Y785000D01*
X-1633475Y786750D01*
X-1633825Y788250D01*
X-1634525Y789250D01*
X-1635750Y790000D01*
X-1640475D01*
Y775000D01*
X-1634700D01*
X-1633475Y776000D01*
X-1632775Y777500D01*
X-1632425Y779250D01*
X-1632775Y781000D01*
X-1633825Y782500D01*
X-1635050Y783000D01*
X-1640475D01*
G01X-1625750Y775000D02*
Y790000D01*
X-1621375D01*
X-1619975Y789250D01*
X-1619100Y788250D01*
X-1618750Y786250D01*
X-1619100Y784250D01*
X-1620150Y783000D01*
X-1621375Y782250D01*
X-1625750D01*
G01X-1621375D02*
X-1618750Y775000D01*
G01X-1604550D02*
X-1611550D01*
Y790000D01*
X-1604550D01*
G01X-1607350Y782750D02*
X-1611550D01*
G01X-1598225Y775000D02*
X-1593850Y790000D01*
X-1589475Y775000D01*
G01X-1591050Y780250D02*
X-1596650D01*
G01X-1583500Y775000D02*
Y790000D01*
G01X-1576850D02*
X-1583500Y780750D01*
G01X-1575800Y775000D02*
X-1580525Y785000D01*
G01X-1565450Y775000D02*
X-1566850Y775250D01*
X-1568075Y776250D01*
X-1569125Y777750D01*
X-1569825Y779500D01*
X-1570175Y781500D01*
Y783500D01*
X-1569825Y785500D01*
X-1569125Y787250D01*
X-1568075Y788750D01*
X-1566850Y789750D01*
X-1565450Y790000D01*
X-1564050Y789750D01*
X-1562825Y788750D01*
X-1561775Y787250D01*
X-1561075Y785500D01*
X-1560725Y783500D01*
Y781500D01*
X-1561075Y779500D01*
X-1561775Y777750D01*
X-1562825Y776250D01*
X-1564050Y775250D01*
X-1565450Y775000D01*
G01X-1555100Y790000D02*
Y779250D01*
X-1554400Y777000D01*
X-1553000Y775500D01*
X-1551250Y775000D01*
X-1549500Y775500D01*
X-1548100Y777000D01*
X-1547400Y779250D01*
Y790000D01*
G01X-1537050D02*
Y775000D01*
G01X-1541075Y790000D02*
X-1533025D01*
G01X-1510750D02*
X-1506550D01*
G01X-1508650D02*
Y775000D01*
G01X-1510750D02*
X-1506550D01*
G01X-1498475D02*
Y790000D01*
X-1490425Y775000D01*
Y790000D01*
G01X-1466050D02*
Y775000D01*
G01X-1470075Y790000D02*
X-1462025D01*
G01X-1455525Y775000D02*
Y790000D01*
G01X-1448175D02*
Y775000D01*
G01Y782500D02*
X-1455525D01*
G01X-1434150Y775000D02*
X-1441150D01*
Y790000D01*
X-1434150D01*
G01X-1436950Y782750D02*
X-1441150D01*
G01X-1412750Y775000D02*
Y790000D01*
X-1408375D01*
X-1406975Y789250D01*
X-1406100Y788250D01*
X-1405750Y786250D01*
X-1406100Y784250D01*
X-1407150Y783000D01*
X-1408375Y782250D01*
X-1412750D01*
G01X-1408375D02*
X-1405750Y775000D01*
G01X-1391550D02*
X-1398550D01*
Y790000D01*
X-1391550D01*
G01X-1394350Y782750D02*
X-1398550D01*
G01X-1379800Y782500D02*
X-1376300D01*
Y778000D01*
X-1377350Y776500D01*
X-1378575Y775500D01*
X-1380325Y775000D01*
X-1382075Y775500D01*
X-1383300Y776500D01*
X-1384350Y778000D01*
X-1385050Y779750D01*
X-1385400Y781750D01*
Y783500D01*
X-1385050Y785000D01*
X-1384350Y786750D01*
X-1383300Y788250D01*
X-1382250Y789250D01*
X-1380850Y790000D01*
X-1379625D01*
X-1378225Y789500D01*
X-1377175Y788500D01*
G01X-1368750Y790000D02*
X-1364550D01*
G01X-1366650D02*
Y775000D01*
G01X-1368750D02*
X-1364550D01*
G01X-1352450D02*
X-1353850Y775250D01*
X-1355075Y776250D01*
X-1356125Y777750D01*
X-1356825Y779500D01*
X-1357175Y781500D01*
Y783500D01*
X-1356825Y785500D01*
X-1356125Y787250D01*
X-1355075Y788750D01*
X-1353850Y789750D01*
X-1352450Y790000D01*
X-1351050Y789750D01*
X-1349825Y788750D01*
X-1348775Y787250D01*
X-1348075Y785500D01*
X-1347725Y783500D01*
Y781500D01*
X-1348075Y779500D01*
X-1348775Y777750D01*
X-1349825Y776250D01*
X-1351050Y775250D01*
X-1352450Y775000D01*
G01X-1342275D02*
Y790000D01*
X-1334225Y775000D01*
Y790000D01*
G01X-1309850Y775000D02*
X-1311250Y775250D01*
X-1312475Y776250D01*
X-1313525Y777750D01*
X-1314225Y779500D01*
X-1314575Y781500D01*
Y783500D01*
X-1314225Y785500D01*
X-1313525Y787250D01*
X-1312475Y788750D01*
X-1311250Y789750D01*
X-1309850Y790000D01*
X-1308450Y789750D01*
X-1307225Y788750D01*
X-1306175Y787250D01*
X-1305475Y785500D01*
X-1305125Y783500D01*
Y781500D01*
X-1305475Y779500D01*
X-1306175Y777750D01*
X-1307225Y776250D01*
X-1308450Y775250D01*
X-1309850Y775000D01*
G01X-1298975D02*
Y790000D01*
X-1292325D01*
G01X-1294775Y782750D02*
X-1298975D01*
G01X-1267250Y790000D02*
Y775000D01*
G01X-1271275Y790000D02*
X-1263225D01*
G01X-1256725Y775000D02*
Y790000D01*
G01X-1249375D02*
Y775000D01*
G01Y782500D02*
X-1256725D01*
G01X-1235350Y775000D02*
X-1242350D01*
Y790000D01*
X-1235350D01*
G01X-1238150Y782750D02*
X-1242350D01*
G01X-1210450Y790000D02*
Y775000D01*
G01X-1214475Y790000D02*
X-1206425D01*
G01X-1199750Y775000D02*
Y790000D01*
X-1195375D01*
X-1193975Y789250D01*
X-1193100Y788250D01*
X-1192750Y786250D01*
X-1193100Y784250D01*
X-1194150Y783000D01*
X-1195375Y782250D01*
X-1199750D01*
G01X-1195375D02*
X-1192750Y775000D01*
G01X-1186425D02*
X-1182050Y790000D01*
X-1177675Y775000D01*
G01X-1179250Y780250D02*
X-1184850D01*
G01X-1164000Y788750D02*
X-1165050Y789500D01*
X-1166275Y790000D01*
X-1167675D01*
X-1169250Y789250D01*
X-1170475Y788000D01*
X-1171350Y786500D01*
X-1172050Y784000D01*
X-1172225Y781750D01*
X-1171875Y779500D01*
X-1171350Y778000D01*
X-1170300Y776500D01*
X-1169075Y775500D01*
X-1167850Y775000D01*
X-1166625D01*
X-1165400Y775500D01*
X-1164350Y776250D01*
X-1163475Y777250D01*
G01X-1150150Y775000D02*
X-1157150D01*
Y790000D01*
X-1150150D01*
G01X-1152950Y782750D02*
X-1157150D01*
G01X-1142600Y774500D02*
X-1136300Y790000D01*
G01X-1128750Y775000D02*
Y790000D01*
X-1124550D01*
X-1123150Y789250D01*
X-1122100Y787500D01*
X-1121750Y785500D01*
X-1122100Y783500D01*
X-1122975Y782000D01*
X-1124550Y781250D01*
X-1128750D01*
G01X-1115425Y775000D02*
X-1111050Y790000D01*
X-1106675Y775000D01*
G01X-1108250Y780250D02*
X-1113850D01*
G01X-1100700Y775000D02*
Y790000D01*
X-1097200D01*
X-1095800Y789250D01*
X-1094750Y788250D01*
X-1093875Y786750D01*
X-1093175Y785000D01*
X-1093000Y782500D01*
X-1093175Y780000D01*
X-1093875Y778250D01*
X-1094750Y776750D01*
X-1095800Y775750D01*
X-1097200Y775000D01*
X-1100700D01*
G01X-1071950Y778000D02*
X-1071075Y776500D01*
X-1070025Y775500D01*
X-1068800Y775000D01*
X-1067400Y775500D01*
X-1066350Y776500D01*
X-1065300Y778000D01*
X-1064950Y780000D01*
Y790000D01*
G01X-1058100D02*
Y779250D01*
X-1057400Y777000D01*
X-1056000Y775500D01*
X-1054250Y775000D01*
X-1052500Y775500D01*
X-1051100Y777000D01*
X-1050400Y779250D01*
Y790000D01*
G01X-1044075Y775000D02*
Y790000D01*
X-1036025Y775000D01*
Y790000D01*
G01X-1022000Y788750D02*
X-1023050Y789500D01*
X-1024275Y790000D01*
X-1025675D01*
X-1027250Y789250D01*
X-1028475Y788000D01*
X-1029350Y786500D01*
X-1030050Y784000D01*
X-1030225Y781750D01*
X-1029875Y779500D01*
X-1029350Y778000D01*
X-1028300Y776500D01*
X-1027075Y775500D01*
X-1025850Y775000D01*
X-1024625D01*
X-1023400Y775500D01*
X-1022350Y776250D01*
X-1021475Y777250D01*
G01X-1011650Y790000D02*
Y775000D01*
G01X-1015675Y790000D02*
X-1007625D01*
G01X-999550D02*
X-995350D01*
G01X-997450D02*
Y775000D01*
G01X-999550D02*
X-995350D01*
G01X-983250D02*
X-984650Y775250D01*
X-985875Y776250D01*
X-986925Y777750D01*
X-987625Y779500D01*
X-987975Y781500D01*
Y783500D01*
X-987625Y785500D01*
X-986925Y787250D01*
X-985875Y788750D01*
X-984650Y789750D01*
X-983250Y790000D01*
X-981850Y789750D01*
X-980625Y788750D01*
X-979575Y787250D01*
X-978875Y785500D01*
X-978525Y783500D01*
Y781500D01*
X-978875Y779500D01*
X-979575Y777750D01*
X-980625Y776250D01*
X-981850Y775250D01*
X-983250Y775000D01*
G01X-973075D02*
Y790000D01*
X-965025Y775000D01*
Y790000D01*
G01X-944325Y777000D02*
X-942925Y775750D01*
X-941350Y775000D01*
X-939950D01*
X-938550Y775750D01*
X-937500Y777000D01*
X-936975Y778750D01*
X-937325Y780500D01*
X-938200Y782000D01*
X-939775Y783000D01*
X-941875Y783500D01*
X-943100Y784500D01*
X-943625Y786250D01*
X-943275Y788000D01*
X-942400Y789250D01*
X-941175Y790000D01*
X-939950D01*
X-938725Y789500D01*
X-937675Y788250D01*
G01X-930125Y775000D02*
Y790000D01*
G01X-922775D02*
Y775000D01*
G01Y782500D02*
X-930125D01*
G01X-916625Y775000D02*
X-912250Y790000D01*
X-907875Y775000D01*
G01X-909450Y780250D02*
X-915050D01*
G01X-901550Y790000D02*
Y775000D01*
X-894550D01*
G01X-887350Y790000D02*
Y775000D01*
X-880350D01*
G01X-859475D02*
Y790000D01*
X-851425Y775000D01*
Y790000D01*
G01X-841250Y775000D02*
X-842650Y775250D01*
X-843875Y776250D01*
X-844925Y777750D01*
X-845625Y779500D01*
X-845975Y781500D01*
Y783500D01*
X-845625Y785500D01*
X-844925Y787250D01*
X-843875Y788750D01*
X-842650Y789750D01*
X-841250Y790000D01*
X-839850Y789750D01*
X-838625Y788750D01*
X-837575Y787250D01*
X-836875Y785500D01*
X-836525Y783500D01*
Y781500D01*
X-836875Y779500D01*
X-837575Y777750D01*
X-838625Y776250D01*
X-839850Y775250D01*
X-841250Y775000D01*
G01X-827050Y790000D02*
Y775000D01*
G01X-831075Y790000D02*
X-823025D01*
G01X-802150Y775000D02*
Y790000D01*
X-797775D01*
X-796375Y789250D01*
X-795500Y788250D01*
X-795150Y786250D01*
X-795500Y784250D01*
X-796550Y783000D01*
X-797775Y782250D01*
X-802150D01*
G01X-797775D02*
X-795150Y775000D01*
G01X-780950D02*
X-787950D01*
Y790000D01*
X-780950D01*
G01X-783750Y782750D02*
X-787950D01*
G01X-774100Y775000D02*
Y790000D01*
X-770600D01*
X-769200Y789250D01*
X-768150Y788250D01*
X-767275Y786750D01*
X-766575Y785000D01*
X-766400Y782500D01*
X-766575Y780000D01*
X-767275Y778250D01*
X-768150Y776750D01*
X-769200Y775750D01*
X-770600Y775000D01*
X-774100D01*
G01X-759900Y790000D02*
Y779250D01*
X-759200Y777000D01*
X-757800Y775500D01*
X-756050Y775000D01*
X-754300Y775500D01*
X-752900Y777000D01*
X-752200Y779250D01*
Y790000D01*
G01X-738000Y788750D02*
X-739050Y789500D01*
X-740275Y790000D01*
X-741675D01*
X-743250Y789250D01*
X-744475Y788000D01*
X-745350Y786500D01*
X-746050Y784000D01*
X-746225Y781750D01*
X-745875Y779500D01*
X-745350Y778000D01*
X-744300Y776500D01*
X-743075Y775500D01*
X-741850Y775000D01*
X-740625D01*
X-739400Y775500D01*
X-738350Y776250D01*
X-737475Y777250D01*
G01X-724150Y775000D02*
X-731150D01*
Y790000D01*
X-724150D01*
G01X-726950Y782750D02*
X-731150D01*
G01X-699250Y790000D02*
Y775000D01*
G01X-703275Y790000D02*
X-695225D01*
G01X-688725Y775000D02*
Y790000D01*
G01X-681375D02*
Y775000D01*
G01Y782500D02*
X-688725D01*
G01X-667350Y775000D02*
X-674350D01*
Y790000D01*
X-667350D01*
G01X-670150Y782750D02*
X-674350D01*
G01X-1682375Y816250D02*
X-1681150Y818000D01*
X-1680100Y819000D01*
X-1678700Y819500D01*
X-1677475Y819000D01*
X-1676600Y818000D01*
X-1675900Y816500D01*
X-1675725Y814750D01*
X-1675900Y813250D01*
X-1676600Y811750D01*
X-1677650Y810500D01*
X-1678875Y810000D01*
X-1680275Y810500D01*
X-1681500Y812000D01*
X-1682200Y814250D01*
X-1682375Y816750D01*
X-1682025Y820000D01*
X-1681500Y821750D01*
X-1680625Y823500D01*
X-1679400Y824750D01*
X-1678175Y825000D01*
X-1676950Y824500D01*
X-1676075Y823250D01*
G01X-1664850Y809500D02*
X-1665200Y809750D01*
Y810250D01*
X-1664850Y810500D01*
X-1664500Y810250D01*
Y809750D01*
X-1664850Y809500D01*
G01X-1635050Y818000D02*
X-1634350Y818750D01*
X-1633825Y820000D01*
X-1633475Y821750D01*
X-1633825Y823250D01*
X-1634525Y824250D01*
X-1635750Y825000D01*
X-1640475D01*
Y810000D01*
X-1634700D01*
X-1633475Y811000D01*
X-1632775Y812500D01*
X-1632425Y814250D01*
X-1632775Y816000D01*
X-1633825Y817500D01*
X-1635050Y818000D01*
X-1640475D01*
G01X-1622250Y810000D02*
X-1623650Y810250D01*
X-1624875Y811250D01*
X-1625925Y812750D01*
X-1626625Y814500D01*
X-1626975Y816500D01*
Y818500D01*
X-1626625Y820500D01*
X-1625925Y822250D01*
X-1624875Y823750D01*
X-1623650Y824750D01*
X-1622250Y825000D01*
X-1620850Y824750D01*
X-1619625Y823750D01*
X-1618575Y822250D01*
X-1617875Y820500D01*
X-1617525Y818500D01*
Y816500D01*
X-1617875Y814500D01*
X-1618575Y812750D01*
X-1619625Y811250D01*
X-1620850Y810250D01*
X-1622250Y810000D01*
G01X-1612425D02*
X-1608050Y825000D01*
X-1603675Y810000D01*
G01X-1605250Y815250D02*
X-1610850D01*
G01X-1597350Y810000D02*
Y825000D01*
X-1592975D01*
X-1591575Y824250D01*
X-1590700Y823250D01*
X-1590350Y821250D01*
X-1590700Y819250D01*
X-1591750Y818000D01*
X-1592975Y817250D01*
X-1597350D01*
G01X-1592975D02*
X-1590350Y810000D01*
G01X-1583500D02*
Y825000D01*
X-1580000D01*
X-1578600Y824250D01*
X-1577550Y823250D01*
X-1576675Y821750D01*
X-1575975Y820000D01*
X-1575800Y817500D01*
X-1575975Y815000D01*
X-1576675Y813250D01*
X-1577550Y811750D01*
X-1578600Y810750D01*
X-1580000Y810000D01*
X-1583500D01*
G01X-1555800D02*
Y825000D01*
X-1551250Y812500D01*
X-1546700Y825000D01*
Y810000D01*
G01X-1540900Y825000D02*
Y814250D01*
X-1540200Y812000D01*
X-1538800Y810500D01*
X-1537050Y810000D01*
X-1535300Y810500D01*
X-1533900Y812000D01*
X-1533200Y814250D01*
Y825000D01*
G01X-1526525Y812000D02*
X-1525125Y810750D01*
X-1523550Y810000D01*
X-1522150D01*
X-1520750Y810750D01*
X-1519700Y812000D01*
X-1519175Y813750D01*
X-1519525Y815500D01*
X-1520400Y817000D01*
X-1521975Y818000D01*
X-1524075Y818500D01*
X-1525300Y819500D01*
X-1525825Y821250D01*
X-1525475Y823000D01*
X-1524600Y824250D01*
X-1523375Y825000D01*
X-1522150D01*
X-1520925Y824500D01*
X-1519875Y823250D01*
G01X-1508650Y825000D02*
Y810000D01*
G01X-1512675Y825000D02*
X-1504625D01*
G01X-1478850Y818000D02*
X-1478150Y818750D01*
X-1477625Y820000D01*
X-1477275Y821750D01*
X-1477625Y823250D01*
X-1478325Y824250D01*
X-1479550Y825000D01*
X-1484275D01*
Y810000D01*
X-1478500D01*
X-1477275Y811000D01*
X-1476575Y812500D01*
X-1476225Y814250D01*
X-1476575Y816000D01*
X-1477625Y817500D01*
X-1478850Y818000D01*
X-1484275D01*
G01X-1462550Y810000D02*
X-1469550D01*
Y825000D01*
X-1462550D01*
G01X-1465350Y817750D02*
X-1469550D01*
G01X-1441500Y825000D02*
Y814250D01*
X-1440800Y812000D01*
X-1439400Y810500D01*
X-1437650Y810000D01*
X-1435900Y810500D01*
X-1434500Y812000D01*
X-1433800Y814250D01*
Y825000D01*
G01X-1426950D02*
Y810000D01*
X-1419950D01*
G01X-1398025Y811750D02*
X-1396800Y810500D01*
X-1395400Y810000D01*
X-1394000Y810500D01*
X-1392775Y812000D01*
X-1391900Y814250D01*
X-1391550Y816500D01*
Y819250D01*
X-1391900Y821500D01*
X-1392775Y823500D01*
X-1393825Y824500D01*
X-1395050Y825000D01*
X-1396450Y824500D01*
X-1397500Y823500D01*
X-1398200Y822000D01*
X-1398550Y820000D01*
X-1398200Y818250D01*
X-1397325Y816500D01*
X-1396275Y815500D01*
X-1395050Y815250D01*
X-1393650Y815750D01*
X-1392600Y817000D01*
X-1391550Y819250D01*
G01X-1378750Y810000D02*
Y825000D01*
X-1385225Y814250D01*
X-1376475D01*
G01X-1371025Y825000D02*
X-1366650Y810000D01*
X-1362275Y825000D01*
G01X-1354725Y815000D02*
X-1350175D01*
G01X-1338250Y825000D02*
X-1339650Y824500D01*
X-1340700Y823250D01*
X-1341400Y821750D01*
X-1341925Y819750D01*
X-1342100Y817500D01*
X-1341925Y815250D01*
X-1341400Y813250D01*
X-1340700Y811750D01*
X-1339650Y810500D01*
X-1338250Y810000D01*
X-1336850Y810500D01*
X-1335800Y811750D01*
X-1335100Y813250D01*
X-1334575Y815250D01*
X-1334400Y817500D01*
X-1334575Y819750D01*
X-1335100Y821750D01*
X-1335800Y823250D01*
X-1336850Y824500D01*
X-1338250Y825000D01*
G01X-1314225Y810000D02*
X-1309850Y825000D01*
X-1305475Y810000D01*
G01X-1307050Y815250D02*
X-1312650D01*
G01X-1299150Y810000D02*
Y825000D01*
X-1294950D01*
X-1293550Y824250D01*
X-1292500Y822500D01*
X-1292150Y820500D01*
X-1292500Y818500D01*
X-1293375Y817000D01*
X-1294950Y816250D01*
X-1299150D01*
G01X-1284950Y810000D02*
Y825000D01*
X-1280750D01*
X-1279350Y824250D01*
X-1278300Y822500D01*
X-1277950Y820500D01*
X-1278300Y818500D01*
X-1279175Y817000D01*
X-1280750Y816250D01*
X-1284950D01*
G01X-1270750Y810000D02*
Y825000D01*
X-1266375D01*
X-1264975Y824250D01*
X-1264100Y823250D01*
X-1263750Y821250D01*
X-1264100Y819250D01*
X-1265150Y818000D01*
X-1266375Y817250D01*
X-1270750D01*
G01X-1266375D02*
X-1263750Y810000D01*
G01X-1253050D02*
X-1254450Y810250D01*
X-1255675Y811250D01*
X-1256725Y812750D01*
X-1257425Y814500D01*
X-1257775Y816500D01*
Y818500D01*
X-1257425Y820500D01*
X-1256725Y822250D01*
X-1255675Y823750D01*
X-1254450Y824750D01*
X-1253050Y825000D01*
X-1251650Y824750D01*
X-1250425Y823750D01*
X-1249375Y822250D01*
X-1248675Y820500D01*
X-1248325Y818500D01*
Y816500D01*
X-1248675Y814500D01*
X-1249375Y812750D01*
X-1250425Y811250D01*
X-1251650Y810250D01*
X-1253050Y810000D01*
G01X-1243225Y825000D02*
X-1238850Y810000D01*
X-1234475Y825000D01*
G01X-1221150Y810000D02*
X-1228150D01*
Y825000D01*
X-1221150D01*
G01X-1223950Y817750D02*
X-1228150D01*
G01X-1214300Y810000D02*
Y825000D01*
X-1210800D01*
X-1209400Y824250D01*
X-1208350Y823250D01*
X-1207475Y821750D01*
X-1206775Y820000D01*
X-1206600Y817500D01*
X-1206775Y815000D01*
X-1207475Y813250D01*
X-1208350Y811750D01*
X-1209400Y810750D01*
X-1210800Y810000D01*
X-1214300D01*
G01X-1682900Y847250D02*
X-1681850Y846000D01*
X-1680625Y845250D01*
X-1679050Y845000D01*
X-1677475Y845500D01*
X-1676250Y846500D01*
X-1675375Y848250D01*
X-1675200Y850250D01*
X-1675550Y852250D01*
X-1676425Y853500D01*
X-1677650Y854500D01*
X-1678875Y854750D01*
X-1680100Y854500D01*
X-1681675Y853500D01*
X-1681150Y860000D01*
X-1676425D01*
G01X-1636450D02*
Y845000D01*
G01X-1640475Y860000D02*
X-1632425D01*
G01X-1625925Y845000D02*
Y860000D01*
G01X-1618575D02*
Y845000D01*
G01Y852500D02*
X-1625925D01*
G01X-1604550Y845000D02*
X-1611550D01*
Y860000D01*
X-1604550D01*
G01X-1607350Y852750D02*
X-1611550D01*
G01X-1597525Y847000D02*
X-1596125Y845750D01*
X-1594550Y845000D01*
X-1593150D01*
X-1591750Y845750D01*
X-1590700Y847000D01*
X-1590175Y848750D01*
X-1590525Y850500D01*
X-1591400Y852000D01*
X-1592975Y853000D01*
X-1595075Y853500D01*
X-1596300Y854500D01*
X-1596825Y856250D01*
X-1596475Y858000D01*
X-1595600Y859250D01*
X-1594375Y860000D01*
X-1593150D01*
X-1591925Y859500D01*
X-1590875Y858250D01*
G01X-1576150Y845000D02*
X-1583150D01*
Y860000D01*
X-1576150D01*
G01X-1578950Y852750D02*
X-1583150D01*
G01X-1554925Y845000D02*
Y860000D01*
G01X-1547575D02*
Y845000D01*
G01Y852500D02*
X-1554925D01*
G01X-1537050Y845000D02*
X-1538450Y845250D01*
X-1539675Y846250D01*
X-1540725Y847750D01*
X-1541425Y849500D01*
X-1541775Y851500D01*
Y853500D01*
X-1541425Y855500D01*
X-1540725Y857250D01*
X-1539675Y858750D01*
X-1538450Y859750D01*
X-1537050Y860000D01*
X-1535650Y859750D01*
X-1534425Y858750D01*
X-1533375Y857250D01*
X-1532675Y855500D01*
X-1532325Y853500D01*
Y851500D01*
X-1532675Y849500D01*
X-1533375Y847750D01*
X-1534425Y846250D01*
X-1535650Y845250D01*
X-1537050Y845000D01*
G01X-1526350Y860000D02*
Y845000D01*
X-1519350D01*
G01X-1505150D02*
X-1512150D01*
Y860000D01*
X-1505150D01*
G01X-1507950Y852750D02*
X-1512150D01*
G01X-1498125Y847000D02*
X-1496725Y845750D01*
X-1495150Y845000D01*
X-1493750D01*
X-1492350Y845750D01*
X-1491300Y847000D01*
X-1490775Y848750D01*
X-1491125Y850500D01*
X-1492000Y852000D01*
X-1493575Y853000D01*
X-1495675Y853500D01*
X-1496900Y854500D01*
X-1497425Y856250D01*
X-1497075Y858000D01*
X-1496200Y859250D01*
X-1494975Y860000D01*
X-1493750D01*
X-1492525Y859500D01*
X-1491475Y858250D01*
G01X-1470600Y845000D02*
Y860000D01*
X-1466050Y847500D01*
X-1461500Y860000D01*
Y845000D01*
G01X-1456225D02*
X-1451850Y860000D01*
X-1447475Y845000D01*
G01X-1449050Y850250D02*
X-1454650D01*
G01X-1437650Y845000D02*
Y851750D01*
X-1441150Y860000D01*
G01X-1434150D02*
X-1437650Y851750D01*
G01X-1407850Y853000D02*
X-1407150Y853750D01*
X-1406625Y855000D01*
X-1406275Y856750D01*
X-1406625Y858250D01*
X-1407325Y859250D01*
X-1408550Y860000D01*
X-1413275D01*
Y845000D01*
X-1407500D01*
X-1406275Y846000D01*
X-1405575Y847500D01*
X-1405225Y849250D01*
X-1405575Y851000D01*
X-1406625Y852500D01*
X-1407850Y853000D01*
X-1413275D01*
G01X-1391550Y845000D02*
X-1398550D01*
Y860000D01*
X-1391550D01*
G01X-1394350Y852750D02*
X-1398550D01*
G01X-1370150Y845000D02*
Y860000D01*
X-1365950D01*
X-1364550Y859250D01*
X-1363500Y857500D01*
X-1363150Y855500D01*
X-1363500Y853500D01*
X-1364375Y852000D01*
X-1365950Y851250D01*
X-1370150D01*
G01X-1355950Y860000D02*
Y845000D01*
X-1348950D01*
G01X-1342625D02*
X-1338250Y860000D01*
X-1333875Y845000D01*
G01X-1335450Y850250D02*
X-1341050D01*
G01X-1324050Y860000D02*
Y845000D01*
G01X-1328075Y860000D02*
X-1320025D01*
G01X-1306350Y845000D02*
X-1313350D01*
Y860000D01*
X-1306350D01*
G01X-1309150Y852750D02*
X-1313350D01*
G01X-1299500Y845000D02*
Y860000D01*
X-1296000D01*
X-1294600Y859250D01*
X-1293550Y858250D01*
X-1292675Y856750D01*
X-1291975Y855000D01*
X-1291800Y852500D01*
X-1291975Y850000D01*
X-1292675Y848250D01*
X-1293550Y846750D01*
X-1294600Y845750D01*
X-1296000Y845000D01*
X-1299500D01*
G01X-1270925Y847000D02*
X-1269525Y845750D01*
X-1267950Y845000D01*
X-1266550D01*
X-1265150Y845750D01*
X-1264100Y847000D01*
X-1263575Y848750D01*
X-1263925Y850500D01*
X-1264800Y852000D01*
X-1266375Y853000D01*
X-1268475Y853500D01*
X-1269700Y854500D01*
X-1270225Y856250D01*
X-1269875Y858000D01*
X-1269000Y859250D01*
X-1267775Y860000D01*
X-1266550D01*
X-1265325Y859500D01*
X-1264275Y858250D01*
G01X-1256725Y845000D02*
Y860000D01*
G01X-1249375D02*
Y845000D01*
G01Y852500D02*
X-1256725D01*
G01X-1242700Y860000D02*
Y849250D01*
X-1242000Y847000D01*
X-1240600Y845500D01*
X-1238850Y845000D01*
X-1237100Y845500D01*
X-1235700Y847000D01*
X-1235000Y849250D01*
Y860000D01*
G01X-1224650D02*
Y845000D01*
G01X-1228675Y860000D02*
X-1220625D01*
G01X-1196250Y845000D02*
X-1197650Y845250D01*
X-1198875Y846250D01*
X-1199925Y847750D01*
X-1200625Y849500D01*
X-1200975Y851500D01*
Y853500D01*
X-1200625Y855500D01*
X-1199925Y857250D01*
X-1198875Y858750D01*
X-1197650Y859750D01*
X-1196250Y860000D01*
X-1194850Y859750D01*
X-1193625Y858750D01*
X-1192575Y857250D01*
X-1191875Y855500D01*
X-1191525Y853500D01*
Y851500D01*
X-1191875Y849500D01*
X-1192575Y847750D01*
X-1193625Y846250D01*
X-1194850Y845250D01*
X-1196250Y845000D01*
G01X-1185550D02*
Y860000D01*
X-1181175D01*
X-1179775Y859250D01*
X-1178900Y858250D01*
X-1178550Y856250D01*
X-1178900Y854250D01*
X-1179950Y853000D01*
X-1181175Y852250D01*
X-1185550D01*
G01X-1181175D02*
X-1178550Y845000D01*
G01X-1157325Y847000D02*
X-1155925Y845750D01*
X-1154350Y845000D01*
X-1152950D01*
X-1151550Y845750D01*
X-1150500Y847000D01*
X-1149975Y848750D01*
X-1150325Y850500D01*
X-1151200Y852000D01*
X-1152775Y853000D01*
X-1154875Y853500D01*
X-1156100Y854500D01*
X-1156625Y856250D01*
X-1156275Y858000D01*
X-1155400Y859250D01*
X-1154175Y860000D01*
X-1152950D01*
X-1151725Y859500D01*
X-1150675Y858250D01*
G01X-1139450Y845000D02*
X-1140850Y845250D01*
X-1142075Y846250D01*
X-1143125Y847750D01*
X-1143825Y849500D01*
X-1144175Y851500D01*
Y853500D01*
X-1143825Y855500D01*
X-1143125Y857250D01*
X-1142075Y858750D01*
X-1140850Y859750D01*
X-1139450Y860000D01*
X-1138050Y859750D01*
X-1136825Y858750D01*
X-1135775Y857250D01*
X-1135075Y855500D01*
X-1134725Y853500D01*
Y851500D01*
X-1135075Y849500D01*
X-1135775Y847750D01*
X-1136825Y846250D01*
X-1138050Y845250D01*
X-1139450Y845000D01*
G01X-1128750Y860000D02*
Y845000D01*
X-1121750D01*
G01X-1114900D02*
Y860000D01*
X-1111400D01*
X-1110000Y859250D01*
X-1108950Y858250D01*
X-1108075Y856750D01*
X-1107375Y855000D01*
X-1107200Y852500D01*
X-1107375Y850000D01*
X-1108075Y848250D01*
X-1108950Y846750D01*
X-1110000Y845750D01*
X-1111400Y845000D01*
X-1114900D01*
G01X-1093350D02*
X-1100350D01*
Y860000D01*
X-1093350D01*
G01X-1096150Y852750D02*
X-1100350D01*
G01X-1086150Y845000D02*
Y860000D01*
X-1081775D01*
X-1080375Y859250D01*
X-1079500Y858250D01*
X-1079150Y856250D01*
X-1079500Y854250D01*
X-1080550Y853000D01*
X-1081775Y852250D01*
X-1086150D01*
G01X-1081775D02*
X-1079150Y845000D01*
G01X-1057575D02*
Y860000D01*
X-1050925D01*
G01X-1053375Y852750D02*
X-1057575D01*
G01X-1042150Y860000D02*
X-1037950D01*
G01X-1040050D02*
Y845000D01*
G01X-1042150D02*
X-1037950D01*
G01X-1029350Y860000D02*
Y845000D01*
X-1022350D01*
G01X-1015150Y860000D02*
Y845000D01*
X-1008150D01*
G01X-993950D02*
X-1000950D01*
Y860000D01*
X-993950D01*
G01X-996750Y852750D02*
X-1000950D01*
G01X-987100Y845000D02*
Y860000D01*
X-983600D01*
X-982200Y859250D01*
X-981150Y858250D01*
X-980275Y856750D01*
X-979575Y855000D01*
X-979400Y852500D01*
X-979575Y850000D01*
X-980275Y848250D01*
X-981150Y846750D01*
X-982200Y845750D01*
X-983600Y845000D01*
X-987100D01*
G01X-969050Y844500D02*
X-969400Y844750D01*
Y845250D01*
X-969050Y845500D01*
X-968700Y845250D01*
Y844750D01*
X-969050Y844500D01*
G01X-1676950Y880000D02*
Y895000D01*
X-1683425Y884250D01*
X-1674675D01*
G01X-1664850Y879500D02*
X-1665200Y879750D01*
Y880250D01*
X-1664850Y880500D01*
X-1664500Y880250D01*
Y879750D01*
X-1664850Y879500D01*
G01X-1640300Y880000D02*
Y895000D01*
X-1636800D01*
X-1635400Y894250D01*
X-1634350Y893250D01*
X-1633475Y891750D01*
X-1632775Y890000D01*
X-1632600Y887500D01*
X-1632775Y885000D01*
X-1633475Y883250D01*
X-1634350Y881750D01*
X-1635400Y880750D01*
X-1636800Y880000D01*
X-1640300D01*
G01X-1624350Y895000D02*
X-1620150D01*
G01X-1622250D02*
Y880000D01*
G01X-1624350D02*
X-1620150D01*
G01X-1612600D02*
Y895000D01*
X-1608050Y882500D01*
X-1603500Y895000D01*
Y880000D01*
G01X-1590350D02*
X-1597350D01*
Y895000D01*
X-1590350D01*
G01X-1593150Y887750D02*
X-1597350D01*
G01X-1583675Y880000D02*
Y895000D01*
X-1575625Y880000D01*
Y895000D01*
G01X-1569125Y882000D02*
X-1567725Y880750D01*
X-1566150Y880000D01*
X-1564750D01*
X-1563350Y880750D01*
X-1562300Y882000D01*
X-1561775Y883750D01*
X-1562125Y885500D01*
X-1563000Y887000D01*
X-1564575Y888000D01*
X-1566675Y888500D01*
X-1567900Y889500D01*
X-1568425Y891250D01*
X-1568075Y893000D01*
X-1567200Y894250D01*
X-1565975Y895000D01*
X-1564750D01*
X-1563525Y894500D01*
X-1562475Y893250D01*
G01X-1553350Y895000D02*
X-1549150D01*
G01X-1551250D02*
Y880000D01*
G01X-1553350D02*
X-1549150D01*
G01X-1537050D02*
X-1538450Y880250D01*
X-1539675Y881250D01*
X-1540725Y882750D01*
X-1541425Y884500D01*
X-1541775Y886500D01*
Y888500D01*
X-1541425Y890500D01*
X-1540725Y892250D01*
X-1539675Y893750D01*
X-1538450Y894750D01*
X-1537050Y895000D01*
X-1535650Y894750D01*
X-1534425Y893750D01*
X-1533375Y892250D01*
X-1532675Y890500D01*
X-1532325Y888500D01*
Y886500D01*
X-1532675Y884500D01*
X-1533375Y882750D01*
X-1534425Y881250D01*
X-1535650Y880250D01*
X-1537050Y880000D01*
G01X-1526875D02*
Y895000D01*
X-1518825Y880000D01*
Y895000D01*
G01X-1510750D02*
X-1506550D01*
G01X-1508650D02*
Y880000D01*
G01X-1510750D02*
X-1506550D01*
G01X-1498475D02*
Y895000D01*
X-1490425Y880000D01*
Y895000D01*
G01X-1479200Y887500D02*
X-1475700D01*
Y883000D01*
X-1476750Y881500D01*
X-1477975Y880500D01*
X-1479725Y880000D01*
X-1481475Y880500D01*
X-1482700Y881500D01*
X-1483750Y883000D01*
X-1484450Y884750D01*
X-1484800Y886750D01*
Y888500D01*
X-1484450Y890000D01*
X-1483750Y891750D01*
X-1482700Y893250D01*
X-1481650Y894250D01*
X-1480250Y895000D01*
X-1479025D01*
X-1477625Y894500D01*
X-1476575Y893500D01*
G01X-1456225Y880000D02*
X-1451850Y895000D01*
X-1447475Y880000D01*
G01X-1449050Y885250D02*
X-1454650D01*
G01X-1441675Y880000D02*
Y895000D01*
X-1433625Y880000D01*
Y895000D01*
G01X-1427300Y880000D02*
Y895000D01*
X-1423800D01*
X-1422400Y894250D01*
X-1421350Y893250D01*
X-1420475Y891750D01*
X-1419775Y890000D01*
X-1419600Y887500D01*
X-1419775Y885000D01*
X-1420475Y883250D01*
X-1421350Y881750D01*
X-1422400Y880750D01*
X-1423800Y880000D01*
X-1427300D01*
G01X-1395050Y895000D02*
Y880000D01*
G01X-1399075Y895000D02*
X-1391025D01*
G01X-1380850Y880000D02*
X-1382250Y880250D01*
X-1383475Y881250D01*
X-1384525Y882750D01*
X-1385225Y884500D01*
X-1385575Y886500D01*
Y888500D01*
X-1385225Y890500D01*
X-1384525Y892250D01*
X-1383475Y893750D01*
X-1382250Y894750D01*
X-1380850Y895000D01*
X-1379450Y894750D01*
X-1378225Y893750D01*
X-1377175Y892250D01*
X-1376475Y890500D01*
X-1376125Y888500D01*
Y886500D01*
X-1376475Y884500D01*
X-1377175Y882750D01*
X-1378225Y881250D01*
X-1379450Y880250D01*
X-1380850Y880000D01*
G01X-1370150Y895000D02*
Y880000D01*
X-1363150D01*
G01X-1348950D02*
X-1355950D01*
Y895000D01*
X-1348950D01*
G01X-1351750Y887750D02*
X-1355950D01*
G01X-1341750Y880000D02*
Y895000D01*
X-1337375D01*
X-1335975Y894250D01*
X-1335100Y893250D01*
X-1334750Y891250D01*
X-1335100Y889250D01*
X-1336150Y888000D01*
X-1337375Y887250D01*
X-1341750D01*
G01X-1337375D02*
X-1334750Y880000D01*
G01X-1328425D02*
X-1324050Y895000D01*
X-1319675Y880000D01*
G01X-1321250Y885250D02*
X-1326850D01*
G01X-1313875Y880000D02*
Y895000D01*
X-1305825Y880000D01*
Y895000D01*
G01X-1291800Y893750D02*
X-1292850Y894500D01*
X-1294075Y895000D01*
X-1295475D01*
X-1297050Y894250D01*
X-1298275Y893000D01*
X-1299150Y891500D01*
X-1299850Y889000D01*
X-1300025Y886750D01*
X-1299675Y884500D01*
X-1299150Y883000D01*
X-1298100Y881500D01*
X-1296875Y880500D01*
X-1295650Y880000D01*
X-1294425D01*
X-1293200Y880500D01*
X-1292150Y881250D01*
X-1291275Y882250D01*
G01X-1283550Y895000D02*
X-1279350D01*
G01X-1281450D02*
Y880000D01*
G01X-1283550D02*
X-1279350D01*
G01X-1271275D02*
Y895000D01*
X-1263225Y880000D01*
Y895000D01*
G01X-1252000Y887500D02*
X-1248500D01*
Y883000D01*
X-1249550Y881500D01*
X-1250775Y880500D01*
X-1252525Y880000D01*
X-1254275Y880500D01*
X-1255500Y881500D01*
X-1256550Y883000D01*
X-1257250Y884750D01*
X-1257600Y886750D01*
Y888500D01*
X-1257250Y890000D01*
X-1256550Y891750D01*
X-1255500Y893250D01*
X-1254450Y894250D01*
X-1253050Y895000D01*
X-1251825D01*
X-1250425Y894500D01*
X-1249375Y893500D01*
G01X-1228150Y880000D02*
Y895000D01*
X-1223950D01*
X-1222550Y894250D01*
X-1221500Y892500D01*
X-1221150Y890500D01*
X-1221500Y888500D01*
X-1222375Y887000D01*
X-1223950Y886250D01*
X-1228150D01*
G01X-1206950Y880000D02*
X-1213950D01*
Y895000D01*
X-1206950D01*
G01X-1209750Y887750D02*
X-1213950D01*
G01X-1199750Y880000D02*
Y895000D01*
X-1195375D01*
X-1193975Y894250D01*
X-1193100Y893250D01*
X-1192750Y891250D01*
X-1193100Y889250D01*
X-1194150Y888000D01*
X-1195375Y887250D01*
X-1199750D01*
G01X-1195375D02*
X-1192750Y880000D01*
G01X-1172225D02*
X-1167850Y895000D01*
X-1163475Y880000D01*
G01X-1165050Y885250D02*
X-1170650D01*
G01X-1157675Y880000D02*
Y895000D01*
X-1149625Y880000D01*
Y895000D01*
G01X-1143125Y882000D02*
X-1141725Y880750D01*
X-1140150Y880000D01*
X-1138750D01*
X-1137350Y880750D01*
X-1136300Y882000D01*
X-1135775Y883750D01*
X-1136125Y885500D01*
X-1137000Y887000D01*
X-1138575Y888000D01*
X-1140675Y888500D01*
X-1141900Y889500D01*
X-1142425Y891250D01*
X-1142075Y893000D01*
X-1141200Y894250D01*
X-1139975Y895000D01*
X-1138750D01*
X-1137525Y894500D01*
X-1136475Y893250D01*
G01X-1127350Y895000D02*
X-1123150D01*
G01X-1125250D02*
Y880000D01*
G01X-1127350D02*
X-1123150D01*
G01X-1096850D02*
Y886750D01*
X-1100350Y895000D01*
G01X-1093350D02*
X-1096850Y886750D01*
G01X-1082650Y880000D02*
Y895000D01*
X-1084750Y892000D01*
G01Y880000D02*
X-1080550D01*
G01X-1066350D02*
Y895000D01*
X-1072825Y884250D01*
X-1064075D01*
G01X-1054250Y879500D02*
X-1054600Y879750D01*
Y880250D01*
X-1054250Y880500D01*
X-1053900Y880250D01*
Y879750D01*
X-1054250Y879500D01*
G01X-1043900Y882250D02*
X-1042850Y881000D01*
X-1041625Y880250D01*
X-1040050Y880000D01*
X-1038475Y880500D01*
X-1037250Y881500D01*
X-1036375Y883250D01*
X-1036200Y885250D01*
X-1036550Y887250D01*
X-1037425Y888500D01*
X-1038650Y889500D01*
X-1039875Y889750D01*
X-1041100Y889500D01*
X-1042675Y888500D01*
X-1042150Y895000D01*
X-1037425D01*
G01X-1030400Y880000D02*
Y895000D01*
X-1025850Y882500D01*
X-1021300Y895000D01*
Y880000D01*
G01X-1011650Y879500D02*
X-1012000Y879750D01*
Y880250D01*
X-1011650Y880500D01*
X-1011300Y880250D01*
Y879750D01*
X-1011650Y879500D01*
G01X-1682900Y918000D02*
X-1681850Y916250D01*
X-1680450Y915250D01*
X-1678875Y915000D01*
X-1677475Y915250D01*
X-1676075Y916500D01*
X-1675200Y918000D01*
X-1675025Y919500D01*
X-1675375Y921250D01*
X-1676600Y922500D01*
X-1677825Y923000D01*
X-1679400D01*
G01X-1677825D02*
X-1676775Y923750D01*
X-1675900Y925000D01*
X-1675550Y926500D01*
X-1675900Y928000D01*
X-1676775Y929250D01*
X-1678350Y930000D01*
X-1679925Y929750D01*
X-1681500Y928750D01*
G01X-1664850Y914500D02*
X-1665200Y914750D01*
Y915250D01*
X-1664850Y915500D01*
X-1664500Y915250D01*
Y914750D01*
X-1664850Y914500D01*
G01X-1639775Y915000D02*
Y930000D01*
X-1633125D01*
G01X-1635575Y922750D02*
X-1639775D01*
G01X-1626625Y915000D02*
X-1622250Y930000D01*
X-1617875Y915000D01*
G01X-1619450Y920250D02*
X-1625050D01*
G01X-1606650Y923000D02*
X-1605950Y923750D01*
X-1605425Y925000D01*
X-1605075Y926750D01*
X-1605425Y928250D01*
X-1606125Y929250D01*
X-1607350Y930000D01*
X-1612075D01*
Y915000D01*
X-1606300D01*
X-1605075Y916000D01*
X-1604375Y917500D01*
X-1604025Y919250D01*
X-1604375Y921000D01*
X-1605425Y922500D01*
X-1606650Y923000D01*
X-1612075D01*
G01X-1597350Y915000D02*
Y930000D01*
X-1592975D01*
X-1591575Y929250D01*
X-1590700Y928250D01*
X-1590350Y926250D01*
X-1590700Y924250D01*
X-1591750Y923000D01*
X-1592975Y922250D01*
X-1597350D01*
G01X-1592975D02*
X-1590350Y915000D01*
G01X-1581750Y930000D02*
X-1577550D01*
G01X-1579650D02*
Y915000D01*
G01X-1581750D02*
X-1577550D01*
G01X-1561600Y928750D02*
X-1562650Y929500D01*
X-1563875Y930000D01*
X-1565275D01*
X-1566850Y929250D01*
X-1568075Y928000D01*
X-1568950Y926500D01*
X-1569650Y924000D01*
X-1569825Y921750D01*
X-1569475Y919500D01*
X-1568950Y918000D01*
X-1567900Y916500D01*
X-1566675Y915500D01*
X-1565450Y915000D01*
X-1564225D01*
X-1563000Y915500D01*
X-1561950Y916250D01*
X-1561075Y917250D01*
G01X-1555625Y915000D02*
X-1551250Y930000D01*
X-1546875Y915000D01*
G01X-1548450Y920250D02*
X-1554050D01*
G01X-1537050Y930000D02*
Y915000D01*
G01X-1541075Y930000D02*
X-1533025D01*
G01X-1519350Y915000D02*
X-1526350D01*
Y930000D01*
X-1519350D01*
G01X-1522150Y922750D02*
X-1526350D01*
G01X-1497950Y915000D02*
Y930000D01*
X-1493750D01*
X-1492350Y929250D01*
X-1491300Y927500D01*
X-1490950Y925500D01*
X-1491300Y923500D01*
X-1492175Y922000D01*
X-1493750Y921250D01*
X-1497950D01*
G01X-1485500Y930000D02*
X-1483050Y915000D01*
X-1480250Y930000D01*
X-1477450Y915000D01*
X-1475000Y930000D01*
G01X-1464650Y923000D02*
X-1463950Y923750D01*
X-1463425Y925000D01*
X-1463075Y926750D01*
X-1463425Y928250D01*
X-1464125Y929250D01*
X-1465350Y930000D01*
X-1470075D01*
Y915000D01*
X-1464300D01*
X-1463075Y916000D01*
X-1462375Y917500D01*
X-1462025Y919250D01*
X-1462375Y921000D01*
X-1463425Y922500D01*
X-1464650Y923000D01*
X-1470075D01*
G01X-1441150Y915000D02*
Y930000D01*
X-1436950D01*
X-1435550Y929250D01*
X-1434500Y927500D01*
X-1434150Y925500D01*
X-1434500Y923500D01*
X-1435375Y922000D01*
X-1436950Y921250D01*
X-1441150D01*
G01X-1419950Y915000D02*
X-1426950D01*
Y930000D01*
X-1419950D01*
G01X-1422750Y922750D02*
X-1426950D01*
G01X-1412750Y915000D02*
Y930000D01*
X-1408375D01*
X-1406975Y929250D01*
X-1406100Y928250D01*
X-1405750Y926250D01*
X-1406100Y924250D01*
X-1407150Y923000D01*
X-1408375Y922250D01*
X-1412750D01*
G01X-1408375D02*
X-1405750Y915000D01*
G01X-1382950Y930000D02*
X-1378750D01*
G01X-1380850D02*
Y915000D01*
G01X-1382950D02*
X-1378750D01*
G01X-1370150D02*
Y930000D01*
X-1365950D01*
X-1364550Y929250D01*
X-1363500Y927500D01*
X-1363150Y925500D01*
X-1363500Y923500D01*
X-1364375Y922000D01*
X-1365950Y921250D01*
X-1370150D01*
G01X-1348600Y928750D02*
X-1349650Y929500D01*
X-1350875Y930000D01*
X-1352275D01*
X-1353850Y929250D01*
X-1355075Y928000D01*
X-1355950Y926500D01*
X-1356650Y924000D01*
X-1356825Y921750D01*
X-1356475Y919500D01*
X-1355950Y918000D01*
X-1354900Y916500D01*
X-1353675Y915500D01*
X-1352450Y915000D01*
X-1351225D01*
X-1350000Y915500D01*
X-1348950Y916250D01*
X-1348075Y917250D01*
G01X-1340525Y920000D02*
X-1335975D01*
G01X-1327375Y921250D02*
X-1326150Y923000D01*
X-1325100Y924000D01*
X-1323700Y924500D01*
X-1322475Y924000D01*
X-1321600Y923000D01*
X-1320900Y921500D01*
X-1320725Y919750D01*
X-1320900Y918250D01*
X-1321600Y916750D01*
X-1322650Y915500D01*
X-1323875Y915000D01*
X-1325275Y915500D01*
X-1326500Y917000D01*
X-1327200Y919250D01*
X-1327375Y921750D01*
X-1327025Y925000D01*
X-1326500Y926750D01*
X-1325625Y928500D01*
X-1324400Y929750D01*
X-1323175Y930000D01*
X-1321950Y929500D01*
X-1321075Y928250D01*
G01X-1309850Y930000D02*
X-1311250Y929500D01*
X-1312300Y928250D01*
X-1313000Y926750D01*
X-1313525Y924750D01*
X-1313700Y922500D01*
X-1313525Y920250D01*
X-1313000Y918250D01*
X-1312300Y916750D01*
X-1311250Y915500D01*
X-1309850Y915000D01*
X-1308450Y915500D01*
X-1307400Y916750D01*
X-1306700Y918250D01*
X-1306175Y920250D01*
X-1306000Y922500D01*
X-1306175Y924750D01*
X-1306700Y926750D01*
X-1307400Y928250D01*
X-1308450Y929500D01*
X-1309850Y930000D01*
G01X-1295650Y915000D02*
Y930000D01*
X-1297750Y927000D01*
G01Y915000D02*
X-1293550D01*
G01X-1284775Y927500D02*
X-1283725Y929000D01*
X-1282500Y929750D01*
X-1281100Y930000D01*
X-1279350Y929500D01*
X-1278125Y928250D01*
X-1277775Y926750D01*
X-1277950Y925250D01*
X-1278650Y924000D01*
X-1282150Y921500D01*
X-1283725Y919750D01*
X-1284775Y917250D01*
X-1285125Y915000D01*
X-1277775D01*
G01X-1249200Y928750D02*
X-1250250Y929500D01*
X-1251475Y930000D01*
X-1252875D01*
X-1254450Y929250D01*
X-1255675Y928000D01*
X-1256550Y926500D01*
X-1257250Y924000D01*
X-1257425Y921750D01*
X-1257075Y919500D01*
X-1256550Y918000D01*
X-1255500Y916500D01*
X-1254275Y915500D01*
X-1253050Y915000D01*
X-1251825D01*
X-1250600Y915500D01*
X-1249550Y916250D01*
X-1248675Y917250D01*
G01X-1242350Y930000D02*
Y915000D01*
X-1235350D01*
G01X-1229025D02*
X-1224650Y930000D01*
X-1220275Y915000D01*
G01X-1221850Y920250D02*
X-1227450D01*
G01X-1214125Y917000D02*
X-1212725Y915750D01*
X-1211150Y915000D01*
X-1209750D01*
X-1208350Y915750D01*
X-1207300Y917000D01*
X-1206775Y918750D01*
X-1207125Y920500D01*
X-1208000Y922000D01*
X-1209575Y923000D01*
X-1211675Y923500D01*
X-1212900Y924500D01*
X-1213425Y926250D01*
X-1213075Y928000D01*
X-1212200Y929250D01*
X-1210975Y930000D01*
X-1209750D01*
X-1208525Y929500D01*
X-1207475Y928250D01*
G01X-1199925Y917000D02*
X-1198525Y915750D01*
X-1196950Y915000D01*
X-1195550D01*
X-1194150Y915750D01*
X-1193100Y917000D01*
X-1192575Y918750D01*
X-1192925Y920500D01*
X-1193800Y922000D01*
X-1195375Y923000D01*
X-1197475Y923500D01*
X-1198700Y924500D01*
X-1199225Y926250D01*
X-1198875Y928000D01*
X-1198000Y929250D01*
X-1196775Y930000D01*
X-1195550D01*
X-1194325Y929500D01*
X-1193275Y928250D01*
G01X-1171175Y927500D02*
X-1170125Y929000D01*
X-1168900Y929750D01*
X-1167500Y930000D01*
X-1165750Y929500D01*
X-1164525Y928250D01*
X-1164175Y926750D01*
X-1164350Y925250D01*
X-1165050Y924000D01*
X-1168550Y921500D01*
X-1170125Y919750D01*
X-1171175Y917250D01*
X-1171525Y915000D01*
X-1164175D01*
G01X-1140325Y910000D02*
X-1142075Y912500D01*
X-1142950Y915000D01*
Y925000D01*
X-1142075Y927500D01*
X-1140325Y930000D01*
G01X-1128750D02*
Y915000D01*
X-1121750D01*
G01X-1115425D02*
X-1111050Y930000D01*
X-1106675Y915000D01*
G01X-1108250Y920250D02*
X-1113850D01*
G01X-1096850Y930000D02*
Y915000D01*
G01X-1100875Y930000D02*
X-1092825D01*
G01X-1079150Y915000D02*
X-1086150D01*
Y930000D01*
X-1079150D01*
G01X-1081950Y922750D02*
X-1086150D01*
G01X-1072125Y917000D02*
X-1070725Y915750D01*
X-1069150Y915000D01*
X-1067750D01*
X-1066350Y915750D01*
X-1065300Y917000D01*
X-1064775Y918750D01*
X-1065125Y920500D01*
X-1066000Y922000D01*
X-1067575Y923000D01*
X-1069675Y923500D01*
X-1070900Y924500D01*
X-1071425Y926250D01*
X-1071075Y928000D01*
X-1070200Y929250D01*
X-1068975Y930000D01*
X-1067750D01*
X-1066525Y929500D01*
X-1065475Y928250D01*
G01X-1054250Y930000D02*
Y915000D01*
G01X-1058275Y930000D02*
X-1050225D01*
G01X-1029350Y915000D02*
Y930000D01*
X-1024975D01*
X-1023575Y929250D01*
X-1022700Y928250D01*
X-1022350Y926250D01*
X-1022700Y924250D01*
X-1023750Y923000D01*
X-1024975Y922250D01*
X-1029350D01*
G01X-1024975D02*
X-1022350Y915000D01*
G01X-1008150D02*
X-1015150D01*
Y930000D01*
X-1008150D01*
G01X-1010950Y922750D02*
X-1015150D01*
G01X-1001825Y930000D02*
X-997450Y915000D01*
X-993075Y930000D01*
G01X-985350D02*
X-981150D01*
G01X-983250D02*
Y915000D01*
G01X-985350D02*
X-981150D01*
G01X-972725Y917000D02*
X-971325Y915750D01*
X-969750Y915000D01*
X-968350D01*
X-966950Y915750D01*
X-965900Y917000D01*
X-965375Y918750D01*
X-965725Y920500D01*
X-966600Y922000D01*
X-968175Y923000D01*
X-970275Y923500D01*
X-971500Y924500D01*
X-972025Y926250D01*
X-971675Y928000D01*
X-970800Y929250D01*
X-969575Y930000D01*
X-968350D01*
X-967125Y929500D01*
X-966075Y928250D01*
G01X-956950Y930000D02*
X-952750D01*
G01X-954850D02*
Y915000D01*
G01X-956950D02*
X-952750D01*
G01X-940650D02*
X-942050Y915250D01*
X-943275Y916250D01*
X-944325Y917750D01*
X-945025Y919500D01*
X-945375Y921500D01*
Y923500D01*
X-945025Y925500D01*
X-944325Y927250D01*
X-943275Y928750D01*
X-942050Y929750D01*
X-940650Y930000D01*
X-939250Y929750D01*
X-938025Y928750D01*
X-936975Y927250D01*
X-936275Y925500D01*
X-935925Y923500D01*
Y921500D01*
X-936275Y919500D01*
X-936975Y917750D01*
X-938025Y916250D01*
X-939250Y915250D01*
X-940650Y915000D01*
G01X-930475D02*
Y930000D01*
X-922425Y915000D01*
Y930000D01*
G01X-911375Y910000D02*
X-909625Y912500D01*
X-908750Y915000D01*
Y925000D01*
X-909625Y927500D01*
X-911375Y930000D01*
G01X-898050Y914500D02*
X-898400Y914750D01*
Y915250D01*
X-898050Y915500D01*
X-897700Y915250D01*
Y914750D01*
X-898050Y914500D01*
G01X-1682375Y962500D02*
X-1681325Y964000D01*
X-1680100Y964750D01*
X-1678700Y965000D01*
X-1676950Y964500D01*
X-1675725Y963250D01*
X-1675375Y961750D01*
X-1675550Y960250D01*
X-1676250Y959000D01*
X-1679750Y956500D01*
X-1681325Y954750D01*
X-1682375Y952250D01*
X-1682725Y950000D01*
X-1675375D01*
G01X-1664850Y949500D02*
X-1665200Y949750D01*
Y950250D01*
X-1664850Y950500D01*
X-1664500Y950250D01*
Y949750D01*
X-1664850Y949500D01*
G01X-1636450Y965000D02*
Y950000D01*
G01X-1640475Y965000D02*
X-1632425D01*
G01X-1625925Y950000D02*
Y965000D01*
G01X-1618575D02*
Y950000D01*
G01Y957500D02*
X-1625925D01*
G01X-1610150Y965000D02*
X-1605950D01*
G01X-1608050D02*
Y950000D01*
G01X-1610150D02*
X-1605950D01*
G01X-1597525Y952000D02*
X-1596125Y950750D01*
X-1594550Y950000D01*
X-1593150D01*
X-1591750Y950750D01*
X-1590700Y952000D01*
X-1590175Y953750D01*
X-1590525Y955500D01*
X-1591400Y957000D01*
X-1592975Y958000D01*
X-1595075Y958500D01*
X-1596300Y959500D01*
X-1596825Y961250D01*
X-1596475Y963000D01*
X-1595600Y964250D01*
X-1594375Y965000D01*
X-1593150D01*
X-1591925Y964500D01*
X-1590875Y963250D01*
G01X-1569300Y950000D02*
Y965000D01*
X-1565800D01*
X-1564400Y964250D01*
X-1563350Y963250D01*
X-1562475Y961750D01*
X-1561775Y960000D01*
X-1561600Y957500D01*
X-1561775Y955000D01*
X-1562475Y953250D01*
X-1563350Y951750D01*
X-1564400Y950750D01*
X-1565800Y950000D01*
X-1569300D01*
G01X-1554750D02*
Y965000D01*
X-1550375D01*
X-1548975Y964250D01*
X-1548100Y963250D01*
X-1547750Y961250D01*
X-1548100Y959250D01*
X-1549150Y958000D01*
X-1550375Y957250D01*
X-1554750D01*
G01X-1550375D02*
X-1547750Y950000D01*
G01X-1541425D02*
X-1537050Y965000D01*
X-1532675Y950000D01*
G01X-1534250Y955250D02*
X-1539850D01*
G01X-1528100Y965000D02*
X-1525650Y950000D01*
X-1522850Y965000D01*
X-1520050Y950000D01*
X-1517600Y965000D01*
G01X-1510750D02*
X-1506550D01*
G01X-1508650D02*
Y950000D01*
G01X-1510750D02*
X-1506550D01*
G01X-1498475D02*
Y965000D01*
X-1490425Y950000D01*
Y965000D01*
G01X-1479200Y957500D02*
X-1475700D01*
Y953000D01*
X-1476750Y951500D01*
X-1477975Y950500D01*
X-1479725Y950000D01*
X-1481475Y950500D01*
X-1482700Y951500D01*
X-1483750Y953000D01*
X-1484450Y954750D01*
X-1484800Y956750D01*
Y958500D01*
X-1484450Y960000D01*
X-1483750Y961750D01*
X-1482700Y963250D01*
X-1481650Y964250D01*
X-1480250Y965000D01*
X-1479025D01*
X-1477625Y964500D01*
X-1476575Y963500D01*
G01X-1456225Y950000D02*
X-1451850Y965000D01*
X-1447475Y950000D01*
G01X-1449050Y955250D02*
X-1454650D01*
G01X-1441150Y965000D02*
Y950000D01*
X-1434150D01*
G01X-1427125Y952000D02*
X-1425725Y950750D01*
X-1424150Y950000D01*
X-1422750D01*
X-1421350Y950750D01*
X-1420300Y952000D01*
X-1419775Y953750D01*
X-1420125Y955500D01*
X-1421000Y957000D01*
X-1422575Y958000D01*
X-1424675Y958500D01*
X-1425900Y959500D01*
X-1426425Y961250D01*
X-1426075Y963000D01*
X-1425200Y964250D01*
X-1423975Y965000D01*
X-1422750D01*
X-1421525Y964500D01*
X-1420475Y963250D01*
G01X-1409250Y950000D02*
X-1410650Y950250D01*
X-1411875Y951250D01*
X-1412925Y952750D01*
X-1413625Y954500D01*
X-1413975Y956500D01*
Y958500D01*
X-1413625Y960500D01*
X-1412925Y962250D01*
X-1411875Y963750D01*
X-1410650Y964750D01*
X-1409250Y965000D01*
X-1407850Y964750D01*
X-1406625Y963750D01*
X-1405575Y962250D01*
X-1404875Y960500D01*
X-1404525Y958500D01*
Y956500D01*
X-1404875Y954500D01*
X-1405575Y952750D01*
X-1406625Y951250D01*
X-1407850Y950250D01*
X-1409250Y950000D01*
G01X-1377350D02*
X-1384350D01*
Y965000D01*
X-1377350D01*
G01X-1380150Y957750D02*
X-1384350D01*
G01X-1370325Y950000D02*
X-1362975Y965000D01*
G01X-1370325D02*
X-1362975Y950000D01*
G01X-1354550Y965000D02*
X-1350350D01*
G01X-1352450D02*
Y950000D01*
G01X-1354550D02*
X-1350350D01*
G01X-1341925Y952000D02*
X-1340525Y950750D01*
X-1338950Y950000D01*
X-1337550D01*
X-1336150Y950750D01*
X-1335100Y952000D01*
X-1334575Y953750D01*
X-1334925Y955500D01*
X-1335800Y957000D01*
X-1337375Y958000D01*
X-1339475Y958500D01*
X-1340700Y959500D01*
X-1341225Y961250D01*
X-1340875Y963000D01*
X-1340000Y964250D01*
X-1338775Y965000D01*
X-1337550D01*
X-1336325Y964500D01*
X-1335275Y963250D01*
G01X-1324050Y965000D02*
Y950000D01*
G01X-1328075Y965000D02*
X-1320025D01*
G01X-1313525Y952000D02*
X-1312125Y950750D01*
X-1310550Y950000D01*
X-1309150D01*
X-1307750Y950750D01*
X-1306700Y952000D01*
X-1306175Y953750D01*
X-1306525Y955500D01*
X-1307400Y957000D01*
X-1308975Y958000D01*
X-1311075Y958500D01*
X-1312300Y959500D01*
X-1312825Y961250D01*
X-1312475Y963000D01*
X-1311600Y964250D01*
X-1310375Y965000D01*
X-1309150D01*
X-1307925Y964500D01*
X-1306875Y963250D01*
G01X-1281450Y950000D02*
X-1282850Y950250D01*
X-1284075Y951250D01*
X-1285125Y952750D01*
X-1285825Y954500D01*
X-1286175Y956500D01*
Y958500D01*
X-1285825Y960500D01*
X-1285125Y962250D01*
X-1284075Y963750D01*
X-1282850Y964750D01*
X-1281450Y965000D01*
X-1280050Y964750D01*
X-1278825Y963750D01*
X-1277775Y962250D01*
X-1277075Y960500D01*
X-1276725Y958500D01*
Y956500D01*
X-1277075Y954500D01*
X-1277775Y952750D01*
X-1278825Y951250D01*
X-1280050Y950250D01*
X-1281450Y950000D01*
G01X-1271275D02*
Y965000D01*
X-1263225Y950000D01*
Y965000D01*
G01X-1235350Y950000D02*
X-1242350D01*
Y965000D01*
X-1235350D01*
G01X-1238150Y957750D02*
X-1242350D01*
G01X-1228150Y965000D02*
Y950000D01*
X-1221150D01*
G01X-1206950D02*
X-1213950D01*
Y965000D01*
X-1206950D01*
G01X-1209750Y957750D02*
X-1213950D01*
G01X-1192400Y963750D02*
X-1193450Y964500D01*
X-1194675Y965000D01*
X-1196075D01*
X-1197650Y964250D01*
X-1198875Y963000D01*
X-1199750Y961500D01*
X-1200450Y959000D01*
X-1200625Y956750D01*
X-1200275Y954500D01*
X-1199750Y953000D01*
X-1198700Y951500D01*
X-1197475Y950500D01*
X-1196250Y950000D01*
X-1195025D01*
X-1193800Y950500D01*
X-1192750Y951250D01*
X-1191875Y952250D01*
G01X-1182050Y965000D02*
Y950000D01*
G01X-1186075Y965000D02*
X-1178025D01*
G01X-1171350Y950000D02*
Y965000D01*
X-1166975D01*
X-1165575Y964250D01*
X-1164700Y963250D01*
X-1164350Y961250D01*
X-1164700Y959250D01*
X-1165750Y958000D01*
X-1166975Y957250D01*
X-1171350D01*
G01X-1166975D02*
X-1164350Y950000D01*
G01X-1153650D02*
X-1155050Y950250D01*
X-1156275Y951250D01*
X-1157325Y952750D01*
X-1158025Y954500D01*
X-1158375Y956500D01*
Y958500D01*
X-1158025Y960500D01*
X-1157325Y962250D01*
X-1156275Y963750D01*
X-1155050Y964750D01*
X-1153650Y965000D01*
X-1152250Y964750D01*
X-1151025Y963750D01*
X-1149975Y962250D01*
X-1149275Y960500D01*
X-1148925Y958500D01*
Y956500D01*
X-1149275Y954500D01*
X-1149975Y952750D01*
X-1151025Y951250D01*
X-1152250Y950250D01*
X-1153650Y950000D01*
G01X-1143475D02*
Y965000D01*
X-1135425Y950000D01*
Y965000D01*
G01X-1127350D02*
X-1123150D01*
G01X-1125250D02*
Y950000D01*
G01X-1127350D02*
X-1123150D01*
G01X-1107200Y963750D02*
X-1108250Y964500D01*
X-1109475Y965000D01*
X-1110875D01*
X-1112450Y964250D01*
X-1113675Y963000D01*
X-1114550Y961500D01*
X-1115250Y959000D01*
X-1115425Y956750D01*
X-1115075Y954500D01*
X-1114550Y953000D01*
X-1113500Y951500D01*
X-1112275Y950500D01*
X-1111050Y950000D01*
X-1109825D01*
X-1108600Y950500D01*
X-1107550Y951250D01*
X-1106675Y952250D01*
G01X-1087200Y950000D02*
Y965000D01*
X-1082650Y952500D01*
X-1078100Y965000D01*
Y950000D01*
G01X-1064950D02*
X-1071950D01*
Y965000D01*
X-1064950D01*
G01X-1067750Y957750D02*
X-1071950D01*
G01X-1058100Y950000D02*
Y965000D01*
X-1054600D01*
X-1053200Y964250D01*
X-1052150Y963250D01*
X-1051275Y961750D01*
X-1050575Y960000D01*
X-1050400Y957500D01*
X-1050575Y955000D01*
X-1051275Y953250D01*
X-1052150Y951750D01*
X-1053200Y950750D01*
X-1054600Y950000D01*
X-1058100D01*
G01X-1042150Y965000D02*
X-1037950D01*
G01X-1040050D02*
Y950000D01*
G01X-1042150D02*
X-1037950D01*
G01X-1030225D02*
X-1025850Y965000D01*
X-1021475Y950000D01*
G01X-1023050Y955250D02*
X-1028650D01*
G01X-1011650Y949500D02*
X-1012000Y949750D01*
Y950250D01*
X-1011650Y950500D01*
X-1011300Y950250D01*
Y949750D01*
X-1011650Y949500D01*
G01X-1640125Y987000D02*
X-1638725Y985750D01*
X-1637150Y985000D01*
X-1635750D01*
X-1634350Y985750D01*
X-1633300Y987000D01*
X-1632775Y988750D01*
X-1633125Y990500D01*
X-1634000Y992000D01*
X-1635575Y993000D01*
X-1637675Y993500D01*
X-1638900Y994500D01*
X-1639425Y996250D01*
X-1639075Y998000D01*
X-1638200Y999250D01*
X-1636975Y1000000D01*
X-1635750D01*
X-1634525Y999500D01*
X-1633475Y998250D01*
G01X-1618750Y985000D02*
X-1625750D01*
Y1000000D01*
X-1618750D01*
G01X-1621550Y992750D02*
X-1625750D01*
G01X-1604550Y985000D02*
X-1611550D01*
Y1000000D01*
X-1604550D01*
G01X-1607350Y992750D02*
X-1611550D01*
G01X-1583325Y987000D02*
X-1581925Y985750D01*
X-1580350Y985000D01*
X-1578950D01*
X-1577550Y985750D01*
X-1576500Y987000D01*
X-1575975Y988750D01*
X-1576325Y990500D01*
X-1577200Y992000D01*
X-1578775Y993000D01*
X-1580875Y993500D01*
X-1582100Y994500D01*
X-1582625Y996250D01*
X-1582275Y998000D01*
X-1581400Y999250D01*
X-1580175Y1000000D01*
X-1578950D01*
X-1577725Y999500D01*
X-1576675Y998250D01*
G01X-1569125Y985000D02*
Y1000000D01*
G01X-1561775D02*
Y985000D01*
G01Y992500D02*
X-1569125D01*
G01X-1547750Y985000D02*
X-1554750D01*
Y1000000D01*
X-1547750D01*
G01X-1550550Y992750D02*
X-1554750D01*
G01X-1533550Y985000D02*
X-1540550D01*
Y1000000D01*
X-1533550D01*
G01X-1536350Y992750D02*
X-1540550D01*
G01X-1522850Y1000000D02*
Y985000D01*
G01X-1526875Y1000000D02*
X-1518825D01*
G01X-1497775Y997500D02*
X-1496725Y999000D01*
X-1495500Y999750D01*
X-1494100Y1000000D01*
X-1492350Y999500D01*
X-1491125Y998250D01*
X-1490775Y996750D01*
X-1490950Y995250D01*
X-1491650Y994000D01*
X-1495150Y991500D01*
X-1496725Y989750D01*
X-1497775Y987250D01*
X-1498125Y985000D01*
X-1490775D01*
G01X-1466050D02*
X-1467450Y985250D01*
X-1468675Y986250D01*
X-1469725Y987750D01*
X-1470425Y989500D01*
X-1470775Y991500D01*
Y993500D01*
X-1470425Y995500D01*
X-1469725Y997250D01*
X-1468675Y998750D01*
X-1467450Y999750D01*
X-1466050Y1000000D01*
X-1464650Y999750D01*
X-1463425Y998750D01*
X-1462375Y997250D01*
X-1461675Y995500D01*
X-1461325Y993500D01*
Y991500D01*
X-1461675Y989500D01*
X-1462375Y987750D01*
X-1463425Y986250D01*
X-1464650Y985250D01*
X-1466050Y985000D01*
G01X-1455175D02*
Y1000000D01*
X-1448525D01*
G01X-1450975Y992750D02*
X-1455175D01*
G01X-1426775Y985000D02*
Y1000000D01*
X-1420125D01*
G01X-1422575Y992750D02*
X-1426775D01*
G01X-1413625Y985000D02*
X-1409250Y1000000D01*
X-1404875Y985000D01*
G01X-1406450Y990250D02*
X-1412050D01*
G01X-1393650Y993000D02*
X-1392950Y993750D01*
X-1392425Y995000D01*
X-1392075Y996750D01*
X-1392425Y998250D01*
X-1393125Y999250D01*
X-1394350Y1000000D01*
X-1399075D01*
Y985000D01*
X-1393300D01*
X-1392075Y986000D01*
X-1391375Y987500D01*
X-1391025Y989250D01*
X-1391375Y991000D01*
X-1392425Y992500D01*
X-1393650Y993000D01*
X-1399075D01*
G01X-1384350Y985000D02*
Y1000000D01*
X-1379975D01*
X-1378575Y999250D01*
X-1377700Y998250D01*
X-1377350Y996250D01*
X-1377700Y994250D01*
X-1378750Y993000D01*
X-1379975Y992250D01*
X-1384350D01*
G01X-1379975D02*
X-1377350Y985000D01*
G01X-1368750Y1000000D02*
X-1364550D01*
G01X-1366650D02*
Y985000D01*
G01X-1368750D02*
X-1364550D01*
G01X-1348600Y998750D02*
X-1349650Y999500D01*
X-1350875Y1000000D01*
X-1352275D01*
X-1353850Y999250D01*
X-1355075Y998000D01*
X-1355950Y996500D01*
X-1356650Y994000D01*
X-1356825Y991750D01*
X-1356475Y989500D01*
X-1355950Y988000D01*
X-1354900Y986500D01*
X-1353675Y985500D01*
X-1352450Y985000D01*
X-1351225D01*
X-1350000Y985500D01*
X-1348950Y986250D01*
X-1348075Y987250D01*
G01X-1342625Y985000D02*
X-1338250Y1000000D01*
X-1333875Y985000D01*
G01X-1335450Y990250D02*
X-1341050D01*
G01X-1324050Y1000000D02*
Y985000D01*
G01X-1328075Y1000000D02*
X-1320025D01*
G01X-1311950D02*
X-1307750D01*
G01X-1309850D02*
Y985000D01*
G01X-1311950D02*
X-1307750D01*
G01X-1295650D02*
X-1297050Y985250D01*
X-1298275Y986250D01*
X-1299325Y987750D01*
X-1300025Y989500D01*
X-1300375Y991500D01*
Y993500D01*
X-1300025Y995500D01*
X-1299325Y997250D01*
X-1298275Y998750D01*
X-1297050Y999750D01*
X-1295650Y1000000D01*
X-1294250Y999750D01*
X-1293025Y998750D01*
X-1291975Y997250D01*
X-1291275Y995500D01*
X-1290925Y993500D01*
Y991500D01*
X-1291275Y989500D01*
X-1291975Y987750D01*
X-1293025Y986250D01*
X-1294250Y985250D01*
X-1295650Y985000D01*
G01X-1285475D02*
Y1000000D01*
X-1277425Y985000D01*
Y1000000D01*
G01X-1256900Y985000D02*
Y1000000D01*
X-1253400D01*
X-1252000Y999250D01*
X-1250950Y998250D01*
X-1250075Y996750D01*
X-1249375Y995000D01*
X-1249200Y992500D01*
X-1249375Y990000D01*
X-1250075Y988250D01*
X-1250950Y986750D01*
X-1252000Y985750D01*
X-1253400Y985000D01*
X-1256900D01*
G01X-1242350D02*
Y1000000D01*
X-1237975D01*
X-1236575Y999250D01*
X-1235700Y998250D01*
X-1235350Y996250D01*
X-1235700Y994250D01*
X-1236750Y993000D01*
X-1237975Y992250D01*
X-1242350D01*
G01X-1237975D02*
X-1235350Y985000D01*
G01X-1229025D02*
X-1224650Y1000000D01*
X-1220275Y985000D01*
G01X-1221850Y990250D02*
X-1227450D01*
G01X-1215700Y1000000D02*
X-1213250Y985000D01*
X-1210450Y1000000D01*
X-1207650Y985000D01*
X-1205200Y1000000D01*
G01X-1198350D02*
X-1194150D01*
G01X-1196250D02*
Y985000D01*
G01X-1198350D02*
X-1194150D01*
G01X-1186075D02*
Y1000000D01*
X-1178025Y985000D01*
Y1000000D01*
G01X-1166800Y992500D02*
X-1163300D01*
Y988000D01*
X-1164350Y986500D01*
X-1165575Y985500D01*
X-1167325Y985000D01*
X-1169075Y985500D01*
X-1170300Y986500D01*
X-1171350Y988000D01*
X-1172050Y989750D01*
X-1172400Y991750D01*
Y993500D01*
X-1172050Y995000D01*
X-1171350Y996750D01*
X-1170300Y998250D01*
X-1169250Y999250D01*
X-1167850Y1000000D01*
X-1166625D01*
X-1165225Y999500D01*
X-1164175Y998500D01*
G01X-1142775Y985000D02*
Y1000000D01*
X-1136125D01*
G01X-1138575Y992750D02*
X-1142775D01*
G01X-1125250Y985000D02*
X-1126650Y985250D01*
X-1127875Y986250D01*
X-1128925Y987750D01*
X-1129625Y989500D01*
X-1129975Y991500D01*
Y993500D01*
X-1129625Y995500D01*
X-1128925Y997250D01*
X-1127875Y998750D01*
X-1126650Y999750D01*
X-1125250Y1000000D01*
X-1123850Y999750D01*
X-1122625Y998750D01*
X-1121575Y997250D01*
X-1120875Y995500D01*
X-1120525Y993500D01*
Y991500D01*
X-1120875Y989500D01*
X-1121575Y987750D01*
X-1122625Y986250D01*
X-1123850Y985250D01*
X-1125250Y985000D01*
G01X-1114550D02*
Y1000000D01*
X-1110175D01*
X-1108775Y999250D01*
X-1107900Y998250D01*
X-1107550Y996250D01*
X-1107900Y994250D01*
X-1108950Y993000D01*
X-1110175Y992250D01*
X-1114550D01*
G01X-1110175D02*
X-1107550Y985000D01*
G01X-1086325Y987000D02*
X-1084925Y985750D01*
X-1083350Y985000D01*
X-1081950D01*
X-1080550Y985750D01*
X-1079500Y987000D01*
X-1078975Y988750D01*
X-1079325Y990500D01*
X-1080200Y992000D01*
X-1081775Y993000D01*
X-1083875Y993500D01*
X-1085100Y994500D01*
X-1085625Y996250D01*
X-1085275Y998000D01*
X-1084400Y999250D01*
X-1083175Y1000000D01*
X-1081950D01*
X-1080725Y999500D01*
X-1079675Y998250D01*
G01X-1068450Y1000000D02*
Y985000D01*
G01X-1072475Y1000000D02*
X-1064425D01*
G01X-1058625Y985000D02*
X-1054250Y1000000D01*
X-1049875Y985000D01*
G01X-1051450Y990250D02*
X-1057050D01*
G01X-1036200Y998750D02*
X-1037250Y999500D01*
X-1038475Y1000000D01*
X-1039875D01*
X-1041450Y999250D01*
X-1042675Y998000D01*
X-1043550Y996500D01*
X-1044250Y994000D01*
X-1044425Y991750D01*
X-1044075Y989500D01*
X-1043550Y988000D01*
X-1042500Y986500D01*
X-1041275Y985500D01*
X-1040050Y985000D01*
X-1038825D01*
X-1037600Y985500D01*
X-1036550Y986250D01*
X-1035675Y987250D01*
G01X-1029700Y985000D02*
Y1000000D01*
G01X-1023050D02*
X-1029700Y990750D01*
G01X-1022000Y985000D02*
X-1026725Y995000D01*
G01X-1015500Y1000000D02*
Y989250D01*
X-1014800Y987000D01*
X-1013400Y985500D01*
X-1011650Y985000D01*
X-1009900Y985500D01*
X-1008500Y987000D01*
X-1007800Y989250D01*
Y1000000D01*
G01X-1000950Y985000D02*
Y1000000D01*
X-996750D01*
X-995350Y999250D01*
X-994300Y997500D01*
X-993950Y995500D01*
X-994300Y993500D01*
X-995175Y992000D01*
X-996750Y991250D01*
X-1000950D01*
G01X-983250Y984500D02*
X-983600Y984750D01*
Y985250D01*
X-983250Y985500D01*
X-982900Y985250D01*
Y984750D01*
X-983250Y984500D01*
G01X-1679050Y1015000D02*
Y1030000D01*
X-1681150Y1027000D01*
G01Y1015000D02*
X-1676950D01*
G01X-1641000D02*
Y1030000D01*
X-1636450Y1017500D01*
X-1631900Y1030000D01*
Y1015000D01*
G01X-1626625D02*
X-1622250Y1030000D01*
X-1617875Y1015000D01*
G01X-1619450Y1020250D02*
X-1625050D01*
G01X-1608050Y1030000D02*
Y1015000D01*
G01X-1612075Y1030000D02*
X-1604025D01*
G01X-1590350Y1015000D02*
X-1597350D01*
Y1030000D01*
X-1590350D01*
G01X-1593150Y1022750D02*
X-1597350D01*
G01X-1583150Y1015000D02*
Y1030000D01*
X-1578775D01*
X-1577375Y1029250D01*
X-1576500Y1028250D01*
X-1576150Y1026250D01*
X-1576500Y1024250D01*
X-1577550Y1023000D01*
X-1578775Y1022250D01*
X-1583150D01*
G01X-1578775D02*
X-1576150Y1015000D01*
G01X-1567550Y1030000D02*
X-1563350D01*
G01X-1565450D02*
Y1015000D01*
G01X-1567550D02*
X-1563350D01*
G01X-1555625D02*
X-1551250Y1030000D01*
X-1546875Y1015000D01*
G01X-1548450Y1020250D02*
X-1554050D01*
G01X-1540550Y1030000D02*
Y1015000D01*
X-1533550D01*
G01X-1522850Y1014500D02*
X-1523200Y1014750D01*
Y1015250D01*
X-1522850Y1015500D01*
X-1522500Y1015250D01*
Y1014750D01*
X-1522850Y1014500D01*
G01Y1021250D02*
X-1523200Y1021500D01*
Y1022000D01*
X-1522850Y1022250D01*
X-1522500Y1022000D01*
Y1021500D01*
X-1522850Y1021250D01*
G01X-1490950Y1015000D02*
X-1497950D01*
Y1030000D01*
X-1490950D01*
G01X-1493750Y1022750D02*
X-1497950D01*
G01X-1484800Y1015000D02*
Y1030000D01*
X-1480250Y1017500D01*
X-1475700Y1030000D01*
Y1015000D01*
G01X-1462200Y1028750D02*
X-1463250Y1029500D01*
X-1464475Y1030000D01*
X-1465875D01*
X-1467450Y1029250D01*
X-1468675Y1028000D01*
X-1469550Y1026500D01*
X-1470250Y1024000D01*
X-1470425Y1021750D01*
X-1470075Y1019500D01*
X-1469550Y1018000D01*
X-1468500Y1016500D01*
X-1467275Y1015500D01*
X-1466050Y1015000D01*
X-1464825D01*
X-1463600Y1015500D01*
X-1462550Y1016250D01*
X-1461675Y1017250D01*
G01X-1452200Y1012250D02*
X-1451500Y1015500D01*
G01X-1419950Y1015000D02*
X-1426950D01*
Y1030000D01*
X-1419950D01*
G01X-1422750Y1022750D02*
X-1426950D01*
G01X-1413800Y1015000D02*
Y1030000D01*
X-1409250Y1017500D01*
X-1404700Y1030000D01*
Y1015000D01*
G01X-1397325Y1020000D02*
X-1392775D01*
G01X-1380850Y1015000D02*
X-1379625Y1015250D01*
X-1378225Y1016000D01*
X-1377350Y1017250D01*
X-1377000Y1019000D01*
X-1377350Y1020750D01*
X-1378400Y1022250D01*
X-1379975Y1023000D01*
X-1381725D01*
X-1382775Y1023500D01*
X-1383650Y1024750D01*
X-1384000Y1026500D01*
X-1383475Y1028250D01*
X-1382250Y1029500D01*
X-1380850Y1030000D01*
X-1379450Y1029500D01*
X-1378225Y1028250D01*
X-1377700Y1026500D01*
X-1378050Y1024750D01*
X-1378925Y1023500D01*
X-1379975Y1023000D01*
X-1381725D01*
X-1383300Y1022250D01*
X-1384350Y1020750D01*
X-1384700Y1019000D01*
X-1384350Y1017250D01*
X-1383475Y1016000D01*
X-1382075Y1015250D01*
X-1380850Y1015000D01*
G01X-1366650D02*
X-1365425Y1015250D01*
X-1364025Y1016000D01*
X-1363150Y1017250D01*
X-1362800Y1019000D01*
X-1363150Y1020750D01*
X-1364200Y1022250D01*
X-1365775Y1023000D01*
X-1367525D01*
X-1368575Y1023500D01*
X-1369450Y1024750D01*
X-1369800Y1026500D01*
X-1369275Y1028250D01*
X-1368050Y1029500D01*
X-1366650Y1030000D01*
X-1365250Y1029500D01*
X-1364025Y1028250D01*
X-1363500Y1026500D01*
X-1363850Y1024750D01*
X-1364725Y1023500D01*
X-1365775Y1023000D01*
X-1367525D01*
X-1369100Y1022250D01*
X-1370150Y1020750D01*
X-1370500Y1019000D01*
X-1370150Y1017250D01*
X-1369275Y1016000D01*
X-1367875Y1015250D01*
X-1366650Y1015000D01*
G01X-1352450D02*
X-1351225Y1015250D01*
X-1349825Y1016000D01*
X-1348950Y1017250D01*
X-1348600Y1019000D01*
X-1348950Y1020750D01*
X-1350000Y1022250D01*
X-1351575Y1023000D01*
X-1353325D01*
X-1354375Y1023500D01*
X-1355250Y1024750D01*
X-1355600Y1026500D01*
X-1355075Y1028250D01*
X-1353850Y1029500D01*
X-1352450Y1030000D01*
X-1351050Y1029500D01*
X-1349825Y1028250D01*
X-1349300Y1026500D01*
X-1349650Y1024750D01*
X-1350525Y1023500D01*
X-1351575Y1023000D01*
X-1353325D01*
X-1354900Y1022250D01*
X-1355950Y1020750D01*
X-1356300Y1019000D01*
X-1355950Y1017250D01*
X-1355075Y1016000D01*
X-1353675Y1015250D01*
X-1352450Y1015000D01*
G01X-1338250Y1014500D02*
X-1338600Y1014750D01*
Y1015250D01*
X-1338250Y1015500D01*
X-1337900Y1015250D01*
Y1014750D01*
X-1338250Y1014500D01*
G01X-1697275Y1055000D02*
Y1070000D01*
X-1689225Y1055000D01*
Y1070000D01*
G01X-1679050Y1055000D02*
X-1680450Y1055250D01*
X-1681675Y1056250D01*
X-1682725Y1057750D01*
X-1683425Y1059500D01*
X-1683775Y1061500D01*
Y1063500D01*
X-1683425Y1065500D01*
X-1682725Y1067250D01*
X-1681675Y1068750D01*
X-1680450Y1069750D01*
X-1679050Y1070000D01*
X-1677650Y1069750D01*
X-1676425Y1068750D01*
X-1675375Y1067250D01*
X-1674675Y1065500D01*
X-1674325Y1063500D01*
Y1061500D01*
X-1674675Y1059500D01*
X-1675375Y1057750D01*
X-1676425Y1056250D01*
X-1677650Y1055250D01*
X-1679050Y1055000D01*
G01X-1664850Y1070000D02*
Y1055000D01*
G01X-1668875Y1070000D02*
X-1660825D01*
G01X-1647150Y1055000D02*
X-1654150D01*
Y1070000D01*
X-1647150D01*
G01X-1649950Y1062750D02*
X-1654150D01*
G01X-1640125Y1057000D02*
X-1638725Y1055750D01*
X-1637150Y1055000D01*
X-1635750D01*
X-1634350Y1055750D01*
X-1633300Y1057000D01*
X-1632775Y1058750D01*
X-1633125Y1060500D01*
X-1634000Y1062000D01*
X-1635575Y1063000D01*
X-1637675Y1063500D01*
X-1638900Y1064500D01*
X-1639425Y1066250D01*
X-1639075Y1068000D01*
X-1638200Y1069250D01*
X-1636975Y1070000D01*
X-1635750D01*
X-1634525Y1069500D01*
X-1633475Y1068250D01*
G01X-1622250Y1054500D02*
X-1622600Y1054750D01*
Y1055250D01*
X-1622250Y1055500D01*
X-1621900Y1055250D01*
Y1054750D01*
X-1622250Y1054500D01*
G01Y1061250D02*
X-1622600Y1061500D01*
Y1062000D01*
X-1622250Y1062250D01*
X-1621900Y1062000D01*
Y1061500D01*
X-1622250Y1061250D01*
G01X-1594725Y1050000D02*
X-1596475Y1052500D01*
X-1597350Y1055000D01*
Y1065000D01*
X-1596475Y1067500D01*
X-1594725Y1070000D01*
G01X-1583500D02*
Y1059250D01*
X-1582800Y1057000D01*
X-1581400Y1055500D01*
X-1579650Y1055000D01*
X-1577900Y1055500D01*
X-1576500Y1057000D01*
X-1575800Y1059250D01*
Y1070000D01*
G01X-1569475Y1055000D02*
Y1070000D01*
X-1561425Y1055000D01*
Y1070000D01*
G01X-1554750D02*
Y1055000D01*
X-1547750D01*
G01X-1533550D02*
X-1540550D01*
Y1070000D01*
X-1533550D01*
G01X-1536350Y1062750D02*
X-1540550D01*
G01X-1526525Y1057000D02*
X-1525125Y1055750D01*
X-1523550Y1055000D01*
X-1522150D01*
X-1520750Y1055750D01*
X-1519700Y1057000D01*
X-1519175Y1058750D01*
X-1519525Y1060500D01*
X-1520400Y1062000D01*
X-1521975Y1063000D01*
X-1524075Y1063500D01*
X-1525300Y1064500D01*
X-1525825Y1066250D01*
X-1525475Y1068000D01*
X-1524600Y1069250D01*
X-1523375Y1070000D01*
X-1522150D01*
X-1520925Y1069500D01*
X-1519875Y1068250D01*
G01X-1512325Y1057000D02*
X-1510925Y1055750D01*
X-1509350Y1055000D01*
X-1507950D01*
X-1506550Y1055750D01*
X-1505500Y1057000D01*
X-1504975Y1058750D01*
X-1505325Y1060500D01*
X-1506200Y1062000D01*
X-1507775Y1063000D01*
X-1509875Y1063500D01*
X-1511100Y1064500D01*
X-1511625Y1066250D01*
X-1511275Y1068000D01*
X-1510400Y1069250D01*
X-1509175Y1070000D01*
X-1507950D01*
X-1506725Y1069500D01*
X-1505675Y1068250D01*
G01X-1480250Y1055000D02*
X-1481650Y1055250D01*
X-1482875Y1056250D01*
X-1483925Y1057750D01*
X-1484625Y1059500D01*
X-1484975Y1061500D01*
Y1063500D01*
X-1484625Y1065500D01*
X-1483925Y1067250D01*
X-1482875Y1068750D01*
X-1481650Y1069750D01*
X-1480250Y1070000D01*
X-1478850Y1069750D01*
X-1477625Y1068750D01*
X-1476575Y1067250D01*
X-1475875Y1065500D01*
X-1475525Y1063500D01*
Y1061500D01*
X-1475875Y1059500D01*
X-1476575Y1057750D01*
X-1477625Y1056250D01*
X-1478850Y1055250D01*
X-1480250Y1055000D01*
G01X-1466050Y1070000D02*
Y1055000D01*
G01X-1470075Y1070000D02*
X-1462025D01*
G01X-1455525Y1055000D02*
Y1070000D01*
G01X-1448175D02*
Y1055000D01*
G01Y1062500D02*
X-1455525D01*
G01X-1434150Y1055000D02*
X-1441150D01*
Y1070000D01*
X-1434150D01*
G01X-1436950Y1062750D02*
X-1441150D01*
G01X-1428700Y1070000D02*
X-1426250Y1055000D01*
X-1423450Y1070000D01*
X-1420650Y1055000D01*
X-1418200Y1070000D01*
G01X-1411350D02*
X-1407150D01*
G01X-1409250D02*
Y1055000D01*
G01X-1411350D02*
X-1407150D01*
G01X-1398725Y1057000D02*
X-1397325Y1055750D01*
X-1395750Y1055000D01*
X-1394350D01*
X-1392950Y1055750D01*
X-1391900Y1057000D01*
X-1391375Y1058750D01*
X-1391725Y1060500D01*
X-1392600Y1062000D01*
X-1394175Y1063000D01*
X-1396275Y1063500D01*
X-1397500Y1064500D01*
X-1398025Y1066250D01*
X-1397675Y1068000D01*
X-1396800Y1069250D01*
X-1395575Y1070000D01*
X-1394350D01*
X-1393125Y1069500D01*
X-1392075Y1068250D01*
G01X-1377350Y1055000D02*
X-1384350D01*
Y1070000D01*
X-1377350D01*
G01X-1380150Y1062750D02*
X-1384350D01*
G01X-1356125Y1057000D02*
X-1354725Y1055750D01*
X-1353150Y1055000D01*
X-1351750D01*
X-1350350Y1055750D01*
X-1349300Y1057000D01*
X-1348775Y1058750D01*
X-1349125Y1060500D01*
X-1350000Y1062000D01*
X-1351575Y1063000D01*
X-1353675Y1063500D01*
X-1354900Y1064500D01*
X-1355425Y1066250D01*
X-1355075Y1068000D01*
X-1354200Y1069250D01*
X-1352975Y1070000D01*
X-1351750D01*
X-1350525Y1069500D01*
X-1349475Y1068250D01*
G01X-1341750Y1055000D02*
Y1070000D01*
X-1337550D01*
X-1336150Y1069250D01*
X-1335100Y1067500D01*
X-1334750Y1065500D01*
X-1335100Y1063500D01*
X-1335975Y1062000D01*
X-1337550Y1061250D01*
X-1341750D01*
G01X-1320550Y1055000D02*
X-1327550D01*
Y1070000D01*
X-1320550D01*
G01X-1323350Y1062750D02*
X-1327550D01*
G01X-1306000Y1068750D02*
X-1307050Y1069500D01*
X-1308275Y1070000D01*
X-1309675D01*
X-1311250Y1069250D01*
X-1312475Y1068000D01*
X-1313350Y1066500D01*
X-1314050Y1064000D01*
X-1314225Y1061750D01*
X-1313875Y1059500D01*
X-1313350Y1058000D01*
X-1312300Y1056500D01*
X-1311075Y1055500D01*
X-1309850Y1055000D01*
X-1308625D01*
X-1307400Y1055500D01*
X-1306350Y1056250D01*
X-1305475Y1057250D01*
G01X-1297750Y1070000D02*
X-1293550D01*
G01X-1295650D02*
Y1055000D01*
G01X-1297750D02*
X-1293550D01*
G01X-1284775D02*
Y1070000D01*
X-1278125D01*
G01X-1280575Y1062750D02*
X-1284775D01*
G01X-1269350Y1070000D02*
X-1265150D01*
G01X-1267250D02*
Y1055000D01*
G01X-1269350D02*
X-1265150D01*
G01X-1249550D02*
X-1256550D01*
Y1070000D01*
X-1249550D01*
G01X-1252350Y1062750D02*
X-1256550D01*
G01X-1242700Y1055000D02*
Y1070000D01*
X-1239200D01*
X-1237800Y1069250D01*
X-1236750Y1068250D01*
X-1235875Y1066750D01*
X-1235175Y1065000D01*
X-1235000Y1062500D01*
X-1235175Y1060000D01*
X-1235875Y1058250D01*
X-1236750Y1056750D01*
X-1237800Y1055750D01*
X-1239200Y1055000D01*
X-1242700D01*
G01X-1223775Y1050000D02*
X-1222025Y1052500D01*
X-1221150Y1055000D01*
Y1065000D01*
X-1222025Y1067500D01*
X-1223775Y1070000D01*
G01X-1475000Y-800000D02*
Y-850000D01*
G01Y1350000D02*
Y1300000D01*
G01X-1050000Y-800000D02*
Y-850000D01*
G01Y1350000D02*
Y1300000D01*
G01X-625000Y-800000D02*
Y-850000D01*
G01Y1350000D02*
Y1300000D01*
G01X-472125Y-324000D02*
X-473875Y-321500D01*
X-474750Y-319000D01*
Y-309000D01*
X-473875Y-306500D01*
X-472125Y-304000D01*
G01X-461075Y-319000D02*
Y-304000D01*
X-453025Y-319000D01*
Y-304000D01*
G01X-446000Y-319500D02*
X-439700Y-304000D01*
G01X-433025Y-319000D02*
X-428650Y-304000D01*
X-424275Y-319000D01*
G01X-425850Y-313750D02*
X-431450D01*
G01X-413575Y-324000D02*
X-411825Y-321500D01*
X-410950Y-319000D01*
Y-309000D01*
X-411825Y-306500D01*
X-413575Y-304000D01*
G01X-469625Y462500D02*
X-471375Y465000D01*
X-472250Y467500D01*
Y477500D01*
X-471375Y480000D01*
X-469625Y482500D01*
G01X-458575Y467500D02*
Y482500D01*
X-450525Y467500D01*
Y482500D01*
G01X-443500Y467000D02*
X-437200Y482500D01*
G01X-430525Y467500D02*
X-426150Y482500D01*
X-421775Y467500D01*
G01X-423350Y472750D02*
X-428950D01*
G01X-411075Y462500D02*
X-409325Y465000D01*
X-408450Y467500D01*
Y477500D01*
X-409325Y480000D01*
X-411075Y482500D01*
G01X-338500Y-431500D02*
Y-416500D01*
X-333950Y-429000D01*
X-329400Y-416500D01*
Y-431500D01*
G01X-321850Y-416500D02*
X-317650D01*
G01X-319750D02*
Y-431500D01*
G01X-321850D02*
X-317650D01*
G01X-301700Y-417750D02*
X-302750Y-417000D01*
X-303975Y-416500D01*
X-305375D01*
X-306950Y-417250D01*
X-308175Y-418500D01*
X-309050Y-420000D01*
X-309750Y-422500D01*
X-309925Y-424750D01*
X-309575Y-427000D01*
X-309050Y-428500D01*
X-308000Y-430000D01*
X-306775Y-431000D01*
X-305550Y-431500D01*
X-304325D01*
X-303100Y-431000D01*
X-302050Y-430250D01*
X-301175Y-429250D01*
G01X-294850Y-431500D02*
Y-416500D01*
X-290475D01*
X-289075Y-417250D01*
X-288200Y-418250D01*
X-287850Y-420250D01*
X-288200Y-422250D01*
X-289250Y-423500D01*
X-290475Y-424250D01*
X-294850D01*
G01X-290475D02*
X-287850Y-431500D01*
G01X-277150D02*
X-278550Y-431250D01*
X-279775Y-430250D01*
X-280825Y-428750D01*
X-281525Y-427000D01*
X-281875Y-425000D01*
Y-423000D01*
X-281525Y-421000D01*
X-280825Y-419250D01*
X-279775Y-417750D01*
X-278550Y-416750D01*
X-277150Y-416500D01*
X-275750Y-416750D01*
X-274525Y-417750D01*
X-273475Y-419250D01*
X-272775Y-421000D01*
X-272425Y-423000D01*
Y-425000D01*
X-272775Y-427000D01*
X-273475Y-428750D01*
X-274525Y-430250D01*
X-275750Y-431250D01*
X-277150Y-431500D01*
G01X-250850Y-416500D02*
X-246650D01*
G01X-248750D02*
Y-431500D01*
G01X-250850D02*
X-246650D01*
G01X-238575D02*
Y-416500D01*
X-230525Y-431500D01*
Y-416500D01*
G01X-216500Y-417750D02*
X-217550Y-417000D01*
X-218775Y-416500D01*
X-220175D01*
X-221750Y-417250D01*
X-222975Y-418500D01*
X-223850Y-420000D01*
X-224550Y-422500D01*
X-224725Y-424750D01*
X-224375Y-427000D01*
X-223850Y-428500D01*
X-222800Y-430000D01*
X-221575Y-431000D01*
X-220350Y-431500D01*
X-219125D01*
X-217900Y-431000D01*
X-216850Y-430250D01*
X-215975Y-429250D01*
G01X-209825Y-431500D02*
Y-416500D01*
G01X-202475D02*
Y-431500D01*
G01Y-424000D02*
X-209825D01*
G01X-188450Y-431500D02*
X-195450D01*
Y-416500D01*
X-188450D01*
G01X-191250Y-423750D02*
X-195450D01*
G01X-181425Y-429500D02*
X-180025Y-430750D01*
X-178450Y-431500D01*
X-177050D01*
X-175650Y-430750D01*
X-174600Y-429500D01*
X-174075Y-427750D01*
X-174425Y-426000D01*
X-175300Y-424500D01*
X-176875Y-423500D01*
X-178975Y-423000D01*
X-180200Y-422000D01*
X-180725Y-420250D01*
X-180375Y-418500D01*
X-179500Y-417250D01*
X-178275Y-416500D01*
X-177050D01*
X-175825Y-417000D01*
X-174775Y-418250D01*
G01X-149350Y-431500D02*
X-150750Y-431250D01*
X-151975Y-430250D01*
X-153025Y-428750D01*
X-153725Y-427000D01*
X-154075Y-425000D01*
Y-423000D01*
X-153725Y-421000D01*
X-153025Y-419250D01*
X-151975Y-417750D01*
X-150750Y-416750D01*
X-149350Y-416500D01*
X-147950Y-416750D01*
X-146725Y-417750D01*
X-145675Y-419250D01*
X-144975Y-421000D01*
X-144625Y-423000D01*
Y-425000D01*
X-144975Y-427000D01*
X-145675Y-428750D01*
X-146725Y-430250D01*
X-147950Y-431250D01*
X-149350Y-431500D01*
G01X-138475D02*
Y-416500D01*
X-131825D01*
G01X-134275Y-423750D02*
X-138475D01*
G01X-110775Y-431500D02*
Y-416500D01*
X-102725Y-431500D01*
Y-416500D01*
G01X-94650D02*
X-90450D01*
G01X-92550D02*
Y-431500D01*
G01X-94650D02*
X-90450D01*
G01X-74500Y-417750D02*
X-75550Y-417000D01*
X-76775Y-416500D01*
X-78175D01*
X-79750Y-417250D01*
X-80975Y-418500D01*
X-81850Y-420000D01*
X-82550Y-422500D01*
X-82725Y-424750D01*
X-82375Y-427000D01*
X-81850Y-428500D01*
X-80800Y-430000D01*
X-79575Y-431000D01*
X-78350Y-431500D01*
X-77125D01*
X-75900Y-431000D01*
X-74850Y-430250D01*
X-73975Y-429250D01*
G01X-68000Y-431500D02*
Y-416500D01*
G01X-61350D02*
X-68000Y-425750D01*
G01X-60300Y-431500D02*
X-65025Y-421500D01*
G01X-46450Y-431500D02*
X-53450D01*
Y-416500D01*
X-46450D01*
G01X-49250Y-423750D02*
X-53450D01*
G01X-39250Y-416500D02*
Y-431500D01*
X-32250D01*
G01X-21550Y-432000D02*
X-21900Y-431750D01*
Y-431250D01*
X-21550Y-431000D01*
X-21200Y-431250D01*
Y-431750D01*
X-21550Y-432000D01*
G01X-395075Y-390500D02*
X-394025Y-389000D01*
X-392800Y-388250D01*
X-391400Y-388000D01*
X-389650Y-388500D01*
X-388425Y-389750D01*
X-388075Y-391250D01*
X-388250Y-392750D01*
X-388950Y-394000D01*
X-392450Y-396500D01*
X-394025Y-398250D01*
X-395075Y-400750D01*
X-395425Y-403000D01*
X-388075D01*
G01X-377900D02*
X-377550Y-399750D01*
X-377025Y-397000D01*
X-376325Y-394500D01*
X-375450Y-391750D01*
X-374050Y-388000D01*
X-381050D01*
G01X-363350Y-403500D02*
X-363700Y-403250D01*
Y-402750D01*
X-363350Y-402500D01*
X-363000Y-402750D01*
Y-403250D01*
X-363350Y-403500D01*
G01X-331450Y-403000D02*
X-338450D01*
Y-388000D01*
X-331450D01*
G01X-334250Y-395250D02*
X-338450D01*
G01X-324600Y-403000D02*
Y-388000D01*
X-321100D01*
X-319700Y-388750D01*
X-318650Y-389750D01*
X-317775Y-391250D01*
X-317075Y-393000D01*
X-316900Y-395500D01*
X-317075Y-398000D01*
X-317775Y-399750D01*
X-318650Y-401250D01*
X-319700Y-402250D01*
X-321100Y-403000D01*
X-324600D01*
G01X-305500Y-395500D02*
X-302000D01*
Y-400000D01*
X-303050Y-401500D01*
X-304275Y-402500D01*
X-306025Y-403000D01*
X-307775Y-402500D01*
X-309000Y-401500D01*
X-310050Y-400000D01*
X-310750Y-398250D01*
X-311100Y-396250D01*
Y-394500D01*
X-310750Y-393000D01*
X-310050Y-391250D01*
X-309000Y-389750D01*
X-307950Y-388750D01*
X-306550Y-388000D01*
X-305325D01*
X-303925Y-388500D01*
X-302875Y-389500D01*
G01X-288850Y-403000D02*
X-295850D01*
Y-388000D01*
X-288850D01*
G01X-291650Y-395250D02*
X-295850D01*
G01X-260100Y-389250D02*
X-261150Y-388500D01*
X-262375Y-388000D01*
X-263775D01*
X-265350Y-388750D01*
X-266575Y-390000D01*
X-267450Y-391500D01*
X-268150Y-394000D01*
X-268325Y-396250D01*
X-267975Y-398500D01*
X-267450Y-400000D01*
X-266400Y-401500D01*
X-265175Y-402500D01*
X-263950Y-403000D01*
X-262725D01*
X-261500Y-402500D01*
X-260450Y-401750D01*
X-259575Y-400750D01*
G01X-249750Y-403000D02*
X-251150Y-402750D01*
X-252375Y-401750D01*
X-253425Y-400250D01*
X-254125Y-398500D01*
X-254475Y-396500D01*
Y-394500D01*
X-254125Y-392500D01*
X-253425Y-390750D01*
X-252375Y-389250D01*
X-251150Y-388250D01*
X-249750Y-388000D01*
X-248350Y-388250D01*
X-247125Y-389250D01*
X-246075Y-390750D01*
X-245375Y-392500D01*
X-245025Y-394500D01*
Y-396500D01*
X-245375Y-398500D01*
X-246075Y-400250D01*
X-247125Y-401750D01*
X-248350Y-402750D01*
X-249750Y-403000D01*
G01X-239575D02*
Y-388000D01*
X-231525Y-403000D01*
Y-388000D01*
G01X-225375Y-403000D02*
Y-388000D01*
X-217325Y-403000D01*
Y-388000D01*
G01X-203650Y-403000D02*
X-210650D01*
Y-388000D01*
X-203650D01*
G01X-206450Y-395250D02*
X-210650D01*
G01X-189100Y-389250D02*
X-190150Y-388500D01*
X-191375Y-388000D01*
X-192775D01*
X-194350Y-388750D01*
X-195575Y-390000D01*
X-196450Y-391500D01*
X-197150Y-394000D01*
X-197325Y-396250D01*
X-196975Y-398500D01*
X-196450Y-400000D01*
X-195400Y-401500D01*
X-194175Y-402500D01*
X-192950Y-403000D01*
X-191725D01*
X-190500Y-402500D01*
X-189450Y-401750D01*
X-188575Y-400750D01*
G01X-178750Y-388000D02*
Y-403000D01*
G01X-182775Y-388000D02*
X-174725D01*
G01X-164550Y-403000D02*
X-165950Y-402750D01*
X-167175Y-401750D01*
X-168225Y-400250D01*
X-168925Y-398500D01*
X-169275Y-396500D01*
Y-394500D01*
X-168925Y-392500D01*
X-168225Y-390750D01*
X-167175Y-389250D01*
X-165950Y-388250D01*
X-164550Y-388000D01*
X-163150Y-388250D01*
X-161925Y-389250D01*
X-160875Y-390750D01*
X-160175Y-392500D01*
X-159825Y-394500D01*
Y-396500D01*
X-160175Y-398500D01*
X-160875Y-400250D01*
X-161925Y-401750D01*
X-163150Y-402750D01*
X-164550Y-403000D01*
G01X-153850D02*
Y-388000D01*
X-149475D01*
X-148075Y-388750D01*
X-147200Y-389750D01*
X-146850Y-391750D01*
X-147200Y-393750D01*
X-148250Y-395000D01*
X-149475Y-395750D01*
X-153850D01*
G01X-149475D02*
X-146850Y-403000D01*
G01X-125275D02*
Y-388000D01*
X-118625D01*
G01X-121075Y-395250D02*
X-125275D01*
G01X-109850Y-388000D02*
X-105650D01*
G01X-107750D02*
Y-403000D01*
G01X-109850D02*
X-105650D01*
G01X-97575D02*
Y-388000D01*
X-89525Y-403000D01*
Y-388000D01*
G01X-78300Y-395500D02*
X-74800D01*
Y-400000D01*
X-75850Y-401500D01*
X-77075Y-402500D01*
X-78825Y-403000D01*
X-80575Y-402500D01*
X-81800Y-401500D01*
X-82850Y-400000D01*
X-83550Y-398250D01*
X-83900Y-396250D01*
Y-394500D01*
X-83550Y-393000D01*
X-82850Y-391250D01*
X-81800Y-389750D01*
X-80750Y-388750D01*
X-79350Y-388000D01*
X-78125D01*
X-76725Y-388500D01*
X-75675Y-389500D01*
G01X-61650Y-403000D02*
X-68650D01*
Y-388000D01*
X-61650D01*
G01X-64450Y-395250D02*
X-68650D01*
G01X-54450Y-403000D02*
Y-388000D01*
X-50075D01*
X-48675Y-388750D01*
X-47800Y-389750D01*
X-47450Y-391750D01*
X-47800Y-393750D01*
X-48850Y-395000D01*
X-50075Y-395750D01*
X-54450D01*
G01X-50075D02*
X-47450Y-403000D01*
G01X-40425Y-401000D02*
X-39025Y-402250D01*
X-37450Y-403000D01*
X-36050D01*
X-34650Y-402250D01*
X-33600Y-401000D01*
X-33075Y-399250D01*
X-33425Y-397500D01*
X-34300Y-396000D01*
X-35875Y-395000D01*
X-37975Y-394500D01*
X-39200Y-393500D01*
X-39725Y-391750D01*
X-39375Y-390000D01*
X-38500Y-388750D01*
X-37275Y-388000D01*
X-36050D01*
X-34825Y-388500D01*
X-33775Y-389750D01*
G01X-22550Y-403500D02*
X-22900Y-403250D01*
Y-402750D01*
X-22550Y-402500D01*
X-22200Y-402750D01*
Y-403250D01*
X-22550Y-403500D01*
G01Y-396750D02*
X-22900Y-396500D01*
Y-396000D01*
X-22550Y-395750D01*
X-22200Y-396000D01*
Y-396500D01*
X-22550Y-396750D01*
G01X2350Y-403000D02*
Y-388000D01*
X6725D01*
X8125Y-388750D01*
X9000Y-389750D01*
X9350Y-391750D01*
X9000Y-393750D01*
X7950Y-395000D01*
X6725Y-395750D01*
X2350D01*
G01X6725D02*
X9350Y-403000D01*
G01X23550D02*
X16550D01*
Y-388000D01*
X23550D01*
G01X20750Y-395250D02*
X16550D01*
G01X34250Y-403000D02*
X32850Y-402750D01*
X31625Y-401750D01*
X30575Y-400250D01*
X29875Y-398500D01*
X29525Y-396500D01*
Y-394500D01*
X29875Y-392500D01*
X30575Y-390750D01*
X31625Y-389250D01*
X32850Y-388250D01*
X34250Y-388000D01*
X35650Y-388250D01*
X36875Y-389250D01*
X37925Y-390750D01*
X38625Y-392500D01*
X38975Y-394500D01*
Y-396500D01*
X38625Y-398500D01*
X37925Y-400250D01*
X36875Y-401750D01*
X35650Y-402750D01*
X34250Y-403000D01*
G01X35650Y-399000D02*
X37750Y-403000D01*
G01X44600Y-388000D02*
Y-398750D01*
X45300Y-401000D01*
X46700Y-402500D01*
X48450Y-403000D01*
X50200Y-402500D01*
X51600Y-401000D01*
X52300Y-398750D01*
Y-388000D01*
G01X60550D02*
X64750D01*
G01X62650D02*
Y-403000D01*
G01X60550D02*
X64750D01*
G01X73350D02*
Y-388000D01*
X77725D01*
X79125Y-388750D01*
X80000Y-389750D01*
X80350Y-391750D01*
X80000Y-393750D01*
X78950Y-395000D01*
X77725Y-395750D01*
X73350D01*
G01X77725D02*
X80350Y-403000D01*
G01X94550D02*
X87550D01*
Y-388000D01*
X94550D01*
G01X91750Y-395250D02*
X87550D01*
G01X115600Y-400000D02*
X116650Y-401750D01*
X118050Y-402750D01*
X119625Y-403000D01*
X121025Y-402750D01*
X122425Y-401500D01*
X123300Y-400000D01*
X123475Y-398500D01*
X123125Y-396750D01*
X121900Y-395500D01*
X120675Y-395000D01*
X119100D01*
G01X120675D02*
X121725Y-394250D01*
X122600Y-393000D01*
X122950Y-391500D01*
X122600Y-390000D01*
X121725Y-388750D01*
X120150Y-388000D01*
X118575Y-388250D01*
X117000Y-389250D01*
G01X133650Y-388000D02*
X132250Y-388500D01*
X131200Y-389750D01*
X130500Y-391250D01*
X129975Y-393250D01*
X129800Y-395500D01*
X129975Y-397750D01*
X130500Y-399750D01*
X131200Y-401250D01*
X132250Y-402500D01*
X133650Y-403000D01*
X135050Y-402500D01*
X136100Y-401250D01*
X136800Y-399750D01*
X137325Y-397750D01*
X137500Y-395500D01*
X137325Y-393250D01*
X136800Y-391250D01*
X136100Y-389750D01*
X135050Y-388500D01*
X133650Y-388000D01*
G01X157500Y-403000D02*
Y-388000D01*
X162050Y-400500D01*
X166600Y-388000D01*
Y-403000D01*
G01X174150Y-388000D02*
X178350D01*
G01X176250D02*
Y-403000D01*
G01X174150D02*
X178350D01*
G01X194300Y-389250D02*
X193250Y-388500D01*
X192025Y-388000D01*
X190625D01*
X189050Y-388750D01*
X187825Y-390000D01*
X186950Y-391500D01*
X186250Y-394000D01*
X186075Y-396250D01*
X186425Y-398500D01*
X186950Y-400000D01*
X188000Y-401500D01*
X189225Y-402500D01*
X190450Y-403000D01*
X191675D01*
X192900Y-402500D01*
X193950Y-401750D01*
X194825Y-400750D01*
G01X201150Y-403000D02*
Y-388000D01*
X205525D01*
X206925Y-388750D01*
X207800Y-389750D01*
X208150Y-391750D01*
X207800Y-393750D01*
X206750Y-395000D01*
X205525Y-395750D01*
X201150D01*
G01X205525D02*
X208150Y-403000D01*
G01X218850D02*
X217450Y-402750D01*
X216225Y-401750D01*
X215175Y-400250D01*
X214475Y-398500D01*
X214125Y-396500D01*
Y-394500D01*
X214475Y-392500D01*
X215175Y-390750D01*
X216225Y-389250D01*
X217450Y-388250D01*
X218850Y-388000D01*
X220250Y-388250D01*
X221475Y-389250D01*
X222525Y-390750D01*
X223225Y-392500D01*
X223575Y-394500D01*
Y-396500D01*
X223225Y-398500D01*
X222525Y-400250D01*
X221475Y-401750D01*
X220250Y-402750D01*
X218850Y-403000D01*
G01X245150Y-388000D02*
X249350D01*
G01X247250D02*
Y-403000D01*
G01X245150D02*
X249350D01*
G01X257425D02*
Y-388000D01*
X265475Y-403000D01*
Y-388000D01*
G01X279500Y-389250D02*
X278450Y-388500D01*
X277225Y-388000D01*
X275825D01*
X274250Y-388750D01*
X273025Y-390000D01*
X272150Y-391500D01*
X271450Y-394000D01*
X271275Y-396250D01*
X271625Y-398500D01*
X272150Y-400000D01*
X273200Y-401500D01*
X274425Y-402500D01*
X275650Y-403000D01*
X276875D01*
X278100Y-402500D01*
X279150Y-401750D01*
X280025Y-400750D01*
G01X286175Y-403000D02*
Y-388000D01*
G01X293525D02*
Y-403000D01*
G01Y-395500D02*
X286175D01*
G01X307550Y-403000D02*
X300550D01*
Y-388000D01*
X307550D01*
G01X304750Y-395250D02*
X300550D01*
G01X314575Y-401000D02*
X315975Y-402250D01*
X317550Y-403000D01*
X318950D01*
X320350Y-402250D01*
X321400Y-401000D01*
X321925Y-399250D01*
X321575Y-397500D01*
X320700Y-396000D01*
X319125Y-395000D01*
X317025Y-394500D01*
X315800Y-393500D01*
X315275Y-391750D01*
X315625Y-390000D01*
X316500Y-388750D01*
X317725Y-388000D01*
X318950D01*
X320175Y-388500D01*
X321225Y-389750D01*
G01X342975Y-403000D02*
Y-388000D01*
G01X350325D02*
Y-403000D01*
G01Y-395500D02*
X342975D01*
G01X356475Y-403000D02*
X360850Y-388000D01*
X365225Y-403000D01*
G01X363650Y-397750D02*
X358050D01*
G01X371550Y-403000D02*
Y-388000D01*
X375925D01*
X377325Y-388750D01*
X378200Y-389750D01*
X378550Y-391750D01*
X378200Y-393750D01*
X377150Y-395000D01*
X375925Y-395750D01*
X371550D01*
G01X375925D02*
X378550Y-403000D01*
G01X385400D02*
Y-388000D01*
X388900D01*
X390300Y-388750D01*
X391350Y-389750D01*
X392225Y-391250D01*
X392925Y-393000D01*
X393100Y-395500D01*
X392925Y-398000D01*
X392225Y-399750D01*
X391350Y-401250D01*
X390300Y-402250D01*
X388900Y-403000D01*
X385400D01*
G01X418700Y-395500D02*
X422200D01*
Y-400000D01*
X421150Y-401500D01*
X419925Y-402500D01*
X418175Y-403000D01*
X416425Y-402500D01*
X415200Y-401500D01*
X414150Y-400000D01*
X413450Y-398250D01*
X413100Y-396250D01*
Y-394500D01*
X413450Y-393000D01*
X414150Y-391250D01*
X415200Y-389750D01*
X416250Y-388750D01*
X417650Y-388000D01*
X418875D01*
X420275Y-388500D01*
X421325Y-389500D01*
G01X431850Y-403000D02*
X430450Y-402750D01*
X429225Y-401750D01*
X428175Y-400250D01*
X427475Y-398500D01*
X427125Y-396500D01*
Y-394500D01*
X427475Y-392500D01*
X428175Y-390750D01*
X429225Y-389250D01*
X430450Y-388250D01*
X431850Y-388000D01*
X433250Y-388250D01*
X434475Y-389250D01*
X435525Y-390750D01*
X436225Y-392500D01*
X436575Y-394500D01*
Y-396500D01*
X436225Y-398500D01*
X435525Y-400250D01*
X434475Y-401750D01*
X433250Y-402750D01*
X431850Y-403000D01*
G01X442550Y-388000D02*
Y-403000D01*
X449550D01*
G01X456400D02*
Y-388000D01*
X459900D01*
X461300Y-388750D01*
X462350Y-389750D01*
X463225Y-391250D01*
X463925Y-393000D01*
X464100Y-395500D01*
X463925Y-398000D01*
X463225Y-399750D01*
X462350Y-401250D01*
X461300Y-402250D01*
X459900Y-403000D01*
X456400D01*
G01X488650D02*
X487250Y-402750D01*
X486025Y-401750D01*
X484975Y-400250D01*
X484275Y-398500D01*
X483925Y-396500D01*
Y-394500D01*
X484275Y-392500D01*
X484975Y-390750D01*
X486025Y-389250D01*
X487250Y-388250D01*
X488650Y-388000D01*
X490050Y-388250D01*
X491275Y-389250D01*
X492325Y-390750D01*
X493025Y-392500D01*
X493375Y-394500D01*
Y-396500D01*
X493025Y-398500D01*
X492325Y-400250D01*
X491275Y-401750D01*
X490050Y-402750D01*
X488650Y-403000D01*
G01X498475Y-388000D02*
X502850Y-403000D01*
X507225Y-388000D01*
G01X520550Y-403000D02*
X513550D01*
Y-388000D01*
X520550D01*
G01X517750Y-395250D02*
X513550D01*
G01X527750Y-403000D02*
Y-388000D01*
X532125D01*
X533525Y-388750D01*
X534400Y-389750D01*
X534750Y-391750D01*
X534400Y-393750D01*
X533350Y-395000D01*
X532125Y-395750D01*
X527750D01*
G01X532125D02*
X534750Y-403000D01*
G01X559650D02*
Y-388000D01*
X557550Y-391000D01*
G01Y-403000D02*
X561750D01*
G01X570000Y-400750D02*
X571050Y-402000D01*
X572275Y-402750D01*
X573850Y-403000D01*
X575425Y-402500D01*
X576650Y-401500D01*
X577525Y-399750D01*
X577700Y-397750D01*
X577350Y-395750D01*
X576475Y-394500D01*
X575250Y-393500D01*
X574025Y-393250D01*
X572800Y-393500D01*
X571225Y-394500D01*
X571750Y-388000D01*
X576475D01*
G01X588050D02*
X586650Y-388500D01*
X585600Y-389750D01*
X584900Y-391250D01*
X584375Y-393250D01*
X584200Y-395500D01*
X584375Y-397750D01*
X584900Y-399750D01*
X585600Y-401250D01*
X586650Y-402500D01*
X588050Y-403000D01*
X589450Y-402500D01*
X590500Y-401250D01*
X591200Y-399750D01*
X591725Y-397750D01*
X591900Y-395500D01*
X591725Y-393250D01*
X591200Y-391250D01*
X590500Y-389750D01*
X589450Y-388500D01*
X588050Y-388000D01*
G01X599975Y-398000D02*
X604525D01*
G01X613125Y-390500D02*
X614175Y-389000D01*
X615400Y-388250D01*
X616800Y-388000D01*
X618550Y-388500D01*
X619775Y-389750D01*
X620125Y-391250D01*
X619950Y-392750D01*
X619250Y-394000D01*
X615750Y-396500D01*
X614175Y-398250D01*
X613125Y-400750D01*
X612775Y-403000D01*
X620125D01*
G01X630650Y-388000D02*
X629250Y-388500D01*
X628200Y-389750D01*
X627500Y-391250D01*
X626975Y-393250D01*
X626800Y-395500D01*
X626975Y-397750D01*
X627500Y-399750D01*
X628200Y-401250D01*
X629250Y-402500D01*
X630650Y-403000D01*
X632050Y-402500D01*
X633100Y-401250D01*
X633800Y-399750D01*
X634325Y-397750D01*
X634500Y-395500D01*
X634325Y-393250D01*
X633800Y-391250D01*
X633100Y-389750D01*
X632050Y-388500D01*
X630650Y-388000D01*
G01X644850D02*
X643450Y-388500D01*
X642400Y-389750D01*
X641700Y-391250D01*
X641175Y-393250D01*
X641000Y-395500D01*
X641175Y-397750D01*
X641700Y-399750D01*
X642400Y-401250D01*
X643450Y-402500D01*
X644850Y-403000D01*
X646250Y-402500D01*
X647300Y-401250D01*
X648000Y-399750D01*
X648525Y-397750D01*
X648700Y-395500D01*
X648525Y-393250D01*
X648000Y-391250D01*
X647300Y-389750D01*
X646250Y-388500D01*
X644850Y-388000D01*
G01X-396575Y-307500D02*
X-395525Y-306000D01*
X-394300Y-305250D01*
X-392900Y-305000D01*
X-391150Y-305500D01*
X-389925Y-306750D01*
X-389575Y-308250D01*
X-389750Y-309750D01*
X-390450Y-311000D01*
X-393950Y-313500D01*
X-395525Y-315250D01*
X-396575Y-317750D01*
X-396925Y-320000D01*
X-389575D01*
G01X-382375Y-313750D02*
X-381150Y-312000D01*
X-380100Y-311000D01*
X-378700Y-310500D01*
X-377475Y-311000D01*
X-376600Y-312000D01*
X-375900Y-313500D01*
X-375725Y-315250D01*
X-375900Y-316750D01*
X-376600Y-318250D01*
X-377650Y-319500D01*
X-378875Y-320000D01*
X-380275Y-319500D01*
X-381500Y-318000D01*
X-382200Y-315750D01*
X-382375Y-313250D01*
X-382025Y-310000D01*
X-381500Y-308250D01*
X-380625Y-306500D01*
X-379400Y-305250D01*
X-378175Y-305000D01*
X-376950Y-305500D01*
X-376075Y-306750D01*
G01X-364850Y-320500D02*
X-365200Y-320250D01*
Y-319750D01*
X-364850Y-319500D01*
X-364500Y-319750D01*
Y-320250D01*
X-364850Y-320500D01*
G01X-338550Y-305000D02*
X-334350D01*
G01X-336450D02*
Y-320000D01*
G01X-338550D02*
X-334350D01*
G01X-326800D02*
Y-305000D01*
X-322250Y-317500D01*
X-317700Y-305000D01*
Y-320000D01*
G01X-311550D02*
Y-305000D01*
X-307350D01*
X-305950Y-305750D01*
X-304900Y-307500D01*
X-304550Y-309500D01*
X-304900Y-311500D01*
X-305775Y-313000D01*
X-307350Y-313750D01*
X-311550D01*
G01X-290350Y-320000D02*
X-297350D01*
Y-305000D01*
X-290350D01*
G01X-293150Y-312250D02*
X-297350D01*
G01X-283500Y-320000D02*
Y-305000D01*
X-280000D01*
X-278600Y-305750D01*
X-277550Y-306750D01*
X-276675Y-308250D01*
X-275975Y-310000D01*
X-275800Y-312500D01*
X-275975Y-315000D01*
X-276675Y-316750D01*
X-277550Y-318250D01*
X-278600Y-319250D01*
X-280000Y-320000D01*
X-283500D01*
G01X-269825D02*
X-265450Y-305000D01*
X-261075Y-320000D01*
G01X-262650Y-314750D02*
X-268250D01*
G01X-255275Y-320000D02*
Y-305000D01*
X-247225Y-320000D01*
Y-305000D01*
G01X-233200Y-306250D02*
X-234250Y-305500D01*
X-235475Y-305000D01*
X-236875D01*
X-238450Y-305750D01*
X-239675Y-307000D01*
X-240550Y-308500D01*
X-241250Y-311000D01*
X-241425Y-313250D01*
X-241075Y-315500D01*
X-240550Y-317000D01*
X-239500Y-318500D01*
X-238275Y-319500D01*
X-237050Y-320000D01*
X-235825D01*
X-234600Y-319500D01*
X-233550Y-318750D01*
X-232675Y-317750D01*
G01X-219350Y-320000D02*
X-226350D01*
Y-305000D01*
X-219350D01*
G01X-222150Y-312250D02*
X-226350D01*
G01X-190600Y-306250D02*
X-191650Y-305500D01*
X-192875Y-305000D01*
X-194275D01*
X-195850Y-305750D01*
X-197075Y-307000D01*
X-197950Y-308500D01*
X-198650Y-311000D01*
X-198825Y-313250D01*
X-198475Y-315500D01*
X-197950Y-317000D01*
X-196900Y-318500D01*
X-195675Y-319500D01*
X-194450Y-320000D01*
X-193225D01*
X-192000Y-319500D01*
X-190950Y-318750D01*
X-190075Y-317750D01*
G01X-180250Y-320000D02*
X-181650Y-319750D01*
X-182875Y-318750D01*
X-183925Y-317250D01*
X-184625Y-315500D01*
X-184975Y-313500D01*
Y-311500D01*
X-184625Y-309500D01*
X-183925Y-307750D01*
X-182875Y-306250D01*
X-181650Y-305250D01*
X-180250Y-305000D01*
X-178850Y-305250D01*
X-177625Y-306250D01*
X-176575Y-307750D01*
X-175875Y-309500D01*
X-175525Y-311500D01*
Y-313500D01*
X-175875Y-315500D01*
X-176575Y-317250D01*
X-177625Y-318750D01*
X-178850Y-319750D01*
X-180250Y-320000D01*
G01X-169900Y-305000D02*
Y-315750D01*
X-169200Y-318000D01*
X-167800Y-319500D01*
X-166050Y-320000D01*
X-164300Y-319500D01*
X-162900Y-318000D01*
X-162200Y-315750D01*
Y-305000D01*
G01X-155350Y-320000D02*
Y-305000D01*
X-151150D01*
X-149750Y-305750D01*
X-148700Y-307500D01*
X-148350Y-309500D01*
X-148700Y-311500D01*
X-149575Y-313000D01*
X-151150Y-313750D01*
X-155350D01*
G01X-137650Y-320000D02*
X-139050Y-319750D01*
X-140275Y-318750D01*
X-141325Y-317250D01*
X-142025Y-315500D01*
X-142375Y-313500D01*
Y-311500D01*
X-142025Y-309500D01*
X-141325Y-307750D01*
X-140275Y-306250D01*
X-139050Y-305250D01*
X-137650Y-305000D01*
X-136250Y-305250D01*
X-135025Y-306250D01*
X-133975Y-307750D01*
X-133275Y-309500D01*
X-132925Y-311500D01*
Y-313500D01*
X-133275Y-315500D01*
X-133975Y-317250D01*
X-135025Y-318750D01*
X-136250Y-319750D01*
X-137650Y-320000D01*
G01X-127475D02*
Y-305000D01*
X-119425Y-320000D01*
Y-305000D01*
G01X-197600Y-275000D02*
X-194450Y-285000D01*
X-191300Y-275000D01*
G01X-180250D02*
Y-285000D01*
G01Y-271000D02*
X-180600Y-270750D01*
Y-270250D01*
X-180250Y-270000D01*
X-179900Y-270250D01*
Y-270750D01*
X-180250Y-271000D01*
G01X-166050Y-275000D02*
Y-285000D01*
G01Y-271000D02*
X-166400Y-270750D01*
Y-270250D01*
X-166050Y-270000D01*
X-165700Y-270250D01*
Y-270750D01*
X-166050Y-271000D01*
G01X-151850Y-275000D02*
Y-285000D01*
G01Y-271000D02*
X-152200Y-270750D01*
Y-270250D01*
X-151850Y-270000D01*
X-151500Y-270250D01*
Y-270750D01*
X-151850Y-271000D01*
G01X-137650Y-285500D02*
X-138000Y-285250D01*
Y-284750D01*
X-137650Y-284500D01*
X-137300Y-284750D01*
Y-285250D01*
X-137650Y-285500D01*
G01X-109250Y-270000D02*
Y-285000D01*
G01X-113275Y-270000D02*
X-105225D01*
G01X-98725Y-285000D02*
Y-270000D01*
G01X-91375D02*
Y-285000D01*
G01Y-277500D02*
X-98725D01*
G01X-77350Y-285000D02*
X-84350D01*
Y-270000D01*
X-77350D01*
G01X-80150Y-277250D02*
X-84350D01*
G01X-52450Y-285000D02*
X-53850Y-284750D01*
X-55075Y-283750D01*
X-56125Y-282250D01*
X-56825Y-280500D01*
X-57175Y-278500D01*
Y-276500D01*
X-56825Y-274500D01*
X-56125Y-272750D01*
X-55075Y-271250D01*
X-53850Y-270250D01*
X-52450Y-270000D01*
X-51050Y-270250D01*
X-49825Y-271250D01*
X-48775Y-272750D01*
X-48075Y-274500D01*
X-47725Y-276500D01*
Y-278500D01*
X-48075Y-280500D01*
X-48775Y-282250D01*
X-49825Y-283750D01*
X-51050Y-284750D01*
X-52450Y-285000D01*
G01X-42100Y-270000D02*
Y-280750D01*
X-41400Y-283000D01*
X-40000Y-284500D01*
X-38250Y-285000D01*
X-36500Y-284500D01*
X-35100Y-283000D01*
X-34400Y-280750D01*
Y-270000D01*
G01X-24050D02*
Y-285000D01*
G01X-28075Y-270000D02*
X-20025D01*
G01X-6350Y-285000D02*
X-13350D01*
Y-270000D01*
X-6350D01*
G01X-9150Y-277250D02*
X-13350D01*
G01X850Y-285000D02*
Y-270000D01*
X5225D01*
X6625Y-270750D01*
X7500Y-271750D01*
X7850Y-273750D01*
X7500Y-275750D01*
X6450Y-277000D01*
X5225Y-277750D01*
X850D01*
G01X5225D02*
X7850Y-285000D01*
G01X28900D02*
Y-270000D01*
X32400D01*
X33800Y-270750D01*
X34850Y-271750D01*
X35725Y-273250D01*
X36425Y-275000D01*
X36600Y-277500D01*
X36425Y-280000D01*
X35725Y-281750D01*
X34850Y-283250D01*
X33800Y-284250D01*
X32400Y-285000D01*
X28900D01*
G01X44850Y-270000D02*
X49050D01*
G01X46950D02*
Y-285000D01*
G01X44850D02*
X49050D01*
G01X56600D02*
Y-270000D01*
X61150Y-282500D01*
X65700Y-270000D01*
Y-285000D01*
G01X78850D02*
X71850D01*
Y-270000D01*
X78850D01*
G01X76050Y-277250D02*
X71850D01*
G01X85525Y-285000D02*
Y-270000D01*
X93575Y-285000D01*
Y-270000D01*
G01X100075Y-283000D02*
X101475Y-284250D01*
X103050Y-285000D01*
X104450D01*
X105850Y-284250D01*
X106900Y-283000D01*
X107425Y-281250D01*
X107075Y-279500D01*
X106200Y-278000D01*
X104625Y-277000D01*
X102525Y-276500D01*
X101300Y-275500D01*
X100775Y-273750D01*
X101125Y-272000D01*
X102000Y-270750D01*
X103225Y-270000D01*
X104450D01*
X105675Y-270500D01*
X106725Y-271750D01*
G01X115850Y-270000D02*
X120050D01*
G01X117950D02*
Y-285000D01*
G01X115850D02*
X120050D01*
G01X132150D02*
X130750Y-284750D01*
X129525Y-283750D01*
X128475Y-282250D01*
X127775Y-280500D01*
X127425Y-278500D01*
Y-276500D01*
X127775Y-274500D01*
X128475Y-272750D01*
X129525Y-271250D01*
X130750Y-270250D01*
X132150Y-270000D01*
X133550Y-270250D01*
X134775Y-271250D01*
X135825Y-272750D01*
X136525Y-274500D01*
X136875Y-276500D01*
Y-278500D01*
X136525Y-280500D01*
X135825Y-282250D01*
X134775Y-283750D01*
X133550Y-284750D01*
X132150Y-285000D01*
G01X142325D02*
Y-270000D01*
X150375Y-285000D01*
Y-270000D01*
G01X156875Y-283000D02*
X158275Y-284250D01*
X159850Y-285000D01*
X161250D01*
X162650Y-284250D01*
X163700Y-283000D01*
X164225Y-281250D01*
X163875Y-279500D01*
X163000Y-278000D01*
X161425Y-277000D01*
X159325Y-276500D01*
X158100Y-275500D01*
X157575Y-273750D01*
X157925Y-272000D01*
X158800Y-270750D01*
X160025Y-270000D01*
X161250D01*
X162475Y-270500D01*
X163525Y-271750D01*
G01X188950Y-285000D02*
X187550Y-284750D01*
X186325Y-283750D01*
X185275Y-282250D01*
X184575Y-280500D01*
X184225Y-278500D01*
Y-276500D01*
X184575Y-274500D01*
X185275Y-272750D01*
X186325Y-271250D01*
X187550Y-270250D01*
X188950Y-270000D01*
X190350Y-270250D01*
X191575Y-271250D01*
X192625Y-272750D01*
X193325Y-274500D01*
X193675Y-276500D01*
Y-278500D01*
X193325Y-280500D01*
X192625Y-282250D01*
X191575Y-283750D01*
X190350Y-284750D01*
X188950Y-285000D01*
G01X199825D02*
Y-270000D01*
X206475D01*
G01X204025Y-277250D02*
X199825D01*
G01X231550Y-270000D02*
Y-285000D01*
G01X227525Y-270000D02*
X235575D01*
G01X242075Y-285000D02*
Y-270000D01*
G01X249425D02*
Y-285000D01*
G01Y-277500D02*
X242075D01*
G01X263450Y-285000D02*
X256450D01*
Y-270000D01*
X263450D01*
G01X260650Y-277250D02*
X256450D01*
G01X289750Y-277000D02*
X290450Y-276250D01*
X290975Y-275000D01*
X291325Y-273250D01*
X290975Y-271750D01*
X290275Y-270750D01*
X289050Y-270000D01*
X284325D01*
Y-285000D01*
X290100D01*
X291325Y-284000D01*
X292025Y-282500D01*
X292375Y-280750D01*
X292025Y-279000D01*
X290975Y-277500D01*
X289750Y-277000D01*
X284325D01*
G01X302550Y-285000D02*
X301150Y-284750D01*
X299925Y-283750D01*
X298875Y-282250D01*
X298175Y-280500D01*
X297825Y-278500D01*
Y-276500D01*
X298175Y-274500D01*
X298875Y-272750D01*
X299925Y-271250D01*
X301150Y-270250D01*
X302550Y-270000D01*
X303950Y-270250D01*
X305175Y-271250D01*
X306225Y-272750D01*
X306925Y-274500D01*
X307275Y-276500D01*
Y-278500D01*
X306925Y-280500D01*
X306225Y-282250D01*
X305175Y-283750D01*
X303950Y-284750D01*
X302550Y-285000D01*
G01X312375D02*
X316750Y-270000D01*
X321125Y-285000D01*
G01X319550Y-279750D02*
X313950D01*
G01X327450Y-285000D02*
Y-270000D01*
X331825D01*
X333225Y-270750D01*
X334100Y-271750D01*
X334450Y-273750D01*
X334100Y-275750D01*
X333050Y-277000D01*
X331825Y-277750D01*
X327450D01*
G01X331825D02*
X334450Y-285000D01*
G01X341300D02*
Y-270000D01*
X344800D01*
X346200Y-270750D01*
X347250Y-271750D01*
X348125Y-273250D01*
X348825Y-275000D01*
X349000Y-277500D01*
X348825Y-280000D01*
X348125Y-281750D01*
X347250Y-283250D01*
X346200Y-284250D01*
X344800Y-285000D01*
X341300D01*
G01X-197600Y-245000D02*
X-194450Y-255000D01*
X-191300Y-245000D01*
G01X-180250D02*
Y-255000D01*
G01Y-241000D02*
X-180600Y-240750D01*
Y-240250D01*
X-180250Y-240000D01*
X-179900Y-240250D01*
Y-240750D01*
X-180250Y-241000D01*
G01X-166050Y-245000D02*
Y-255000D01*
G01Y-241000D02*
X-166400Y-240750D01*
Y-240250D01*
X-166050Y-240000D01*
X-165700Y-240250D01*
Y-240750D01*
X-166050Y-241000D01*
G01X-151850Y-255500D02*
X-152200Y-255250D01*
Y-254750D01*
X-151850Y-254500D01*
X-151500Y-254750D01*
Y-255250D01*
X-151850Y-255500D01*
G01X-109250Y-240000D02*
Y-255000D01*
G01X-113275Y-240000D02*
X-105225D01*
G01X-98725Y-255000D02*
Y-240000D01*
G01X-91375D02*
Y-255000D01*
G01Y-247500D02*
X-98725D01*
G01X-77350Y-255000D02*
X-84350D01*
Y-240000D01*
X-77350D01*
G01X-80150Y-247250D02*
X-84350D01*
G01X-56300Y-255000D02*
Y-240000D01*
X-52800D01*
X-51400Y-240750D01*
X-50350Y-241750D01*
X-49475Y-243250D01*
X-48775Y-245000D01*
X-48600Y-247500D01*
X-48775Y-250000D01*
X-49475Y-251750D01*
X-50350Y-253250D01*
X-51400Y-254250D01*
X-52800Y-255000D01*
X-56300D01*
G01X-40350Y-240000D02*
X-36150D01*
G01X-38250D02*
Y-255000D01*
G01X-40350D02*
X-36150D01*
G01X-28600D02*
Y-240000D01*
X-24050Y-252500D01*
X-19500Y-240000D01*
Y-255000D01*
G01X-6350D02*
X-13350D01*
Y-240000D01*
X-6350D01*
G01X-9150Y-247250D02*
X-13350D01*
G01X325Y-255000D02*
Y-240000D01*
X8375Y-255000D01*
Y-240000D01*
G01X14875Y-253000D02*
X16275Y-254250D01*
X17850Y-255000D01*
X19250D01*
X20650Y-254250D01*
X21700Y-253000D01*
X22225Y-251250D01*
X21875Y-249500D01*
X21000Y-248000D01*
X19425Y-247000D01*
X17325Y-246500D01*
X16100Y-245500D01*
X15575Y-243750D01*
X15925Y-242000D01*
X16800Y-240750D01*
X18025Y-240000D01*
X19250D01*
X20475Y-240500D01*
X21525Y-241750D01*
G01X30650Y-240000D02*
X34850D01*
G01X32750D02*
Y-255000D01*
G01X30650D02*
X34850D01*
G01X46950D02*
X45550Y-254750D01*
X44325Y-253750D01*
X43275Y-252250D01*
X42575Y-250500D01*
X42225Y-248500D01*
Y-246500D01*
X42575Y-244500D01*
X43275Y-242750D01*
X44325Y-241250D01*
X45550Y-240250D01*
X46950Y-240000D01*
X48350Y-240250D01*
X49575Y-241250D01*
X50625Y-242750D01*
X51325Y-244500D01*
X51675Y-246500D01*
Y-248500D01*
X51325Y-250500D01*
X50625Y-252250D01*
X49575Y-253750D01*
X48350Y-254750D01*
X46950Y-255000D01*
G01X57125D02*
Y-240000D01*
X65175Y-255000D01*
Y-240000D01*
G01X71675Y-253000D02*
X73075Y-254250D01*
X74650Y-255000D01*
X76050D01*
X77450Y-254250D01*
X78500Y-253000D01*
X79025Y-251250D01*
X78675Y-249500D01*
X77800Y-248000D01*
X76225Y-247000D01*
X74125Y-246500D01*
X72900Y-245500D01*
X72375Y-243750D01*
X72725Y-242000D01*
X73600Y-240750D01*
X74825Y-240000D01*
X76050D01*
X77275Y-240500D01*
X78325Y-241750D01*
G01X103750Y-255000D02*
X102350Y-254750D01*
X101125Y-253750D01*
X100075Y-252250D01*
X99375Y-250500D01*
X99025Y-248500D01*
Y-246500D01*
X99375Y-244500D01*
X100075Y-242750D01*
X101125Y-241250D01*
X102350Y-240250D01*
X103750Y-240000D01*
X105150Y-240250D01*
X106375Y-241250D01*
X107425Y-242750D01*
X108125Y-244500D01*
X108475Y-246500D01*
Y-248500D01*
X108125Y-250500D01*
X107425Y-252250D01*
X106375Y-253750D01*
X105150Y-254750D01*
X103750Y-255000D01*
G01X114625D02*
Y-240000D01*
X121275D01*
G01X118825Y-247250D02*
X114625D01*
G01X146350Y-255000D02*
X144950Y-254750D01*
X143725Y-253750D01*
X142675Y-252250D01*
X141975Y-250500D01*
X141625Y-248500D01*
Y-246500D01*
X141975Y-244500D01*
X142675Y-242750D01*
X143725Y-241250D01*
X144950Y-240250D01*
X146350Y-240000D01*
X147750Y-240250D01*
X148975Y-241250D01*
X150025Y-242750D01*
X150725Y-244500D01*
X151075Y-246500D01*
Y-248500D01*
X150725Y-250500D01*
X150025Y-252250D01*
X148975Y-253750D01*
X147750Y-254750D01*
X146350Y-255000D01*
G01X156525D02*
Y-240000D01*
X164575Y-255000D01*
Y-240000D01*
G01X178250Y-255000D02*
X171250D01*
Y-240000D01*
X178250D01*
G01X175450Y-247250D02*
X171250D01*
G01X203150Y-255000D02*
X201750Y-254750D01*
X200525Y-253750D01*
X199475Y-252250D01*
X198775Y-250500D01*
X198425Y-248500D01*
Y-246500D01*
X198775Y-244500D01*
X199475Y-242750D01*
X200525Y-241250D01*
X201750Y-240250D01*
X203150Y-240000D01*
X204550Y-240250D01*
X205775Y-241250D01*
X206825Y-242750D01*
X207525Y-244500D01*
X207875Y-246500D01*
Y-248500D01*
X207525Y-250500D01*
X206825Y-252250D01*
X205775Y-253750D01*
X204550Y-254750D01*
X203150Y-255000D01*
G01X214025D02*
Y-240000D01*
X220675D01*
G01X218225Y-247250D02*
X214025D01*
G01X249250Y-255000D02*
X242250D01*
Y-240000D01*
X249250D01*
G01X246450Y-247250D02*
X242250D01*
G01X255575Y-240000D02*
X259950Y-255000D01*
X264325Y-240000D01*
G01X277650Y-255000D02*
X270650D01*
Y-240000D01*
X277650D01*
G01X274850Y-247250D02*
X270650D01*
G01X284850Y-255000D02*
Y-240000D01*
X289225D01*
X290625Y-240750D01*
X291500Y-241750D01*
X291850Y-243750D01*
X291500Y-245750D01*
X290450Y-247000D01*
X289225Y-247750D01*
X284850D01*
G01X289225D02*
X291850Y-255000D01*
G01X302550D02*
Y-248250D01*
X299050Y-240000D01*
G01X306050D02*
X302550Y-248250D01*
G01X327100Y-255000D02*
Y-240000D01*
G01X333750D02*
X327100Y-249250D01*
G01X334800Y-255000D02*
X330075Y-245000D01*
G01X343050Y-240000D02*
X347250D01*
G01X345150D02*
Y-255000D01*
G01X343050D02*
X347250D01*
G01X355325D02*
Y-240000D01*
X363375Y-255000D01*
Y-240000D01*
G01X369700Y-255000D02*
Y-240000D01*
X373200D01*
X374600Y-240750D01*
X375650Y-241750D01*
X376525Y-243250D01*
X377225Y-245000D01*
X377400Y-247500D01*
X377225Y-250000D01*
X376525Y-251750D01*
X375650Y-253250D01*
X374600Y-254250D01*
X373200Y-255000D01*
X369700D01*
G01X401950D02*
X400550Y-254750D01*
X399325Y-253750D01*
X398275Y-252250D01*
X397575Y-250500D01*
X397225Y-248500D01*
Y-246500D01*
X397575Y-244500D01*
X398275Y-242750D01*
X399325Y-241250D01*
X400550Y-240250D01*
X401950Y-240000D01*
X403350Y-240250D01*
X404575Y-241250D01*
X405625Y-242750D01*
X406325Y-244500D01*
X406675Y-246500D01*
Y-248500D01*
X406325Y-250500D01*
X405625Y-252250D01*
X404575Y-253750D01*
X403350Y-254750D01*
X401950Y-255000D01*
G01X412825D02*
Y-240000D01*
X419475D01*
G01X417025Y-247250D02*
X412825D01*
G01X440875Y-255000D02*
Y-240000D01*
G01X448225D02*
Y-255000D01*
G01Y-247500D02*
X440875D01*
G01X458750Y-255000D02*
X457350Y-254750D01*
X456125Y-253750D01*
X455075Y-252250D01*
X454375Y-250500D01*
X454025Y-248500D01*
Y-246500D01*
X454375Y-244500D01*
X455075Y-242750D01*
X456125Y-241250D01*
X457350Y-240250D01*
X458750Y-240000D01*
X460150Y-240250D01*
X461375Y-241250D01*
X462425Y-242750D01*
X463125Y-244500D01*
X463475Y-246500D01*
Y-248500D01*
X463125Y-250500D01*
X462425Y-252250D01*
X461375Y-253750D01*
X460150Y-254750D01*
X458750Y-255000D01*
G01X469450Y-240000D02*
Y-255000D01*
X476450D01*
G01X490650D02*
X483650D01*
Y-240000D01*
X490650D01*
G01X487850Y-247250D02*
X483650D01*
G01X-197600Y-215000D02*
X-194450Y-225000D01*
X-191300Y-215000D01*
G01X-180250D02*
Y-225000D01*
G01Y-211000D02*
X-180600Y-210750D01*
Y-210250D01*
X-180250Y-210000D01*
X-179900Y-210250D01*
Y-210750D01*
X-180250Y-211000D01*
G01X-166050Y-225500D02*
X-166400Y-225250D01*
Y-224750D01*
X-166050Y-224500D01*
X-165700Y-224750D01*
Y-225250D01*
X-166050Y-225500D01*
G01X-109250Y-210000D02*
Y-225000D01*
G01X-113275Y-210000D02*
X-105225D01*
G01X-98725Y-225000D02*
Y-210000D01*
G01X-91375D02*
Y-225000D01*
G01Y-217500D02*
X-98725D01*
G01X-77350Y-225000D02*
X-84350D01*
Y-210000D01*
X-77350D01*
G01X-80150Y-217250D02*
X-84350D01*
G01X-70150Y-225000D02*
Y-210000D01*
X-65775D01*
X-64375Y-210750D01*
X-63500Y-211750D01*
X-63150Y-213750D01*
X-63500Y-215750D01*
X-64550Y-217000D01*
X-65775Y-217750D01*
X-70150D01*
G01X-65775D02*
X-63150Y-225000D01*
G01X-57000D02*
Y-210000D01*
X-52450Y-222500D01*
X-47900Y-210000D01*
Y-225000D01*
G01X-42625D02*
X-38250Y-210000D01*
X-33875Y-225000D01*
G01X-35450Y-219750D02*
X-41050D01*
G01X-27550Y-210000D02*
Y-225000D01*
X-20550D01*
G01X675Y-223000D02*
X2075Y-224250D01*
X3650Y-225000D01*
X5050D01*
X6450Y-224250D01*
X7500Y-223000D01*
X8025Y-221250D01*
X7675Y-219500D01*
X6800Y-218000D01*
X5225Y-217000D01*
X3125Y-216500D01*
X1900Y-215500D01*
X1375Y-213750D01*
X1725Y-212000D01*
X2600Y-210750D01*
X3825Y-210000D01*
X5050D01*
X6275Y-210500D01*
X7325Y-211750D01*
G01X18550Y-210000D02*
Y-225000D01*
G01X14525Y-210000D02*
X22575D01*
G01X29250Y-225000D02*
Y-210000D01*
X33625D01*
X35025Y-210750D01*
X35900Y-211750D01*
X36250Y-213750D01*
X35900Y-215750D01*
X34850Y-217000D01*
X33625Y-217750D01*
X29250D01*
G01X33625D02*
X36250Y-225000D01*
G01X50450D02*
X43450D01*
Y-210000D01*
X50450D01*
G01X47650Y-217250D02*
X43450D01*
G01X57475Y-223000D02*
X58875Y-224250D01*
X60450Y-225000D01*
X61850D01*
X63250Y-224250D01*
X64300Y-223000D01*
X64825Y-221250D01*
X64475Y-219500D01*
X63600Y-218000D01*
X62025Y-217000D01*
X59925Y-216500D01*
X58700Y-215500D01*
X58175Y-213750D01*
X58525Y-212000D01*
X59400Y-210750D01*
X60625Y-210000D01*
X61850D01*
X63075Y-210500D01*
X64125Y-211750D01*
G01X71675Y-223000D02*
X73075Y-224250D01*
X74650Y-225000D01*
X76050D01*
X77450Y-224250D01*
X78500Y-223000D01*
X79025Y-221250D01*
X78675Y-219500D01*
X77800Y-218000D01*
X76225Y-217000D01*
X74125Y-216500D01*
X72900Y-215500D01*
X72375Y-213750D01*
X72725Y-212000D01*
X73600Y-210750D01*
X74825Y-210000D01*
X76050D01*
X77275Y-210500D01*
X78325Y-211750D01*
G01X-197600Y-185000D02*
X-194450Y-195000D01*
X-191300Y-185000D01*
G01X-180250Y-195500D02*
X-180600Y-195250D01*
Y-194750D01*
X-180250Y-194500D01*
X-179900Y-194750D01*
Y-195250D01*
X-180250Y-195500D01*
G01X-112925Y-193000D02*
X-111525Y-194250D01*
X-109950Y-195000D01*
X-108550D01*
X-107150Y-194250D01*
X-106100Y-193000D01*
X-105575Y-191250D01*
X-105925Y-189500D01*
X-106800Y-188000D01*
X-108375Y-187000D01*
X-110475Y-186500D01*
X-111700Y-185500D01*
X-112225Y-183750D01*
X-111875Y-182000D01*
X-111000Y-180750D01*
X-109775Y-180000D01*
X-108550D01*
X-107325Y-180500D01*
X-106275Y-181750D01*
G01X-95050Y-195000D02*
X-96450Y-194750D01*
X-97675Y-193750D01*
X-98725Y-192250D01*
X-99425Y-190500D01*
X-99775Y-188500D01*
Y-186500D01*
X-99425Y-184500D01*
X-98725Y-182750D01*
X-97675Y-181250D01*
X-96450Y-180250D01*
X-95050Y-180000D01*
X-93650Y-180250D01*
X-92425Y-181250D01*
X-91375Y-182750D01*
X-90675Y-184500D01*
X-90325Y-186500D01*
Y-188500D01*
X-90675Y-190500D01*
X-91375Y-192250D01*
X-92425Y-193750D01*
X-93650Y-194750D01*
X-95050Y-195000D01*
G01X-84350Y-180000D02*
Y-195000D01*
X-77350D01*
G01X-70500D02*
Y-180000D01*
X-67000D01*
X-65600Y-180750D01*
X-64550Y-181750D01*
X-63675Y-183250D01*
X-62975Y-185000D01*
X-62800Y-187500D01*
X-62975Y-190000D01*
X-63675Y-191750D01*
X-64550Y-193250D01*
X-65600Y-194250D01*
X-67000Y-195000D01*
X-70500D01*
G01X-48950D02*
X-55950D01*
Y-180000D01*
X-48950D01*
G01X-51750Y-187250D02*
X-55950D01*
G01X-41750Y-195000D02*
Y-180000D01*
X-37375D01*
X-35975Y-180750D01*
X-35100Y-181750D01*
X-34750Y-183750D01*
X-35100Y-185750D01*
X-36150Y-187000D01*
X-37375Y-187750D01*
X-41750D01*
G01X-37375D02*
X-34750Y-195000D01*
G01X-28425D02*
X-24050Y-180000D01*
X-19675Y-195000D01*
G01X-21250Y-189750D02*
X-26850D01*
G01X-8450Y-187000D02*
X-7750Y-186250D01*
X-7225Y-185000D01*
X-6875Y-183250D01*
X-7225Y-181750D01*
X-7925Y-180750D01*
X-9150Y-180000D01*
X-13875D01*
Y-195000D01*
X-8100D01*
X-6875Y-194000D01*
X-6175Y-192500D01*
X-5825Y-190750D01*
X-6175Y-189000D01*
X-7225Y-187500D01*
X-8450Y-187000D01*
X-13875D01*
G01X2250Y-180000D02*
X6450D01*
G01X4350D02*
Y-195000D01*
G01X2250D02*
X6450D01*
G01X15050Y-180000D02*
Y-195000D01*
X22050D01*
G01X30650Y-180000D02*
X34850D01*
G01X32750D02*
Y-195000D01*
G01X30650D02*
X34850D01*
G01X46950Y-180000D02*
Y-195000D01*
G01X42925Y-180000D02*
X50975D01*
G01X61150Y-195000D02*
Y-188250D01*
X57650Y-180000D01*
G01X64650D02*
X61150Y-188250D01*
G01X-194450Y-155000D02*
Y-165000D01*
G01Y-151000D02*
X-194800Y-150750D01*
Y-150250D01*
X-194450Y-150000D01*
X-194100Y-150250D01*
Y-150750D01*
X-194450Y-151000D01*
G01X-183400Y-155000D02*
X-180250Y-165000D01*
X-177100Y-155000D01*
G01X-166050Y-165500D02*
X-166400Y-165250D01*
Y-164750D01*
X-166050Y-164500D01*
X-165700Y-164750D01*
Y-165250D01*
X-166050Y-165500D01*
G01X-105400Y-151250D02*
X-106450Y-150500D01*
X-107675Y-150000D01*
X-109075D01*
X-110650Y-150750D01*
X-111875Y-152000D01*
X-112750Y-153500D01*
X-113450Y-156000D01*
X-113625Y-158250D01*
X-113275Y-160500D01*
X-112750Y-162000D01*
X-111700Y-163500D01*
X-110475Y-164500D01*
X-109250Y-165000D01*
X-108025D01*
X-106800Y-164500D01*
X-105750Y-163750D01*
X-104875Y-162750D01*
G01X-98550Y-150000D02*
Y-165000D01*
X-91550D01*
G01X-77350D02*
X-84350D01*
Y-150000D01*
X-77350D01*
G01X-80150Y-157250D02*
X-84350D01*
G01X-71025Y-165000D02*
X-66650Y-150000D01*
X-62275Y-165000D01*
G01X-63850Y-159750D02*
X-69450D01*
G01X-56475Y-165000D02*
Y-150000D01*
X-48425Y-165000D01*
Y-150000D01*
G01X-41750D02*
Y-165000D01*
X-34750D01*
G01X-26150Y-150000D02*
X-21950D01*
G01X-24050D02*
Y-165000D01*
G01X-26150D02*
X-21950D01*
G01X-13875D02*
Y-150000D01*
X-5825Y-165000D01*
Y-150000D01*
G01X7850Y-165000D02*
X850D01*
Y-150000D01*
X7850D01*
G01X5050Y-157250D02*
X850D01*
G01X14875Y-163000D02*
X16275Y-164250D01*
X17850Y-165000D01*
X19250D01*
X20650Y-164250D01*
X21700Y-163000D01*
X22225Y-161250D01*
X21875Y-159500D01*
X21000Y-158000D01*
X19425Y-157000D01*
X17325Y-156500D01*
X16100Y-155500D01*
X15575Y-153750D01*
X15925Y-152000D01*
X16800Y-150750D01*
X18025Y-150000D01*
X19250D01*
X20475Y-150500D01*
X21525Y-151750D01*
G01X29075Y-163000D02*
X30475Y-164250D01*
X32050Y-165000D01*
X33450D01*
X34850Y-164250D01*
X35900Y-163000D01*
X36425Y-161250D01*
X36075Y-159500D01*
X35200Y-158000D01*
X33625Y-157000D01*
X31525Y-156500D01*
X30300Y-155500D01*
X29775Y-153750D01*
X30125Y-152000D01*
X31000Y-150750D01*
X32225Y-150000D01*
X33450D01*
X34675Y-150500D01*
X35725Y-151750D01*
G01X61150Y-150000D02*
Y-165000D01*
G01X57125Y-150000D02*
X65175D01*
G01X78850Y-165000D02*
X71850D01*
Y-150000D01*
X78850D01*
G01X76050Y-157250D02*
X71850D01*
G01X85875Y-163000D02*
X87275Y-164250D01*
X88850Y-165000D01*
X90250D01*
X91650Y-164250D01*
X92700Y-163000D01*
X93225Y-161250D01*
X92875Y-159500D01*
X92000Y-158000D01*
X90425Y-157000D01*
X88325Y-156500D01*
X87100Y-155500D01*
X86575Y-153750D01*
X86925Y-152000D01*
X87800Y-150750D01*
X89025Y-150000D01*
X90250D01*
X91475Y-150500D01*
X92525Y-151750D01*
G01X103750Y-150000D02*
Y-165000D01*
G01X99725Y-150000D02*
X107775D01*
G01X-194450Y-125000D02*
Y-135000D01*
G01Y-121000D02*
X-194800Y-120750D01*
Y-120250D01*
X-194450Y-120000D01*
X-194100Y-120250D01*
Y-120750D01*
X-194450Y-121000D01*
G01X-180250Y-125000D02*
Y-135000D01*
G01Y-121000D02*
X-180600Y-120750D01*
Y-120250D01*
X-180250Y-120000D01*
X-179900Y-120250D01*
Y-120750D01*
X-180250Y-121000D01*
G01X-166050Y-125000D02*
Y-135000D01*
G01Y-121000D02*
X-166400Y-120750D01*
Y-120250D01*
X-166050Y-120000D01*
X-165700Y-120250D01*
Y-120750D01*
X-166050Y-121000D01*
G01X-151850Y-135500D02*
X-152200Y-135250D01*
Y-134750D01*
X-151850Y-134500D01*
X-151500Y-134750D01*
Y-135250D01*
X-151850Y-135500D01*
G01X-112750Y-135000D02*
Y-120000D01*
X-108550D01*
X-107150Y-120750D01*
X-106100Y-122500D01*
X-105750Y-124500D01*
X-106100Y-126500D01*
X-106975Y-128000D01*
X-108550Y-128750D01*
X-112750D01*
G01X-91550Y-135000D02*
X-98550D01*
Y-120000D01*
X-91550D01*
G01X-94350Y-127250D02*
X-98550D01*
G01X-77350Y-135000D02*
X-84350D01*
Y-120000D01*
X-77350D01*
G01X-80150Y-127250D02*
X-84350D01*
G01X-70150Y-120000D02*
Y-135000D01*
X-63150D01*
G01X-41925Y-133000D02*
X-40525Y-134250D01*
X-38950Y-135000D01*
X-37550D01*
X-36150Y-134250D01*
X-35100Y-133000D01*
X-34575Y-131250D01*
X-34925Y-129500D01*
X-35800Y-128000D01*
X-37375Y-127000D01*
X-39475Y-126500D01*
X-40700Y-125500D01*
X-41225Y-123750D01*
X-40875Y-122000D01*
X-40000Y-120750D01*
X-38775Y-120000D01*
X-37550D01*
X-36325Y-120500D01*
X-35275Y-121750D01*
G01X-24050Y-120000D02*
Y-135000D01*
G01X-28075Y-120000D02*
X-20025D01*
G01X-13350Y-135000D02*
Y-120000D01*
X-8975D01*
X-7575Y-120750D01*
X-6700Y-121750D01*
X-6350Y-123750D01*
X-6700Y-125750D01*
X-7750Y-127000D01*
X-8975Y-127750D01*
X-13350D01*
G01X-8975D02*
X-6350Y-135000D01*
G01X7850D02*
X850D01*
Y-120000D01*
X7850D01*
G01X5050Y-127250D02*
X850D01*
G01X14525Y-135000D02*
Y-120000D01*
X22575Y-135000D01*
Y-120000D01*
G01X33800Y-127500D02*
X37300D01*
Y-132000D01*
X36250Y-133500D01*
X35025Y-134500D01*
X33275Y-135000D01*
X31525Y-134500D01*
X30300Y-133500D01*
X29250Y-132000D01*
X28550Y-130250D01*
X28200Y-128250D01*
Y-126500D01*
X28550Y-125000D01*
X29250Y-123250D01*
X30300Y-121750D01*
X31350Y-120750D01*
X32750Y-120000D01*
X33975D01*
X35375Y-120500D01*
X36425Y-121500D01*
G01X46950Y-120000D02*
Y-135000D01*
G01X42925Y-120000D02*
X50975D01*
G01X57475Y-135000D02*
Y-120000D01*
G01X64825D02*
Y-135000D01*
G01Y-127500D02*
X57475D01*
G01X-194450Y-95000D02*
Y-105000D01*
G01Y-91000D02*
X-194800Y-90750D01*
Y-90250D01*
X-194450Y-90000D01*
X-194100Y-90250D01*
Y-90750D01*
X-194450Y-91000D01*
G01X-180250Y-95000D02*
Y-105000D01*
G01Y-91000D02*
X-180600Y-90750D01*
Y-90250D01*
X-180250Y-90000D01*
X-179900Y-90250D01*
Y-90750D01*
X-180250Y-91000D01*
G01X-166050Y-105500D02*
X-166400Y-105250D01*
Y-104750D01*
X-166050Y-104500D01*
X-165700Y-104750D01*
Y-105250D01*
X-166050Y-105500D01*
G01X-107850Y-97000D02*
X-107150Y-96250D01*
X-106625Y-95000D01*
X-106275Y-93250D01*
X-106625Y-91750D01*
X-107325Y-90750D01*
X-108550Y-90000D01*
X-113275D01*
Y-105000D01*
X-107500D01*
X-106275Y-104000D01*
X-105575Y-102500D01*
X-105225Y-100750D01*
X-105575Y-99000D01*
X-106625Y-97500D01*
X-107850Y-97000D01*
X-113275D01*
G01X-95050Y-105000D02*
X-96450Y-104750D01*
X-97675Y-103750D01*
X-98725Y-102250D01*
X-99425Y-100500D01*
X-99775Y-98500D01*
Y-96500D01*
X-99425Y-94500D01*
X-98725Y-92750D01*
X-97675Y-91250D01*
X-96450Y-90250D01*
X-95050Y-90000D01*
X-93650Y-90250D01*
X-92425Y-91250D01*
X-91375Y-92750D01*
X-90675Y-94500D01*
X-90325Y-96500D01*
Y-98500D01*
X-90675Y-100500D01*
X-91375Y-102250D01*
X-92425Y-103750D01*
X-93650Y-104750D01*
X-95050Y-105000D01*
G01X-86100Y-90000D02*
X-83650Y-105000D01*
X-80850Y-90000D01*
X-78050Y-105000D01*
X-75600Y-90000D01*
G01X-56825Y-105000D02*
X-52450Y-90000D01*
X-48075Y-105000D01*
G01X-49650Y-99750D02*
X-55250D01*
G01X-42275Y-105000D02*
Y-90000D01*
X-34225Y-105000D01*
Y-90000D01*
G01X-27900Y-105000D02*
Y-90000D01*
X-24400D01*
X-23000Y-90750D01*
X-21950Y-91750D01*
X-21075Y-93250D01*
X-20375Y-95000D01*
X-20200Y-97500D01*
X-20375Y-100000D01*
X-21075Y-101750D01*
X-21950Y-103250D01*
X-23000Y-104250D01*
X-24400Y-105000D01*
X-27900D01*
G01X4350Y-90000D02*
Y-105000D01*
G01X325Y-90000D02*
X8375D01*
G01X13300D02*
X15750Y-105000D01*
X18550Y-90000D01*
X21350Y-105000D01*
X23800Y-90000D01*
G01X30650D02*
X34850D01*
G01X32750D02*
Y-105000D01*
G01X30650D02*
X34850D01*
G01X43275Y-103000D02*
X44675Y-104250D01*
X46250Y-105000D01*
X47650D01*
X49050Y-104250D01*
X50100Y-103000D01*
X50625Y-101250D01*
X50275Y-99500D01*
X49400Y-98000D01*
X47825Y-97000D01*
X45725Y-96500D01*
X44500Y-95500D01*
X43975Y-93750D01*
X44325Y-92000D01*
X45200Y-90750D01*
X46425Y-90000D01*
X47650D01*
X48875Y-90500D01*
X49925Y-91750D01*
G01X61150Y-90000D02*
Y-105000D01*
G01X57125Y-90000D02*
X65175D01*
G01X88675Y-110000D02*
X86925Y-107500D01*
X86050Y-105000D01*
Y-95000D01*
X86925Y-92500D01*
X88675Y-90000D01*
G01X99200Y-105000D02*
Y-90000D01*
X103750Y-102500D01*
X108300Y-90000D01*
Y-105000D01*
G01X113575D02*
X117950Y-90000D01*
X122325Y-105000D01*
G01X120750Y-99750D02*
X115150D01*
G01X128475Y-105000D02*
X135825Y-90000D01*
G01X128475D02*
X135825Y-105000D01*
G01X156175D02*
X160550Y-90000D01*
X164925Y-105000D01*
G01X163350Y-99750D02*
X157750D01*
G01X170725Y-105000D02*
Y-90000D01*
X178775Y-105000D01*
Y-90000D01*
G01X185100Y-105000D02*
Y-90000D01*
X188600D01*
X190000Y-90750D01*
X191050Y-91750D01*
X191925Y-93250D01*
X192625Y-95000D01*
X192800Y-97500D01*
X192625Y-100000D01*
X191925Y-101750D01*
X191050Y-103250D01*
X190000Y-104250D01*
X188600Y-105000D01*
X185100D01*
G01X212800D02*
Y-90000D01*
X217350Y-102500D01*
X221900Y-90000D01*
Y-105000D01*
G01X229450Y-90000D02*
X233650D01*
G01X231550D02*
Y-105000D01*
G01X229450D02*
X233650D01*
G01X241725D02*
Y-90000D01*
X249775Y-105000D01*
Y-90000D01*
G01X260825Y-110000D02*
X262575Y-107500D01*
X263450Y-105000D01*
Y-95000D01*
X262575Y-92500D01*
X260825Y-90000D01*
G01X-194450Y-65000D02*
Y-75000D01*
G01Y-61000D02*
X-194800Y-60750D01*
Y-60250D01*
X-194450Y-60000D01*
X-194100Y-60250D01*
Y-60750D01*
X-194450Y-61000D01*
G01X-180250Y-75500D02*
X-180600Y-75250D01*
Y-74750D01*
X-180250Y-74500D01*
X-179900Y-74750D01*
Y-75250D01*
X-180250Y-75500D01*
G01X-109250Y-75000D02*
X-110650Y-74750D01*
X-111875Y-73750D01*
X-112925Y-72250D01*
X-113625Y-70500D01*
X-113975Y-68500D01*
Y-66500D01*
X-113625Y-64500D01*
X-112925Y-62750D01*
X-111875Y-61250D01*
X-110650Y-60250D01*
X-109250Y-60000D01*
X-107850Y-60250D01*
X-106625Y-61250D01*
X-105575Y-62750D01*
X-104875Y-64500D01*
X-104525Y-66500D01*
Y-68500D01*
X-104875Y-70500D01*
X-105575Y-72250D01*
X-106625Y-73750D01*
X-107850Y-74750D01*
X-109250Y-75000D01*
G01X-98725Y-73000D02*
X-97325Y-74250D01*
X-95750Y-75000D01*
X-94350D01*
X-92950Y-74250D01*
X-91900Y-73000D01*
X-91375Y-71250D01*
X-91725Y-69500D01*
X-92600Y-68000D01*
X-94175Y-67000D01*
X-96275Y-66500D01*
X-97500Y-65500D01*
X-98025Y-63750D01*
X-97675Y-62000D01*
X-96800Y-60750D01*
X-95575Y-60000D01*
X-94350D01*
X-93125Y-60500D01*
X-92075Y-61750D01*
G01X-84350Y-75000D02*
Y-60000D01*
X-80150D01*
X-78750Y-60750D01*
X-77700Y-62500D01*
X-77350Y-64500D01*
X-77700Y-66500D01*
X-78575Y-68000D01*
X-80150Y-68750D01*
X-84350D01*
G01X-52450Y-60000D02*
Y-75000D01*
G01X-56475Y-60000D02*
X-48425D01*
G01X-41925Y-75000D02*
Y-60000D01*
G01X-34575D02*
Y-75000D01*
G01Y-67500D02*
X-41925D01*
G01X-26150Y-60000D02*
X-21950D01*
G01X-24050D02*
Y-75000D01*
G01X-26150D02*
X-21950D01*
G01X-6000Y-61250D02*
X-7050Y-60500D01*
X-8275Y-60000D01*
X-9675D01*
X-11250Y-60750D01*
X-12475Y-62000D01*
X-13350Y-63500D01*
X-14050Y-66000D01*
X-14225Y-68250D01*
X-13875Y-70500D01*
X-13350Y-72000D01*
X-12300Y-73500D01*
X-11075Y-74500D01*
X-9850Y-75000D01*
X-8625D01*
X-7400Y-74500D01*
X-6350Y-73750D01*
X-5475Y-72750D01*
G01X500Y-75000D02*
Y-60000D01*
G01X7150D02*
X500Y-69250D01*
G01X8200Y-75000D02*
X3475Y-65000D01*
G01X14525Y-75000D02*
Y-60000D01*
X22575Y-75000D01*
Y-60000D01*
G01X36250Y-75000D02*
X29250D01*
Y-60000D01*
X36250D01*
G01X33450Y-67250D02*
X29250D01*
G01X43275Y-73000D02*
X44675Y-74250D01*
X46250Y-75000D01*
X47650D01*
X49050Y-74250D01*
X50100Y-73000D01*
X50625Y-71250D01*
X50275Y-69500D01*
X49400Y-68000D01*
X47825Y-67000D01*
X45725Y-66500D01*
X44500Y-65500D01*
X43975Y-63750D01*
X44325Y-62000D01*
X45200Y-60750D01*
X46425Y-60000D01*
X47650D01*
X48875Y-60500D01*
X49925Y-61750D01*
G01X57475Y-73000D02*
X58875Y-74250D01*
X60450Y-75000D01*
X61850D01*
X63250Y-74250D01*
X64300Y-73000D01*
X64825Y-71250D01*
X64475Y-69500D01*
X63600Y-68000D01*
X62025Y-67000D01*
X59925Y-66500D01*
X58700Y-65500D01*
X58175Y-63750D01*
X58525Y-62000D01*
X59400Y-60750D01*
X60625Y-60000D01*
X61850D01*
X63075Y-60500D01*
X64125Y-61750D01*
G01X-276500Y-30000D02*
Y-45000D01*
G01Y-42750D02*
X-277200Y-44000D01*
X-278250Y-44750D01*
X-279475Y-45000D01*
X-280875Y-44500D01*
X-281925Y-43250D01*
X-282625Y-41750D01*
X-282800Y-40000D01*
X-282625Y-38250D01*
X-281925Y-36750D01*
X-280875Y-35500D01*
X-279475Y-35000D01*
X-278250Y-35250D01*
X-277375Y-35750D01*
X-276500Y-36750D01*
G01X-265450Y-45500D02*
X-265800Y-45250D01*
Y-44750D01*
X-265450Y-44500D01*
X-265100Y-44750D01*
Y-45250D01*
X-265450Y-45500D01*
G01X-227400Y-45000D02*
Y-30000D01*
X-222850Y-42500D01*
X-218300Y-30000D01*
Y-45000D01*
G01X-205150D02*
X-212150D01*
Y-30000D01*
X-205150D01*
G01X-207950Y-37250D02*
X-212150D01*
G01X-198825Y-45000D02*
X-194450Y-30000D01*
X-190075Y-45000D01*
G01X-191650Y-39750D02*
X-197250D01*
G01X-183925Y-43000D02*
X-182525Y-44250D01*
X-180950Y-45000D01*
X-179550D01*
X-178150Y-44250D01*
X-177100Y-43000D01*
X-176575Y-41250D01*
X-176925Y-39500D01*
X-177800Y-38000D01*
X-179375Y-37000D01*
X-181475Y-36500D01*
X-182700Y-35500D01*
X-183225Y-33750D01*
X-182875Y-32000D01*
X-182000Y-30750D01*
X-180775Y-30000D01*
X-179550D01*
X-178325Y-30500D01*
X-177275Y-31750D01*
G01X-169900Y-30000D02*
Y-40750D01*
X-169200Y-43000D01*
X-167800Y-44500D01*
X-166050Y-45000D01*
X-164300Y-44500D01*
X-162900Y-43000D01*
X-162200Y-40750D01*
Y-30000D01*
G01X-155350Y-45000D02*
Y-30000D01*
X-150975D01*
X-149575Y-30750D01*
X-148700Y-31750D01*
X-148350Y-33750D01*
X-148700Y-35750D01*
X-149750Y-37000D01*
X-150975Y-37750D01*
X-155350D01*
G01X-150975D02*
X-148350Y-45000D01*
G01X-134150D02*
X-141150D01*
Y-30000D01*
X-134150D01*
G01X-136950Y-37250D02*
X-141150D01*
G01X-113625Y-45000D02*
X-109250Y-30000D01*
X-104875Y-45000D01*
G01X-106450Y-39750D02*
X-112050D01*
G01X-98550Y-30000D02*
Y-45000D01*
X-91550D01*
G01X-84525Y-43000D02*
X-83125Y-44250D01*
X-81550Y-45000D01*
X-80150D01*
X-78750Y-44250D01*
X-77700Y-43000D01*
X-77175Y-41250D01*
X-77525Y-39500D01*
X-78400Y-38000D01*
X-79975Y-37000D01*
X-82075Y-36500D01*
X-83300Y-35500D01*
X-83825Y-33750D01*
X-83475Y-32000D01*
X-82600Y-30750D01*
X-81375Y-30000D01*
X-80150D01*
X-78925Y-30500D01*
X-77875Y-31750D01*
G01X-66650Y-45000D02*
X-68050Y-44750D01*
X-69275Y-43750D01*
X-70325Y-42250D01*
X-71025Y-40500D01*
X-71375Y-38500D01*
Y-36500D01*
X-71025Y-34500D01*
X-70325Y-32750D01*
X-69275Y-31250D01*
X-68050Y-30250D01*
X-66650Y-30000D01*
X-65250Y-30250D01*
X-64025Y-31250D01*
X-62975Y-32750D01*
X-62275Y-34500D01*
X-61925Y-36500D01*
Y-38500D01*
X-62275Y-40500D01*
X-62975Y-42250D01*
X-64025Y-43750D01*
X-65250Y-44750D01*
X-66650Y-45000D01*
G01X-38250Y-30000D02*
Y-45000D01*
G01X-42275Y-30000D02*
X-34225D01*
G01X-27725Y-45000D02*
Y-30000D01*
G01X-20375D02*
Y-45000D01*
G01Y-37500D02*
X-27725D01*
G01X-6350Y-45000D02*
X-13350D01*
Y-30000D01*
X-6350D01*
G01X-9150Y-37250D02*
X-13350D01*
G01X15225Y-45000D02*
Y-30000D01*
X21875D01*
G01X19425Y-37250D02*
X15225D01*
G01X32750Y-45000D02*
X31350Y-44750D01*
X30125Y-43750D01*
X29075Y-42250D01*
X28375Y-40500D01*
X28025Y-38500D01*
Y-36500D01*
X28375Y-34500D01*
X29075Y-32750D01*
X30125Y-31250D01*
X31350Y-30250D01*
X32750Y-30000D01*
X34150Y-30250D01*
X35375Y-31250D01*
X36425Y-32750D01*
X37125Y-34500D01*
X37475Y-36500D01*
Y-38500D01*
X37125Y-40500D01*
X36425Y-42250D01*
X35375Y-43750D01*
X34150Y-44750D01*
X32750Y-45000D01*
G01X43450Y-30000D02*
Y-45000D01*
X50450D01*
G01X57650Y-30000D02*
Y-45000D01*
X64650D01*
G01X75350D02*
X73950Y-44750D01*
X72725Y-43750D01*
X71675Y-42250D01*
X70975Y-40500D01*
X70625Y-38500D01*
Y-36500D01*
X70975Y-34500D01*
X71675Y-32750D01*
X72725Y-31250D01*
X73950Y-30250D01*
X75350Y-30000D01*
X76750Y-30250D01*
X77975Y-31250D01*
X79025Y-32750D01*
X79725Y-34500D01*
X80075Y-36500D01*
Y-38500D01*
X79725Y-40500D01*
X79025Y-42250D01*
X77975Y-43750D01*
X76750Y-44750D01*
X75350Y-45000D01*
G01X84300Y-30000D02*
X86750Y-45000D01*
X89550Y-30000D01*
X92350Y-45000D01*
X94800Y-30000D01*
G01X101650D02*
X105850D01*
G01X103750D02*
Y-45000D01*
G01X101650D02*
X105850D01*
G01X113925D02*
Y-30000D01*
X121975Y-45000D01*
Y-30000D01*
G01X133200Y-37500D02*
X136700D01*
Y-42000D01*
X135650Y-43500D01*
X134425Y-44500D01*
X132675Y-45000D01*
X130925Y-44500D01*
X129700Y-43500D01*
X128650Y-42000D01*
X127950Y-40250D01*
X127600Y-38250D01*
Y-36500D01*
X127950Y-35000D01*
X128650Y-33250D01*
X129700Y-31750D01*
X130750Y-30750D01*
X132150Y-30000D01*
X133375D01*
X134775Y-30500D01*
X135825Y-31500D01*
G01X158450Y-30000D02*
X162650D01*
G01X160550D02*
Y-45000D01*
G01X158450D02*
X162650D01*
G01X174750Y-30000D02*
Y-45000D01*
G01X170725Y-30000D02*
X178775D01*
G01X192450Y-45000D02*
X185450D01*
Y-30000D01*
X192450D01*
G01X189650Y-37250D02*
X185450D01*
G01X198600Y-45000D02*
Y-30000D01*
X203150Y-42500D01*
X207700Y-30000D01*
Y-45000D01*
G01X213675Y-43000D02*
X215075Y-44250D01*
X216650Y-45000D01*
X218050D01*
X219450Y-44250D01*
X220500Y-43000D01*
X221025Y-41250D01*
X220675Y-39500D01*
X219800Y-38000D01*
X218225Y-37000D01*
X216125Y-36500D01*
X214900Y-35500D01*
X214375Y-33750D01*
X214725Y-32000D01*
X215600Y-30750D01*
X216825Y-30000D01*
X218050D01*
X219275Y-30500D01*
X220325Y-31750D01*
G01X242425Y-45000D02*
Y-30000D01*
X249075D01*
G01X246625Y-37250D02*
X242425D01*
G01X256450Y-45000D02*
Y-30000D01*
X260825D01*
X262225Y-30750D01*
X263100Y-31750D01*
X263450Y-33750D01*
X263100Y-35750D01*
X262050Y-37000D01*
X260825Y-37750D01*
X256450D01*
G01X260825D02*
X263450Y-45000D01*
G01X274150D02*
X272750Y-44750D01*
X271525Y-43750D01*
X270475Y-42250D01*
X269775Y-40500D01*
X269425Y-38500D01*
Y-36500D01*
X269775Y-34500D01*
X270475Y-32750D01*
X271525Y-31250D01*
X272750Y-30250D01*
X274150Y-30000D01*
X275550Y-30250D01*
X276775Y-31250D01*
X277825Y-32750D01*
X278525Y-34500D01*
X278875Y-36500D01*
Y-38500D01*
X278525Y-40500D01*
X277825Y-42250D01*
X276775Y-43750D01*
X275550Y-44750D01*
X274150Y-45000D01*
G01X283800D02*
Y-30000D01*
X288350Y-42500D01*
X292900Y-30000D01*
Y-45000D01*
G01X316750D02*
X315350Y-44750D01*
X314125Y-43750D01*
X313075Y-42250D01*
X312375Y-40500D01*
X312025Y-38500D01*
Y-36500D01*
X312375Y-34500D01*
X313075Y-32750D01*
X314125Y-31250D01*
X315350Y-30250D01*
X316750Y-30000D01*
X318150Y-30250D01*
X319375Y-31250D01*
X320425Y-32750D01*
X321125Y-34500D01*
X321475Y-36500D01*
Y-38500D01*
X321125Y-40500D01*
X320425Y-42250D01*
X319375Y-43750D01*
X318150Y-44750D01*
X316750Y-45000D01*
G01X326925D02*
Y-30000D01*
X334975Y-45000D01*
Y-30000D01*
G01X348650Y-45000D02*
X341650D01*
Y-30000D01*
X348650D01*
G01X345850Y-37250D02*
X341650D01*
G01X374950Y-37000D02*
X375650Y-36250D01*
X376175Y-35000D01*
X376525Y-33250D01*
X376175Y-31750D01*
X375475Y-30750D01*
X374250Y-30000D01*
X369525D01*
Y-45000D01*
X375300D01*
X376525Y-44000D01*
X377225Y-42500D01*
X377575Y-40750D01*
X377225Y-39000D01*
X376175Y-37500D01*
X374950Y-37000D01*
X369525D01*
G01X387750Y-45000D02*
X386350Y-44750D01*
X385125Y-43750D01*
X384075Y-42250D01*
X383375Y-40500D01*
X383025Y-38500D01*
Y-36500D01*
X383375Y-34500D01*
X384075Y-32750D01*
X385125Y-31250D01*
X386350Y-30250D01*
X387750Y-30000D01*
X389150Y-30250D01*
X390375Y-31250D01*
X391425Y-32750D01*
X392125Y-34500D01*
X392475Y-36500D01*
Y-38500D01*
X392125Y-40500D01*
X391425Y-42250D01*
X390375Y-43750D01*
X389150Y-44750D01*
X387750Y-45000D01*
G01X397575D02*
X401950Y-30000D01*
X406325Y-45000D01*
G01X404750Y-39750D02*
X399150D01*
G01X412650Y-45000D02*
Y-30000D01*
X417025D01*
X418425Y-30750D01*
X419300Y-31750D01*
X419650Y-33750D01*
X419300Y-35750D01*
X418250Y-37000D01*
X417025Y-37750D01*
X412650D01*
G01X417025D02*
X419650Y-45000D01*
G01X426500D02*
Y-30000D01*
X430000D01*
X431400Y-30750D01*
X432450Y-31750D01*
X433325Y-33250D01*
X434025Y-35000D01*
X434200Y-37500D01*
X434025Y-40000D01*
X433325Y-41750D01*
X432450Y-43250D01*
X431400Y-44250D01*
X430000Y-45000D01*
X426500D01*
G01X444550Y-45500D02*
X444200Y-45250D01*
Y-44750D01*
X444550Y-44500D01*
X444900Y-44750D01*
Y-45250D01*
X444550Y-45500D01*
G01Y-38750D02*
X444200Y-38500D01*
Y-38000D01*
X444550Y-37750D01*
X444900Y-38000D01*
Y-38500D01*
X444550Y-38750D01*
G01X-228100Y0D02*
X-225650Y-15000D01*
X-222850Y0D01*
X-220050Y-15000D01*
X-217600Y0D01*
G01X-210750D02*
X-206550D01*
G01X-208650D02*
Y-15000D01*
G01X-210750D02*
X-206550D01*
G01X-198300D02*
Y0D01*
X-194800D01*
X-193400Y-750D01*
X-192350Y-1750D01*
X-191475Y-3250D01*
X-190775Y-5000D01*
X-190600Y-7500D01*
X-190775Y-10000D01*
X-191475Y-11750D01*
X-192350Y-13250D01*
X-193400Y-14250D01*
X-194800Y-15000D01*
X-198300D01*
G01X-180250Y0D02*
Y-15000D01*
G01X-184275Y0D02*
X-176225D01*
G01X-169725Y-15000D02*
Y0D01*
G01X-162375D02*
Y-15000D01*
G01Y-7500D02*
X-169725D01*
G01X-152200Y-17750D02*
X-151500Y-14500D01*
G01X-122050Y-7000D02*
X-121350Y-6250D01*
X-120825Y-5000D01*
X-120475Y-3250D01*
X-120825Y-1750D01*
X-121525Y-750D01*
X-122750Y0D01*
X-127475D01*
Y-15000D01*
X-121700D01*
X-120475Y-14000D01*
X-119775Y-12500D01*
X-119425Y-10750D01*
X-119775Y-9000D01*
X-120825Y-7500D01*
X-122050Y-7000D01*
X-127475D01*
G01X-113625Y-15000D02*
X-109250Y0D01*
X-104875Y-15000D01*
G01X-106450Y-9750D02*
X-112050D01*
G01X-99075Y-15000D02*
Y0D01*
X-91025Y-15000D01*
Y0D01*
G01X-84700Y-15000D02*
Y0D01*
X-81200D01*
X-79800Y-750D01*
X-78750Y-1750D01*
X-77875Y-3250D01*
X-77175Y-5000D01*
X-77000Y-7500D01*
X-77175Y-10000D01*
X-77875Y-11750D01*
X-78750Y-13250D01*
X-79800Y-14250D01*
X-81200Y-15000D01*
X-84700D01*
G01X-71900Y0D02*
X-69450Y-15000D01*
X-66650Y0D01*
X-63850Y-15000D01*
X-61400Y0D01*
G01X-54550D02*
X-50350D01*
G01X-52450D02*
Y-15000D01*
G01X-54550D02*
X-50350D01*
G01X-42100D02*
Y0D01*
X-38600D01*
X-37200Y-750D01*
X-36150Y-1750D01*
X-35275Y-3250D01*
X-34575Y-5000D01*
X-34400Y-7500D01*
X-34575Y-10000D01*
X-35275Y-11750D01*
X-36150Y-13250D01*
X-37200Y-14250D01*
X-38600Y-15000D01*
X-42100D01*
G01X-24050Y0D02*
Y-15000D01*
G01X-28075Y0D02*
X-20025D01*
G01X-13525Y-15000D02*
Y0D01*
G01X-6175D02*
Y-15000D01*
G01Y-7500D02*
X-13525D01*
G01X14175Y-15000D02*
X18550Y0D01*
X22925Y-15000D01*
G01X21350Y-9750D02*
X15750D01*
G01X28725Y-15000D02*
Y0D01*
X36775Y-15000D01*
Y0D01*
G01X43100Y-15000D02*
Y0D01*
X46600D01*
X48000Y-750D01*
X49050Y-1750D01*
X49925Y-3250D01*
X50625Y-5000D01*
X50800Y-7500D01*
X50625Y-10000D01*
X49925Y-11750D01*
X49050Y-13250D01*
X48000Y-14250D01*
X46600Y-15000D01*
X43100D01*
G01X75350Y0D02*
Y-15000D01*
G01X71325Y0D02*
X79375D01*
G01X85875Y-15000D02*
Y0D01*
G01X93225D02*
Y-15000D01*
G01Y-7500D02*
X85875D01*
G01X101650Y0D02*
X105850D01*
G01X103750D02*
Y-15000D01*
G01X101650D02*
X105850D01*
G01X121800Y-1250D02*
X120750Y-500D01*
X119525Y0D01*
X118125D01*
X116550Y-750D01*
X115325Y-2000D01*
X114450Y-3500D01*
X113750Y-6000D01*
X113575Y-8250D01*
X113925Y-10500D01*
X114450Y-12000D01*
X115500Y-13500D01*
X116725Y-14500D01*
X117950Y-15000D01*
X119175D01*
X120400Y-14500D01*
X121450Y-13750D01*
X122325Y-12750D01*
G01X128300Y-15000D02*
Y0D01*
G01X134950D02*
X128300Y-9250D01*
G01X136000Y-15000D02*
X131275Y-5000D01*
G01X142325Y-15000D02*
Y0D01*
X150375Y-15000D01*
Y0D01*
G01X164050Y-15000D02*
X157050D01*
Y0D01*
X164050D01*
G01X161250Y-7250D02*
X157050D01*
G01X171075Y-13000D02*
X172475Y-14250D01*
X174050Y-15000D01*
X175450D01*
X176850Y-14250D01*
X177900Y-13000D01*
X178425Y-11250D01*
X178075Y-9500D01*
X177200Y-8000D01*
X175625Y-7000D01*
X173525Y-6500D01*
X172300Y-5500D01*
X171775Y-3750D01*
X172125Y-2000D01*
X173000Y-750D01*
X174225Y0D01*
X175450D01*
X176675Y-500D01*
X177725Y-1750D01*
G01X185275Y-13000D02*
X186675Y-14250D01*
X188250Y-15000D01*
X189650D01*
X191050Y-14250D01*
X192100Y-13000D01*
X192625Y-11250D01*
X192275Y-9500D01*
X191400Y-8000D01*
X189825Y-7000D01*
X187725Y-6500D01*
X186500Y-5500D01*
X185975Y-3750D01*
X186325Y-2000D01*
X187200Y-750D01*
X188425Y0D01*
X189650D01*
X190875Y-500D01*
X191925Y-1750D01*
G01X204025Y-20000D02*
X205775Y-17500D01*
X206650Y-15000D01*
Y-5000D01*
X205775Y-2500D01*
X204025Y0D01*
G01X217000Y-17750D02*
X217700Y-14500D01*
G01X241375Y-15000D02*
X245750Y0D01*
X250125Y-15000D01*
G01X248550Y-9750D02*
X242950D01*
G01X255925Y-15000D02*
Y0D01*
X263975Y-15000D01*
Y0D01*
G01X270300Y-15000D02*
Y0D01*
X273800D01*
X275200Y-750D01*
X276250Y-1750D01*
X277125Y-3250D01*
X277825Y-5000D01*
X278000Y-7500D01*
X277825Y-10000D01*
X277125Y-11750D01*
X276250Y-13250D01*
X275200Y-14250D01*
X273800Y-15000D01*
X270300D01*
G01X303950Y-7000D02*
X304650Y-6250D01*
X305175Y-5000D01*
X305525Y-3250D01*
X305175Y-1750D01*
X304475Y-750D01*
X303250Y0D01*
X298525D01*
Y-15000D01*
X304300D01*
X305525Y-14000D01*
X306225Y-12500D01*
X306575Y-10750D01*
X306225Y-9000D01*
X305175Y-7500D01*
X303950Y-7000D01*
X298525D01*
G01X316750Y-15000D02*
X315350Y-14750D01*
X314125Y-13750D01*
X313075Y-12250D01*
X312375Y-10500D01*
X312025Y-8500D01*
Y-6500D01*
X312375Y-4500D01*
X313075Y-2750D01*
X314125Y-1250D01*
X315350Y-250D01*
X316750Y0D01*
X318150Y-250D01*
X319375Y-1250D01*
X320425Y-2750D01*
X321125Y-4500D01*
X321475Y-6500D01*
Y-8500D01*
X321125Y-10500D01*
X320425Y-12250D01*
X319375Y-13750D01*
X318150Y-14750D01*
X316750Y-15000D01*
G01X326575D02*
X330950Y0D01*
X335325Y-15000D01*
G01X333750Y-9750D02*
X328150D01*
G01X341650Y-15000D02*
Y0D01*
X346025D01*
X347425Y-750D01*
X348300Y-1750D01*
X348650Y-3750D01*
X348300Y-5750D01*
X347250Y-7000D01*
X346025Y-7750D01*
X341650D01*
G01X346025D02*
X348650Y-15000D01*
G01X355500D02*
Y0D01*
X359000D01*
X360400Y-750D01*
X361450Y-1750D01*
X362325Y-3250D01*
X363025Y-5000D01*
X363200Y-7500D01*
X363025Y-10000D01*
X362325Y-11750D01*
X361450Y-13250D01*
X360400Y-14250D01*
X359000Y-15000D01*
X355500D01*
G01X387750Y0D02*
Y-15000D01*
G01X383725Y0D02*
X391775D01*
G01X398275Y-15000D02*
Y0D01*
G01X405625D02*
Y-15000D01*
G01Y-7500D02*
X398275D01*
G01X414050Y0D02*
X418250D01*
G01X416150D02*
Y-15000D01*
G01X414050D02*
X418250D01*
G01X434200Y-1250D02*
X433150Y-500D01*
X431925Y0D01*
X430525D01*
X428950Y-750D01*
X427725Y-2000D01*
X426850Y-3500D01*
X426150Y-6000D01*
X425975Y-8250D01*
X426325Y-10500D01*
X426850Y-12000D01*
X427900Y-13500D01*
X429125Y-14500D01*
X430350Y-15000D01*
X431575D01*
X432800Y-14500D01*
X433850Y-13750D01*
X434725Y-12750D01*
G01X440700Y-15000D02*
Y0D01*
G01X447350D02*
X440700Y-9250D01*
G01X448400Y-15000D02*
X443675Y-5000D01*
G01X454725Y-15000D02*
Y0D01*
X462775Y-15000D01*
Y0D01*
G01X476450Y-15000D02*
X469450D01*
Y0D01*
X476450D01*
G01X473650Y-7250D02*
X469450D01*
G01X483475Y-13000D02*
X484875Y-14250D01*
X486450Y-15000D01*
X487850D01*
X489250Y-14250D01*
X490300Y-13000D01*
X490825Y-11250D01*
X490475Y-9500D01*
X489600Y-8000D01*
X488025Y-7000D01*
X485925Y-6500D01*
X484700Y-5500D01*
X484175Y-3750D01*
X484525Y-2000D01*
X485400Y-750D01*
X486625Y0D01*
X487850D01*
X489075Y-500D01*
X490125Y-1750D01*
G01X497675Y-13000D02*
X499075Y-14250D01*
X500650Y-15000D01*
X502050D01*
X503450Y-14250D01*
X504500Y-13000D01*
X505025Y-11250D01*
X504675Y-9500D01*
X503800Y-8000D01*
X502225Y-7000D01*
X500125Y-6500D01*
X498900Y-5500D01*
X498375Y-3750D01*
X498725Y-2000D01*
X499600Y-750D01*
X500825Y0D01*
X502050D01*
X503275Y-500D01*
X504325Y-1750D01*
G01X528875Y-20000D02*
X527125Y-17500D01*
X526250Y-15000D01*
Y-5000D01*
X527125Y-2500D01*
X528875Y0D01*
G01X538700D02*
X541150Y-15000D01*
X543950Y0D01*
X546750Y-15000D01*
X549200Y0D01*
G01X556050D02*
X560250D01*
G01X558150D02*
Y-15000D01*
G01X556050D02*
X560250D01*
G01X572350Y0D02*
Y-15000D01*
G01X568325Y0D02*
X576375D01*
G01X582875Y-15000D02*
Y0D01*
G01X590225D02*
Y-15000D01*
G01Y-7500D02*
X582875D01*
G01X600750Y-15000D02*
X599350Y-14750D01*
X598125Y-13750D01*
X597075Y-12250D01*
X596375Y-10500D01*
X596025Y-8500D01*
Y-6500D01*
X596375Y-4500D01*
X597075Y-2750D01*
X598125Y-1250D01*
X599350Y-250D01*
X600750Y0D01*
X602150Y-250D01*
X603375Y-1250D01*
X604425Y-2750D01*
X605125Y-4500D01*
X605475Y-6500D01*
Y-8500D01*
X605125Y-10500D01*
X604425Y-12250D01*
X603375Y-13750D01*
X602150Y-14750D01*
X600750Y-15000D01*
G01X611100Y0D02*
Y-10750D01*
X611800Y-13000D01*
X613200Y-14500D01*
X614950Y-15000D01*
X616700Y-14500D01*
X618100Y-13000D01*
X618800Y-10750D01*
Y0D01*
G01X629150D02*
Y-15000D01*
G01X625125Y0D02*
X633175D01*
G01X653875Y-13000D02*
X655275Y-14250D01*
X656850Y-15000D01*
X658250D01*
X659650Y-14250D01*
X660700Y-13000D01*
X661225Y-11250D01*
X660875Y-9500D01*
X660000Y-8000D01*
X658425Y-7000D01*
X656325Y-6500D01*
X655100Y-5500D01*
X654575Y-3750D01*
X654925Y-2000D01*
X655800Y-750D01*
X657025Y0D01*
X658250D01*
X659475Y-500D01*
X660525Y-1750D01*
G01X671750Y-15000D02*
X670350Y-14750D01*
X669125Y-13750D01*
X668075Y-12250D01*
X667375Y-10500D01*
X667025Y-8500D01*
Y-6500D01*
X667375Y-4500D01*
X668075Y-2750D01*
X669125Y-1250D01*
X670350Y-250D01*
X671750Y0D01*
X673150Y-250D01*
X674375Y-1250D01*
X675425Y-2750D01*
X676125Y-4500D01*
X676475Y-6500D01*
Y-8500D01*
X676125Y-10500D01*
X675425Y-12250D01*
X674375Y-13750D01*
X673150Y-14750D01*
X671750Y-15000D01*
G01X682450Y0D02*
Y-15000D01*
X689450D01*
G01X696300D02*
Y0D01*
X699800D01*
X701200Y-750D01*
X702250Y-1750D01*
X703125Y-3250D01*
X703825Y-5000D01*
X704000Y-7500D01*
X703825Y-10000D01*
X703125Y-11750D01*
X702250Y-13250D01*
X701200Y-14250D01*
X699800Y-15000D01*
X696300D01*
G01X717850D02*
X710850D01*
Y0D01*
X717850D01*
G01X715050Y-7250D02*
X710850D01*
G01X725050Y-15000D02*
Y0D01*
X729425D01*
X730825Y-750D01*
X731700Y-1750D01*
X732050Y-3750D01*
X731700Y-5750D01*
X730650Y-7000D01*
X729425Y-7750D01*
X725050D01*
G01X729425D02*
X732050Y-15000D01*
G01X738200D02*
Y0D01*
X742750Y-12500D01*
X747300Y0D01*
Y-15000D01*
G01X752575D02*
X756950Y0D01*
X761325Y-15000D01*
G01X759750Y-9750D02*
X754150D01*
G01X767475Y-13000D02*
X768875Y-14250D01*
X770450Y-15000D01*
X771850D01*
X773250Y-14250D01*
X774300Y-13000D01*
X774825Y-11250D01*
X774475Y-9500D01*
X773600Y-8000D01*
X772025Y-7000D01*
X769925Y-6500D01*
X768700Y-5500D01*
X768175Y-3750D01*
X768525Y-2000D01*
X769400Y-750D01*
X770625Y0D01*
X771850D01*
X773075Y-500D01*
X774125Y-1750D01*
G01X781500Y-15000D02*
Y0D01*
G01X788150D02*
X781500Y-9250D01*
G01X789200Y-15000D02*
X784475Y-5000D01*
G01X800425Y-20000D02*
X802175Y-17500D01*
X803050Y-15000D01*
Y-5000D01*
X802175Y-2500D01*
X800425Y0D01*
G01X813750Y-15500D02*
X813400Y-15250D01*
Y-14750D01*
X813750Y-14500D01*
X814100Y-14750D01*
Y-15250D01*
X813750Y-15500D01*
G01X-221450Y23000D02*
X-220750Y23750D01*
X-220225Y25000D01*
X-219875Y26750D01*
X-220225Y28250D01*
X-220925Y29250D01*
X-222150Y30000D01*
X-226875D01*
Y15000D01*
X-221100D01*
X-219875Y16000D01*
X-219175Y17500D01*
X-218825Y19250D01*
X-219175Y21000D01*
X-220225Y22500D01*
X-221450Y23000D01*
X-226875D01*
G01X-208650Y15000D02*
X-210050Y15250D01*
X-211275Y16250D01*
X-212325Y17750D01*
X-213025Y19500D01*
X-213375Y21500D01*
Y23500D01*
X-213025Y25500D01*
X-212325Y27250D01*
X-211275Y28750D01*
X-210050Y29750D01*
X-208650Y30000D01*
X-207250Y29750D01*
X-206025Y28750D01*
X-204975Y27250D01*
X-204275Y25500D01*
X-203925Y23500D01*
Y21500D01*
X-204275Y19500D01*
X-204975Y17750D01*
X-206025Y16250D01*
X-207250Y15250D01*
X-208650Y15000D01*
G01X-194450Y30000D02*
Y15000D01*
G01X-198475Y30000D02*
X-190425D01*
G01X-180250D02*
Y15000D01*
G01X-184275Y30000D02*
X-176225D01*
G01X-166050Y15000D02*
X-167450Y15250D01*
X-168675Y16250D01*
X-169725Y17750D01*
X-170425Y19500D01*
X-170775Y21500D01*
Y23500D01*
X-170425Y25500D01*
X-169725Y27250D01*
X-168675Y28750D01*
X-167450Y29750D01*
X-166050Y30000D01*
X-164650Y29750D01*
X-163425Y28750D01*
X-162375Y27250D01*
X-161675Y25500D01*
X-161325Y23500D01*
Y21500D01*
X-161675Y19500D01*
X-162375Y17750D01*
X-163425Y16250D01*
X-164650Y15250D01*
X-166050Y15000D01*
G01X-156400D02*
Y30000D01*
X-151850Y17500D01*
X-147300Y30000D01*
Y15000D01*
G01X-141325Y17000D02*
X-139925Y15750D01*
X-138350Y15000D01*
X-136950D01*
X-135550Y15750D01*
X-134500Y17000D01*
X-133975Y18750D01*
X-134325Y20500D01*
X-135200Y22000D01*
X-136775Y23000D01*
X-138875Y23500D01*
X-140100Y24500D01*
X-140625Y26250D01*
X-140275Y28000D01*
X-139400Y29250D01*
X-138175Y30000D01*
X-136950D01*
X-135725Y29500D01*
X-134675Y28250D01*
G01X-122575Y10000D02*
X-120825Y12500D01*
X-119950Y15000D01*
Y25000D01*
X-120825Y27500D01*
X-122575Y30000D01*
G01X-109600Y12250D02*
X-108900Y15500D01*
G01X-84700Y15000D02*
Y30000D01*
X-81200D01*
X-79800Y29250D01*
X-78750Y28250D01*
X-77875Y26750D01*
X-77175Y25000D01*
X-77000Y22500D01*
X-77175Y20000D01*
X-77875Y18250D01*
X-78750Y16750D01*
X-79800Y15750D01*
X-81200Y15000D01*
X-84700D01*
G01X-68750Y30000D02*
X-64550D01*
G01X-66650D02*
Y15000D01*
G01X-68750D02*
X-64550D01*
G01X-48950D02*
X-55950D01*
Y30000D01*
X-48950D01*
G01X-51750Y22750D02*
X-55950D01*
G01X-41750Y30000D02*
Y15000D01*
X-34750D01*
G01X-20550D02*
X-27550D01*
Y30000D01*
X-20550D01*
G01X-23350Y22750D02*
X-27550D01*
G01X-6000Y28750D02*
X-7050Y29500D01*
X-8275Y30000D01*
X-9675D01*
X-11250Y29250D01*
X-12475Y28000D01*
X-13350Y26500D01*
X-14050Y24000D01*
X-14225Y21750D01*
X-13875Y19500D01*
X-13350Y18000D01*
X-12300Y16500D01*
X-11075Y15500D01*
X-9850Y15000D01*
X-8625D01*
X-7400Y15500D01*
X-6350Y16250D01*
X-5475Y17250D01*
G01X4350Y30000D02*
Y15000D01*
G01X325Y30000D02*
X8375D01*
G01X15050Y15000D02*
Y30000D01*
X19425D01*
X20825Y29250D01*
X21700Y28250D01*
X22050Y26250D01*
X21700Y24250D01*
X20650Y23000D01*
X19425Y22250D01*
X15050D01*
G01X19425D02*
X22050Y15000D01*
G01X30650Y30000D02*
X34850D01*
G01X32750D02*
Y15000D01*
G01X30650D02*
X34850D01*
G01X50800Y28750D02*
X49750Y29500D01*
X48525Y30000D01*
X47125D01*
X45550Y29250D01*
X44325Y28000D01*
X43450Y26500D01*
X42750Y24000D01*
X42575Y21750D01*
X42925Y19500D01*
X43450Y18000D01*
X44500Y16500D01*
X45725Y15500D01*
X46950Y15000D01*
X48175D01*
X49400Y15500D01*
X50450Y16250D01*
X51325Y17250D01*
G01X75350Y30000D02*
Y15000D01*
G01X71325Y30000D02*
X79375D01*
G01X85875Y15000D02*
Y30000D01*
G01X93225D02*
Y15000D01*
G01Y22500D02*
X85875D01*
G01X101650Y30000D02*
X105850D01*
G01X103750D02*
Y15000D01*
G01X101650D02*
X105850D01*
G01X121800Y28750D02*
X120750Y29500D01*
X119525Y30000D01*
X118125D01*
X116550Y29250D01*
X115325Y28000D01*
X114450Y26500D01*
X113750Y24000D01*
X113575Y21750D01*
X113925Y19500D01*
X114450Y18000D01*
X115500Y16500D01*
X116725Y15500D01*
X117950Y15000D01*
X119175D01*
X120400Y15500D01*
X121450Y16250D01*
X122325Y17250D01*
G01X128300Y15000D02*
Y30000D01*
G01X134950D02*
X128300Y20750D01*
G01X136000Y15000D02*
X131275Y25000D01*
G01X142325Y15000D02*
Y30000D01*
X150375Y15000D01*
Y30000D01*
G01X164050Y15000D02*
X157050D01*
Y30000D01*
X164050D01*
G01X161250Y22750D02*
X157050D01*
G01X171075Y17000D02*
X172475Y15750D01*
X174050Y15000D01*
X175450D01*
X176850Y15750D01*
X177900Y17000D01*
X178425Y18750D01*
X178075Y20500D01*
X177200Y22000D01*
X175625Y23000D01*
X173525Y23500D01*
X172300Y24500D01*
X171775Y26250D01*
X172125Y28000D01*
X173000Y29250D01*
X174225Y30000D01*
X175450D01*
X176675Y29500D01*
X177725Y28250D01*
G01X185275Y17000D02*
X186675Y15750D01*
X188250Y15000D01*
X189650D01*
X191050Y15750D01*
X192100Y17000D01*
X192625Y18750D01*
X192275Y20500D01*
X191400Y22000D01*
X189825Y23000D01*
X187725Y23500D01*
X186500Y24500D01*
X185975Y26250D01*
X186325Y28000D01*
X187200Y29250D01*
X188425Y30000D01*
X189650D01*
X190875Y29500D01*
X191925Y28250D01*
G01X216475Y10000D02*
X214725Y12500D01*
X213850Y15000D01*
Y25000D01*
X214725Y27500D01*
X216475Y30000D01*
G01X235400Y28750D02*
X234350Y29500D01*
X233125Y30000D01*
X231725D01*
X230150Y29250D01*
X228925Y28000D01*
X228050Y26500D01*
X227350Y24000D01*
X227175Y21750D01*
X227525Y19500D01*
X228050Y18000D01*
X229100Y16500D01*
X230325Y15500D01*
X231550Y15000D01*
X232775D01*
X234000Y15500D01*
X235050Y16250D01*
X235925Y17250D01*
G01X249250Y15000D02*
X242250D01*
Y30000D01*
X249250D01*
G01X246450Y22750D02*
X242250D01*
G01X255925Y15000D02*
Y30000D01*
X263975Y15000D01*
Y30000D01*
G01X274150D02*
Y15000D01*
G01X270125Y30000D02*
X278175D01*
G01X291850Y15000D02*
X284850D01*
Y30000D01*
X291850D01*
G01X289050Y22750D02*
X284850D01*
G01X299050Y15000D02*
Y30000D01*
X303425D01*
X304825Y29250D01*
X305700Y28250D01*
X306050Y26250D01*
X305700Y24250D01*
X304650Y23000D01*
X303425Y22250D01*
X299050D01*
G01X303425D02*
X306050Y15000D01*
G01X326575D02*
X330950Y30000D01*
X335325Y15000D01*
G01X333750Y20250D02*
X328150D01*
G01X341125Y15000D02*
Y30000D01*
X349175Y15000D01*
Y30000D01*
G01X355500Y15000D02*
Y30000D01*
X359000D01*
X360400Y29250D01*
X361450Y28250D01*
X362325Y26750D01*
X363025Y25000D01*
X363200Y22500D01*
X363025Y20000D01*
X362325Y18250D01*
X361450Y16750D01*
X360400Y15750D01*
X359000Y15000D01*
X355500D01*
G01X391600Y28750D02*
X390550Y29500D01*
X389325Y30000D01*
X387925D01*
X386350Y29250D01*
X385125Y28000D01*
X384250Y26500D01*
X383550Y24000D01*
X383375Y21750D01*
X383725Y19500D01*
X384250Y18000D01*
X385300Y16500D01*
X386525Y15500D01*
X387750Y15000D01*
X388975D01*
X390200Y15500D01*
X391250Y16250D01*
X392125Y17250D01*
G01X401950Y15000D02*
X400550Y15250D01*
X399325Y16250D01*
X398275Y17750D01*
X397575Y19500D01*
X397225Y21500D01*
Y23500D01*
X397575Y25500D01*
X398275Y27250D01*
X399325Y28750D01*
X400550Y29750D01*
X401950Y30000D01*
X403350Y29750D01*
X404575Y28750D01*
X405625Y27250D01*
X406325Y25500D01*
X406675Y23500D01*
Y21500D01*
X406325Y19500D01*
X405625Y17750D01*
X404575Y16250D01*
X403350Y15250D01*
X401950Y15000D01*
G01X412650D02*
Y30000D01*
X417025D01*
X418425Y29250D01*
X419300Y28250D01*
X419650Y26250D01*
X419300Y24250D01*
X418250Y23000D01*
X417025Y22250D01*
X412650D01*
G01X417025D02*
X419650Y15000D01*
G01X426325D02*
Y30000D01*
X434375Y15000D01*
Y30000D01*
G01X448050Y15000D02*
X441050D01*
Y30000D01*
X448050D01*
G01X445250Y22750D02*
X441050D01*
G01X455250Y15000D02*
Y30000D01*
X459625D01*
X461025Y29250D01*
X461900Y28250D01*
X462250Y26250D01*
X461900Y24250D01*
X460850Y23000D01*
X459625Y22250D01*
X455250D01*
G01X459625D02*
X462250Y15000D01*
G01X473825Y10000D02*
X475575Y12500D01*
X476450Y15000D01*
Y25000D01*
X475575Y27500D01*
X473825Y30000D01*
G01X486800Y12250D02*
X487500Y15500D01*
G01X515550Y30000D02*
Y15000D01*
G01X511525Y30000D02*
X519575D01*
G01X526250Y15000D02*
Y30000D01*
X530625D01*
X532025Y29250D01*
X532900Y28250D01*
X533250Y26250D01*
X532900Y24250D01*
X531850Y23000D01*
X530625Y22250D01*
X526250D01*
G01X530625D02*
X533250Y15000D01*
G01X539575D02*
X543950Y30000D01*
X548325Y15000D01*
G01X546750Y20250D02*
X541150D01*
G01X562000Y28750D02*
X560950Y29500D01*
X559725Y30000D01*
X558325D01*
X556750Y29250D01*
X555525Y28000D01*
X554650Y26500D01*
X553950Y24000D01*
X553775Y21750D01*
X554125Y19500D01*
X554650Y18000D01*
X555700Y16500D01*
X556925Y15500D01*
X558150Y15000D01*
X559375D01*
X560600Y15500D01*
X561650Y16250D01*
X562525Y17250D01*
G01X575850Y15000D02*
X568850D01*
Y30000D01*
X575850D01*
G01X573050Y22750D02*
X568850D01*
G01X597250Y15000D02*
Y30000D01*
X601450D01*
X602850Y29250D01*
X603900Y27500D01*
X604250Y25500D01*
X603900Y23500D01*
X603025Y22000D01*
X601450Y21250D01*
X597250D01*
G01X611450Y15000D02*
Y30000D01*
X615825D01*
X617225Y29250D01*
X618100Y28250D01*
X618450Y26250D01*
X618100Y24250D01*
X617050Y23000D01*
X615825Y22250D01*
X611450D01*
G01X615825D02*
X618450Y15000D01*
G01X629150D02*
X627750Y15250D01*
X626525Y16250D01*
X625475Y17750D01*
X624775Y19500D01*
X624425Y21500D01*
Y23500D01*
X624775Y25500D01*
X625475Y27250D01*
X626525Y28750D01*
X627750Y29750D01*
X629150Y30000D01*
X630550Y29750D01*
X631775Y28750D01*
X632825Y27250D01*
X633525Y25500D01*
X633875Y23500D01*
Y21500D01*
X633525Y19500D01*
X632825Y17750D01*
X631775Y16250D01*
X630550Y15250D01*
X629150Y15000D01*
G01X639850D02*
Y30000D01*
X644050D01*
X645450Y29250D01*
X646500Y27500D01*
X646850Y25500D01*
X646500Y23500D01*
X645625Y22000D01*
X644050Y21250D01*
X639850D01*
G01X657550Y15000D02*
X656150Y15250D01*
X654925Y16250D01*
X653875Y17750D01*
X653175Y19500D01*
X652825Y21500D01*
Y23500D01*
X653175Y25500D01*
X653875Y27250D01*
X654925Y28750D01*
X656150Y29750D01*
X657550Y30000D01*
X658950Y29750D01*
X660175Y28750D01*
X661225Y27250D01*
X661925Y25500D01*
X662275Y23500D01*
Y21500D01*
X661925Y19500D01*
X661225Y17750D01*
X660175Y16250D01*
X658950Y15250D01*
X657550Y15000D01*
G01X675250D02*
X668250D01*
Y30000D01*
X675250D01*
G01X672450Y22750D02*
X668250D01*
G01X682450Y15000D02*
Y30000D01*
X686825D01*
X688225Y29250D01*
X689100Y28250D01*
X689450Y26250D01*
X689100Y24250D01*
X688050Y23000D01*
X686825Y22250D01*
X682450D01*
G01X686825D02*
X689450Y15000D01*
G01X700150Y30000D02*
Y15000D01*
G01X696125Y30000D02*
X704175D01*
G01X714350Y15000D02*
Y21750D01*
X710850Y30000D01*
G01X717850D02*
X714350Y21750D01*
G01X741875Y10000D02*
X740125Y12500D01*
X739250Y15000D01*
Y25000D01*
X740125Y27500D01*
X741875Y30000D01*
G01X756950D02*
Y15000D01*
G01X752925Y30000D02*
X760975D01*
G01X771150Y15000D02*
X769750Y15250D01*
X768525Y16250D01*
X767475Y17750D01*
X766775Y19500D01*
X766425Y21500D01*
Y23500D01*
X766775Y25500D01*
X767475Y27250D01*
X768525Y28750D01*
X769750Y29750D01*
X771150Y30000D01*
X772550Y29750D01*
X773775Y28750D01*
X774825Y27250D01*
X775525Y25500D01*
X775875Y23500D01*
Y21500D01*
X775525Y19500D01*
X774825Y17750D01*
X773775Y16250D01*
X772550Y15250D01*
X771150Y15000D01*
G01X781850D02*
Y30000D01*
X786050D01*
X787450Y29250D01*
X788500Y27500D01*
X788850Y25500D01*
X788500Y23500D01*
X787625Y22000D01*
X786050Y21250D01*
X781850D01*
G01X-222850Y60000D02*
Y45000D01*
G01X-226875Y60000D02*
X-218825D01*
G01X-212325Y45000D02*
Y60000D01*
G01X-204975D02*
Y45000D01*
G01Y52500D02*
X-212325D01*
G01X-196550Y60000D02*
X-192350D01*
G01X-194450D02*
Y45000D01*
G01X-196550D02*
X-192350D01*
G01X-176400Y58750D02*
X-177450Y59500D01*
X-178675Y60000D01*
X-180075D01*
X-181650Y59250D01*
X-182875Y58000D01*
X-183750Y56500D01*
X-184450Y54000D01*
X-184625Y51750D01*
X-184275Y49500D01*
X-183750Y48000D01*
X-182700Y46500D01*
X-181475Y45500D01*
X-180250Y45000D01*
X-179025D01*
X-177800Y45500D01*
X-176750Y46250D01*
X-175875Y47250D01*
G01X-169900Y45000D02*
Y60000D01*
G01X-163250D02*
X-169900Y50750D01*
G01X-162200Y45000D02*
X-166925Y55000D01*
G01X-155875Y45000D02*
Y60000D01*
X-147825Y45000D01*
Y60000D01*
G01X-134150Y45000D02*
X-141150D01*
Y60000D01*
X-134150D01*
G01X-136950Y52750D02*
X-141150D01*
G01X-127125Y47000D02*
X-125725Y45750D01*
X-124150Y45000D01*
X-122750D01*
X-121350Y45750D01*
X-120300Y47000D01*
X-119775Y48750D01*
X-120125Y50500D01*
X-121000Y52000D01*
X-122575Y53000D01*
X-124675Y53500D01*
X-125900Y54500D01*
X-126425Y56250D01*
X-126075Y58000D01*
X-125200Y59250D01*
X-123975Y60000D01*
X-122750D01*
X-121525Y59500D01*
X-120475Y58250D01*
G01X-112925Y47000D02*
X-111525Y45750D01*
X-109950Y45000D01*
X-108550D01*
X-107150Y45750D01*
X-106100Y47000D01*
X-105575Y48750D01*
X-105925Y50500D01*
X-106800Y52000D01*
X-108375Y53000D01*
X-110475Y53500D01*
X-111700Y54500D01*
X-112225Y56250D01*
X-111875Y58000D01*
X-111000Y59250D01*
X-109775Y60000D01*
X-108550D01*
X-107325Y59500D01*
X-106275Y58250D01*
G01X-82950Y60000D02*
X-78750D01*
G01X-80850D02*
Y45000D01*
G01X-82950D02*
X-78750D01*
G01X-70675D02*
Y60000D01*
X-62625Y45000D01*
Y60000D01*
G01X-41925Y45000D02*
Y60000D01*
G01X-34575D02*
Y45000D01*
G01Y52500D02*
X-41925D01*
G01X-24050Y45000D02*
X-25450Y45250D01*
X-26675Y46250D01*
X-27725Y47750D01*
X-28425Y49500D01*
X-28775Y51500D01*
Y53500D01*
X-28425Y55500D01*
X-27725Y57250D01*
X-26675Y58750D01*
X-25450Y59750D01*
X-24050Y60000D01*
X-22650Y59750D01*
X-21425Y58750D01*
X-20375Y57250D01*
X-19675Y55500D01*
X-19325Y53500D01*
Y51500D01*
X-19675Y49500D01*
X-20375Y47750D01*
X-21425Y46250D01*
X-22650Y45250D01*
X-24050Y45000D01*
G01X-13350Y60000D02*
Y45000D01*
X-6350D01*
G01X7850D02*
X850D01*
Y60000D01*
X7850D01*
G01X5050Y52750D02*
X850D01*
G01X31875Y40000D02*
X30125Y42500D01*
X29250Y45000D01*
Y55000D01*
X30125Y57500D01*
X31875Y60000D01*
G01X43625Y51250D02*
X44850Y53000D01*
X45900Y54000D01*
X47300Y54500D01*
X48525Y54000D01*
X49400Y53000D01*
X50100Y51500D01*
X50275Y49750D01*
X50100Y48250D01*
X49400Y46750D01*
X48350Y45500D01*
X47125Y45000D01*
X45725Y45500D01*
X44500Y47000D01*
X43800Y49250D01*
X43625Y51750D01*
X43975Y55000D01*
X44500Y56750D01*
X45375Y58500D01*
X46600Y59750D01*
X47825Y60000D01*
X49050Y59500D01*
X49925Y58250D01*
G01X71850Y60000D02*
Y45000D01*
X78850D01*
G01X89550D02*
X88150Y45250D01*
X86925Y46250D01*
X85875Y47750D01*
X85175Y49500D01*
X84825Y51500D01*
Y53500D01*
X85175Y55500D01*
X85875Y57250D01*
X86925Y58750D01*
X88150Y59750D01*
X89550Y60000D01*
X90950Y59750D01*
X92175Y58750D01*
X93225Y57250D01*
X93925Y55500D01*
X94275Y53500D01*
Y51500D01*
X93925Y49500D01*
X93225Y47750D01*
X92175Y46250D01*
X90950Y45250D01*
X89550Y45000D01*
G01X107600Y58750D02*
X106550Y59500D01*
X105325Y60000D01*
X103925D01*
X102350Y59250D01*
X101125Y58000D01*
X100250Y56500D01*
X99550Y54000D01*
X99375Y51750D01*
X99725Y49500D01*
X100250Y48000D01*
X101300Y46500D01*
X102525Y45500D01*
X103750Y45000D01*
X104975D01*
X106200Y45500D01*
X107250Y46250D01*
X108125Y47250D01*
G01X113575Y45000D02*
X117950Y60000D01*
X122325Y45000D01*
G01X120750Y50250D02*
X115150D01*
G01X132150Y60000D02*
Y45000D01*
G01X128125Y60000D02*
X136175D01*
G01X144250D02*
X148450D01*
G01X146350D02*
Y45000D01*
G01X144250D02*
X148450D01*
G01X160550D02*
X159150Y45250D01*
X157925Y46250D01*
X156875Y47750D01*
X156175Y49500D01*
X155825Y51500D01*
Y53500D01*
X156175Y55500D01*
X156875Y57250D01*
X157925Y58750D01*
X159150Y59750D01*
X160550Y60000D01*
X161950Y59750D01*
X163175Y58750D01*
X164225Y57250D01*
X164925Y55500D01*
X165275Y53500D01*
Y51500D01*
X164925Y49500D01*
X164225Y47750D01*
X163175Y46250D01*
X161950Y45250D01*
X160550Y45000D01*
G01X170725D02*
Y60000D01*
X178775Y45000D01*
Y60000D01*
G01X185275Y47000D02*
X186675Y45750D01*
X188250Y45000D01*
X189650D01*
X191050Y45750D01*
X192100Y47000D01*
X192625Y48750D01*
X192275Y50500D01*
X191400Y52000D01*
X189825Y53000D01*
X187725Y53500D01*
X186500Y54500D01*
X185975Y56250D01*
X186325Y58000D01*
X187200Y59250D01*
X188425Y60000D01*
X189650D01*
X190875Y59500D01*
X191925Y58250D01*
G01X215075Y50000D02*
X219625D01*
G01X242425Y57500D02*
X243475Y59000D01*
X244700Y59750D01*
X246100Y60000D01*
X247850Y59500D01*
X249075Y58250D01*
X249425Y56750D01*
X249250Y55250D01*
X248550Y54000D01*
X245050Y51500D01*
X243475Y49750D01*
X242425Y47250D01*
X242075Y45000D01*
X249425D01*
G01X274150Y60000D02*
Y45000D01*
G01X270125Y60000D02*
X278175D01*
G01X288350Y45000D02*
X286950Y45250D01*
X285725Y46250D01*
X284675Y47750D01*
X283975Y49500D01*
X283625Y51500D01*
Y53500D01*
X283975Y55500D01*
X284675Y57250D01*
X285725Y58750D01*
X286950Y59750D01*
X288350Y60000D01*
X289750Y59750D01*
X290975Y58750D01*
X292025Y57250D01*
X292725Y55500D01*
X293075Y53500D01*
Y51500D01*
X292725Y49500D01*
X292025Y47750D01*
X290975Y46250D01*
X289750Y45250D01*
X288350Y45000D01*
G01X299050D02*
Y60000D01*
X303250D01*
X304650Y59250D01*
X305700Y57500D01*
X306050Y55500D01*
X305700Y53500D01*
X304825Y52000D01*
X303250Y51250D01*
X299050D01*
G01X313075Y47000D02*
X314475Y45750D01*
X316050Y45000D01*
X317450D01*
X318850Y45750D01*
X319900Y47000D01*
X320425Y48750D01*
X320075Y50500D01*
X319200Y52000D01*
X317625Y53000D01*
X315525Y53500D01*
X314300Y54500D01*
X313775Y56250D01*
X314125Y58000D01*
X315000Y59250D01*
X316225Y60000D01*
X317450D01*
X318675Y59500D01*
X319725Y58250D01*
G01X330600Y42250D02*
X331300Y45500D01*
G01X356025Y57500D02*
X357075Y59000D01*
X358300Y59750D01*
X359700Y60000D01*
X361450Y59500D01*
X362675Y58250D01*
X363025Y56750D01*
X362850Y55250D01*
X362150Y54000D01*
X358650Y51500D01*
X357075Y49750D01*
X356025Y47250D01*
X355675Y45000D01*
X363025D01*
G01X383200D02*
Y60000D01*
X387750Y47500D01*
X392300Y60000D01*
Y45000D01*
G01X399850Y60000D02*
X404050D01*
G01X401950D02*
Y45000D01*
G01X399850D02*
X404050D01*
G01X412300D02*
Y60000D01*
X415800D01*
X417200Y59250D01*
X418250Y58250D01*
X419125Y56750D01*
X419825Y55000D01*
X420000Y52500D01*
X419825Y50000D01*
X419125Y48250D01*
X418250Y46750D01*
X417200Y45750D01*
X415800Y45000D01*
X412300D01*
G01X426500D02*
Y60000D01*
X430000D01*
X431400Y59250D01*
X432450Y58250D01*
X433325Y56750D01*
X434025Y55000D01*
X434200Y52500D01*
X434025Y50000D01*
X433325Y48250D01*
X432450Y46750D01*
X431400Y45750D01*
X430000Y45000D01*
X426500D01*
G01X441050Y60000D02*
Y45000D01*
X448050D01*
G01X462250D02*
X455250D01*
Y60000D01*
X462250D01*
G01X459450Y52750D02*
X455250D01*
G01X469275Y47000D02*
X470675Y45750D01*
X472250Y45000D01*
X473650D01*
X475050Y45750D01*
X476100Y47000D01*
X476625Y48750D01*
X476275Y50500D01*
X475400Y52000D01*
X473825Y53000D01*
X471725Y53500D01*
X470500Y54500D01*
X469975Y56250D01*
X470325Y58000D01*
X471200Y59250D01*
X472425Y60000D01*
X473650D01*
X474875Y59500D01*
X475925Y58250D01*
G01X496975Y45000D02*
X501350Y60000D01*
X505725Y45000D01*
G01X504150Y50250D02*
X498550D01*
G01X511525Y45000D02*
Y60000D01*
X519575Y45000D01*
Y60000D01*
G01X525900Y45000D02*
Y60000D01*
X529400D01*
X530800Y59250D01*
X531850Y58250D01*
X532725Y56750D01*
X533425Y55000D01*
X533600Y52500D01*
X533425Y50000D01*
X532725Y48250D01*
X531850Y46750D01*
X530800Y45750D01*
X529400Y45000D01*
X525900D01*
G01X554825Y57500D02*
X555875Y59000D01*
X557100Y59750D01*
X558500Y60000D01*
X560250Y59500D01*
X561475Y58250D01*
X561825Y56750D01*
X561650Y55250D01*
X560950Y54000D01*
X557450Y51500D01*
X555875Y49750D01*
X554825Y47250D01*
X554475Y45000D01*
X561825D01*
G01X-227225Y90000D02*
X-222850Y75000D01*
X-218475Y90000D01*
G01X-210750D02*
X-206550D01*
G01X-208650D02*
Y75000D01*
G01X-210750D02*
X-206550D01*
G01X-198825D02*
X-194450Y90000D01*
X-190075Y75000D01*
G01X-191650Y80250D02*
X-197250D01*
G01X-183925Y77000D02*
X-182525Y75750D01*
X-180950Y75000D01*
X-179550D01*
X-178150Y75750D01*
X-177100Y77000D01*
X-176575Y78750D01*
X-176925Y80500D01*
X-177800Y82000D01*
X-179375Y83000D01*
X-181475Y83500D01*
X-182700Y84500D01*
X-183225Y86250D01*
X-182875Y88000D01*
X-182000Y89250D01*
X-180775Y90000D01*
X-179550D01*
X-178325Y89500D01*
X-177275Y88250D01*
G01X-166400Y72250D02*
X-165700Y75500D01*
G01X-133800Y88750D02*
X-134850Y89500D01*
X-136075Y90000D01*
X-137475D01*
X-139050Y89250D01*
X-140275Y88000D01*
X-141150Y86500D01*
X-141850Y84000D01*
X-142025Y81750D01*
X-141675Y79500D01*
X-141150Y78000D01*
X-140100Y76500D01*
X-138875Y75500D01*
X-137650Y75000D01*
X-136425D01*
X-135200Y75500D01*
X-134150Y76250D01*
X-133275Y77250D01*
G01X-123450Y75000D02*
X-124850Y75250D01*
X-126075Y76250D01*
X-127125Y77750D01*
X-127825Y79500D01*
X-128175Y81500D01*
Y83500D01*
X-127825Y85500D01*
X-127125Y87250D01*
X-126075Y88750D01*
X-124850Y89750D01*
X-123450Y90000D01*
X-122050Y89750D01*
X-120825Y88750D01*
X-119775Y87250D01*
X-119075Y85500D01*
X-118725Y83500D01*
Y81500D01*
X-119075Y79500D01*
X-119775Y77750D01*
X-120825Y76250D01*
X-122050Y75250D01*
X-123450Y75000D01*
G01X-112750D02*
Y90000D01*
X-108550D01*
X-107150Y89250D01*
X-106100Y87500D01*
X-105750Y85500D01*
X-106100Y83500D01*
X-106975Y82000D01*
X-108550Y81250D01*
X-112750D01*
G01X-98550Y75000D02*
Y90000D01*
X-94350D01*
X-92950Y89250D01*
X-91900Y87500D01*
X-91550Y85500D01*
X-91900Y83500D01*
X-92775Y82000D01*
X-94350Y81250D01*
X-98550D01*
G01X-77350Y75000D02*
X-84350D01*
Y90000D01*
X-77350D01*
G01X-80150Y82750D02*
X-84350D01*
G01X-70150Y75000D02*
Y90000D01*
X-65775D01*
X-64375Y89250D01*
X-63500Y88250D01*
X-63150Y86250D01*
X-63500Y84250D01*
X-64550Y83000D01*
X-65775Y82250D01*
X-70150D01*
G01X-65775D02*
X-63150Y75000D01*
G01X-41575D02*
Y90000D01*
X-34925D01*
G01X-37375Y82750D02*
X-41575D01*
G01X-24050Y75000D02*
X-25450Y75250D01*
X-26675Y76250D01*
X-27725Y77750D01*
X-28425Y79500D01*
X-28775Y81500D01*
Y83500D01*
X-28425Y85500D01*
X-27725Y87250D01*
X-26675Y88750D01*
X-25450Y89750D01*
X-24050Y90000D01*
X-22650Y89750D01*
X-21425Y88750D01*
X-20375Y87250D01*
X-19675Y85500D01*
X-19325Y83500D01*
Y81500D01*
X-19675Y79500D01*
X-20375Y77750D01*
X-21425Y76250D01*
X-22650Y75250D01*
X-24050Y75000D01*
G01X-11950Y90000D02*
X-7750D01*
G01X-9850D02*
Y75000D01*
G01X-11950D02*
X-7750D01*
G01X850Y90000D02*
Y75000D01*
X7850D01*
G01X30825Y80000D02*
X35025D01*
G01X32750Y83250D02*
Y76750D01*
G01X57650Y75000D02*
Y90000D01*
X61850D01*
X63250Y89250D01*
X64300Y87500D01*
X64650Y85500D01*
X64300Y83500D01*
X63425Y82000D01*
X61850Y81250D01*
X57650D01*
G01X71850Y90000D02*
Y75000D01*
X78850D01*
G01X85175D02*
X89550Y90000D01*
X93925Y75000D01*
G01X92350Y80250D02*
X86750D01*
G01X103750Y90000D02*
Y75000D01*
G01X99725Y90000D02*
X107775D01*
G01X115850D02*
X120050D01*
G01X117950D02*
Y75000D01*
G01X115850D02*
X120050D01*
G01X128125D02*
Y90000D01*
X136175Y75000D01*
Y90000D01*
G01X147400Y82500D02*
X150900D01*
Y78000D01*
X149850Y76500D01*
X148625Y75500D01*
X146875Y75000D01*
X145125Y75500D01*
X143900Y76500D01*
X142850Y78000D01*
X142150Y79750D01*
X141800Y81750D01*
Y83500D01*
X142150Y85000D01*
X142850Y86750D01*
X143900Y88250D01*
X144950Y89250D01*
X146350Y90000D01*
X147575D01*
X148975Y89500D01*
X150025Y88500D01*
G01X174750Y90000D02*
Y75000D01*
G01X170725Y90000D02*
X178775D01*
G01X185275Y75000D02*
Y90000D01*
G01X192625D02*
Y75000D01*
G01Y82500D02*
X185275D01*
G01X201050Y90000D02*
X205250D01*
G01X203150D02*
Y75000D01*
G01X201050D02*
X205250D01*
G01X221200Y88750D02*
X220150Y89500D01*
X218925Y90000D01*
X217525D01*
X215950Y89250D01*
X214725Y88000D01*
X213850Y86500D01*
X213150Y84000D01*
X212975Y81750D01*
X213325Y79500D01*
X213850Y78000D01*
X214900Y76500D01*
X216125Y75500D01*
X217350Y75000D01*
X218575D01*
X219800Y75500D01*
X220850Y76250D01*
X221725Y77250D01*
G01X227700Y75000D02*
Y90000D01*
G01X234350D02*
X227700Y80750D01*
G01X235400Y75000D02*
X230675Y85000D01*
G01X241725Y75000D02*
Y90000D01*
X249775Y75000D01*
Y90000D01*
G01X263450Y75000D02*
X256450D01*
Y90000D01*
X263450D01*
G01X260650Y82750D02*
X256450D01*
G01X270475Y77000D02*
X271875Y75750D01*
X273450Y75000D01*
X274850D01*
X276250Y75750D01*
X277300Y77000D01*
X277825Y78750D01*
X277475Y80500D01*
X276600Y82000D01*
X275025Y83000D01*
X272925Y83500D01*
X271700Y84500D01*
X271175Y86250D01*
X271525Y88000D01*
X272400Y89250D01*
X273625Y90000D01*
X274850D01*
X276075Y89500D01*
X277125Y88250D01*
G01X284675Y77000D02*
X286075Y75750D01*
X287650Y75000D01*
X289050D01*
X290450Y75750D01*
X291500Y77000D01*
X292025Y78750D01*
X291675Y80500D01*
X290800Y82000D01*
X289225Y83000D01*
X287125Y83500D01*
X285900Y84500D01*
X285375Y86250D01*
X285725Y88000D01*
X286600Y89250D01*
X287825Y90000D01*
X289050D01*
X290275Y89500D01*
X291325Y88250D01*
G01X315875Y70000D02*
X314125Y72500D01*
X313250Y75000D01*
Y85000D01*
X314125Y87500D01*
X315875Y90000D01*
G01X330950D02*
Y75000D01*
G01X326925Y90000D02*
X334975D01*
G01X345150Y75000D02*
X343750Y75250D01*
X342525Y76250D01*
X341475Y77750D01*
X340775Y79500D01*
X340425Y81500D01*
Y83500D01*
X340775Y85500D01*
X341475Y87250D01*
X342525Y88750D01*
X343750Y89750D01*
X345150Y90000D01*
X346550Y89750D01*
X347775Y88750D01*
X348825Y87250D01*
X349525Y85500D01*
X349875Y83500D01*
Y81500D01*
X349525Y79500D01*
X348825Y77750D01*
X347775Y76250D01*
X346550Y75250D01*
X345150Y75000D01*
G01X355850D02*
Y90000D01*
X360050D01*
X361450Y89250D01*
X362500Y87500D01*
X362850Y85500D01*
X362500Y83500D01*
X361625Y82000D01*
X360050Y81250D01*
X355850D01*
G01X387750Y90000D02*
Y75000D01*
G01X383725Y90000D02*
X391775D01*
G01X401950Y75000D02*
X400550Y75250D01*
X399325Y76250D01*
X398275Y77750D01*
X397575Y79500D01*
X397225Y81500D01*
Y83500D01*
X397575Y85500D01*
X398275Y87250D01*
X399325Y88750D01*
X400550Y89750D01*
X401950Y90000D01*
X403350Y89750D01*
X404575Y88750D01*
X405625Y87250D01*
X406325Y85500D01*
X406675Y83500D01*
Y81500D01*
X406325Y79500D01*
X405625Y77750D01*
X404575Y76250D01*
X403350Y75250D01*
X401950Y75000D01*
G01X431750Y83000D02*
X432450Y83750D01*
X432975Y85000D01*
X433325Y86750D01*
X432975Y88250D01*
X432275Y89250D01*
X431050Y90000D01*
X426325D01*
Y75000D01*
X432100D01*
X433325Y76000D01*
X434025Y77500D01*
X434375Y79250D01*
X434025Y81000D01*
X432975Y82500D01*
X431750Y83000D01*
X426325D01*
G01X444550Y75000D02*
X443150Y75250D01*
X441925Y76250D01*
X440875Y77750D01*
X440175Y79500D01*
X439825Y81500D01*
Y83500D01*
X440175Y85500D01*
X440875Y87250D01*
X441925Y88750D01*
X443150Y89750D01*
X444550Y90000D01*
X445950Y89750D01*
X447175Y88750D01*
X448225Y87250D01*
X448925Y85500D01*
X449275Y83500D01*
Y81500D01*
X448925Y79500D01*
X448225Y77750D01*
X447175Y76250D01*
X445950Y75250D01*
X444550Y75000D01*
G01X458750Y90000D02*
Y75000D01*
G01X454725Y90000D02*
X462775D01*
G01X472950D02*
Y75000D01*
G01X468925Y90000D02*
X476975D01*
G01X487150Y75000D02*
X485750Y75250D01*
X484525Y76250D01*
X483475Y77750D01*
X482775Y79500D01*
X482425Y81500D01*
Y83500D01*
X482775Y85500D01*
X483475Y87250D01*
X484525Y88750D01*
X485750Y89750D01*
X487150Y90000D01*
X488550Y89750D01*
X489775Y88750D01*
X490825Y87250D01*
X491525Y85500D01*
X491875Y83500D01*
Y81500D01*
X491525Y79500D01*
X490825Y77750D01*
X489775Y76250D01*
X488550Y75250D01*
X487150Y75000D01*
G01X496800D02*
Y90000D01*
X501350Y77500D01*
X505900Y90000D01*
Y75000D01*
G01X516425Y70000D02*
X518175Y72500D01*
X519050Y75000D01*
Y85000D01*
X518175Y87500D01*
X516425Y90000D01*
G01X529400Y72250D02*
X530100Y75500D01*
G01X562000Y88750D02*
X560950Y89500D01*
X559725Y90000D01*
X558325D01*
X556750Y89250D01*
X555525Y88000D01*
X554650Y86500D01*
X553950Y84000D01*
X553775Y81750D01*
X554125Y79500D01*
X554650Y78000D01*
X555700Y76500D01*
X556925Y75500D01*
X558150Y75000D01*
X559375D01*
X560600Y75500D01*
X561650Y76250D01*
X562525Y77250D01*
G01X572350Y75000D02*
X570950Y75250D01*
X569725Y76250D01*
X568675Y77750D01*
X567975Y79500D01*
X567625Y81500D01*
Y83500D01*
X567975Y85500D01*
X568675Y87250D01*
X569725Y88750D01*
X570950Y89750D01*
X572350Y90000D01*
X573750Y89750D01*
X574975Y88750D01*
X576025Y87250D01*
X576725Y85500D01*
X577075Y83500D01*
Y81500D01*
X576725Y79500D01*
X576025Y77750D01*
X574975Y76250D01*
X573750Y75250D01*
X572350Y75000D01*
G01X583050D02*
Y90000D01*
X587250D01*
X588650Y89250D01*
X589700Y87500D01*
X590050Y85500D01*
X589700Y83500D01*
X588825Y82000D01*
X587250Y81250D01*
X583050D01*
G01X597250Y75000D02*
Y90000D01*
X601450D01*
X602850Y89250D01*
X603900Y87500D01*
X604250Y85500D01*
X603900Y83500D01*
X603025Y82000D01*
X601450Y81250D01*
X597250D01*
G01X618450Y75000D02*
X611450D01*
Y90000D01*
X618450D01*
G01X615650Y82750D02*
X611450D01*
G01X625650Y75000D02*
Y90000D01*
X630025D01*
X631425Y89250D01*
X632300Y88250D01*
X632650Y86250D01*
X632300Y84250D01*
X631250Y83000D01*
X630025Y82250D01*
X625650D01*
G01X630025D02*
X632650Y75000D01*
G01X654050D02*
Y90000D01*
X658250D01*
X659650Y89250D01*
X660700Y87500D01*
X661050Y85500D01*
X660700Y83500D01*
X659825Y82000D01*
X658250Y81250D01*
X654050D01*
G01X668250Y90000D02*
Y75000D01*
X675250D01*
G01X681575D02*
X685950Y90000D01*
X690325Y75000D01*
G01X688750Y80250D02*
X683150D01*
G01X700150Y90000D02*
Y75000D01*
G01X696125Y90000D02*
X704175D01*
G01X712250D02*
X716450D01*
G01X714350D02*
Y75000D01*
G01X712250D02*
X716450D01*
G01X724525D02*
Y90000D01*
X732575Y75000D01*
Y90000D01*
G01X743800Y82500D02*
X747300D01*
Y78000D01*
X746250Y76500D01*
X745025Y75500D01*
X743275Y75000D01*
X741525Y75500D01*
X740300Y76500D01*
X739250Y78000D01*
X738550Y79750D01*
X738200Y81750D01*
Y83500D01*
X738550Y85000D01*
X739250Y86750D01*
X740300Y88250D01*
X741350Y89250D01*
X742750Y90000D01*
X743975D01*
X745375Y89500D01*
X746425Y88500D01*
G01X-224950Y120000D02*
X-220750D01*
G01X-222850D02*
Y105000D01*
G01X-224950D02*
X-220750D01*
G01X-212675D02*
Y120000D01*
X-204625Y105000D01*
Y120000D01*
G01X-180250D02*
Y105000D01*
G01X-184275Y120000D02*
X-176225D01*
G01X-169725Y105000D02*
Y120000D01*
G01X-162375D02*
Y105000D01*
G01Y112500D02*
X-169725D01*
G01X-148350Y105000D02*
X-155350D01*
Y120000D01*
X-148350D01*
G01X-151150Y112750D02*
X-155350D01*
G01X-126950Y105000D02*
Y120000D01*
X-122575D01*
X-121175Y119250D01*
X-120300Y118250D01*
X-119950Y116250D01*
X-120300Y114250D01*
X-121350Y113000D01*
X-122575Y112250D01*
X-126950D01*
G01X-122575D02*
X-119950Y105000D01*
G01X-105750D02*
X-112750D01*
Y120000D01*
X-105750D01*
G01X-108550Y112750D02*
X-112750D01*
G01X-98550Y105000D02*
Y120000D01*
X-94350D01*
X-92950Y119250D01*
X-91900Y117500D01*
X-91550Y115500D01*
X-91900Y113500D01*
X-92775Y112000D01*
X-94350Y111250D01*
X-98550D01*
G01X-80850Y105000D02*
X-82250Y105250D01*
X-83475Y106250D01*
X-84525Y107750D01*
X-85225Y109500D01*
X-85575Y111500D01*
Y113500D01*
X-85225Y115500D01*
X-84525Y117250D01*
X-83475Y118750D01*
X-82250Y119750D01*
X-80850Y120000D01*
X-79450Y119750D01*
X-78225Y118750D01*
X-77175Y117250D01*
X-76475Y115500D01*
X-76125Y113500D01*
Y111500D01*
X-76475Y109500D01*
X-77175Y107750D01*
X-78225Y106250D01*
X-79450Y105250D01*
X-80850Y105000D01*
G01X-70150D02*
Y120000D01*
X-65775D01*
X-64375Y119250D01*
X-63500Y118250D01*
X-63150Y116250D01*
X-63500Y114250D01*
X-64550Y113000D01*
X-65775Y112250D01*
X-70150D01*
G01X-65775D02*
X-63150Y105000D01*
G01X-52450Y120000D02*
Y105000D01*
G01X-56475Y120000D02*
X-48425D01*
G01X-38250Y104500D02*
X-38600Y104750D01*
Y105250D01*
X-38250Y105500D01*
X-37900Y105250D01*
Y104750D01*
X-38250Y104500D01*
G01X-14400Y105000D02*
Y120000D01*
X-9850Y107500D01*
X-5300Y120000D01*
Y105000D01*
G01X7850D02*
X850D01*
Y120000D01*
X7850D01*
G01X5050Y112750D02*
X850D01*
G01X14175Y105000D02*
X18550Y120000D01*
X22925Y105000D01*
G01X21350Y110250D02*
X15750D01*
G01X29075Y107000D02*
X30475Y105750D01*
X32050Y105000D01*
X33450D01*
X34850Y105750D01*
X35900Y107000D01*
X36425Y108750D01*
X36075Y110500D01*
X35200Y112000D01*
X33625Y113000D01*
X31525Y113500D01*
X30300Y114500D01*
X29775Y116250D01*
X30125Y118000D01*
X31000Y119250D01*
X32225Y120000D01*
X33450D01*
X34675Y119500D01*
X35725Y118250D01*
G01X43100Y120000D02*
Y109250D01*
X43800Y107000D01*
X45200Y105500D01*
X46950Y105000D01*
X48700Y105500D01*
X50100Y107000D01*
X50800Y109250D01*
Y120000D01*
G01X57650Y105000D02*
Y120000D01*
X62025D01*
X63425Y119250D01*
X64300Y118250D01*
X64650Y116250D01*
X64300Y114250D01*
X63250Y113000D01*
X62025Y112250D01*
X57650D01*
G01X62025D02*
X64650Y105000D01*
G01X78850D02*
X71850D01*
Y120000D01*
X78850D01*
G01X76050Y112750D02*
X71850D01*
G01X103750Y120000D02*
Y105000D01*
G01X99725Y120000D02*
X107775D01*
G01X114275Y105000D02*
Y120000D01*
G01X121625D02*
Y105000D01*
G01Y112500D02*
X114275D01*
G01X135650Y105000D02*
X128650D01*
Y120000D01*
X135650D01*
G01X132850Y112750D02*
X128650D01*
G01X157050Y105000D02*
Y120000D01*
X161250D01*
X162650Y119250D01*
X163700Y117500D01*
X164050Y115500D01*
X163700Y113500D01*
X162825Y112000D01*
X161250Y111250D01*
X157050D01*
G01X178250Y105000D02*
X171250D01*
Y120000D01*
X178250D01*
G01X175450Y112750D02*
X171250D01*
G01X185450Y105000D02*
Y120000D01*
X189825D01*
X191225Y119250D01*
X192100Y118250D01*
X192450Y116250D01*
X192100Y114250D01*
X191050Y113000D01*
X189825Y112250D01*
X185450D01*
G01X189825D02*
X192450Y105000D01*
G01X207000Y118750D02*
X205950Y119500D01*
X204725Y120000D01*
X203325D01*
X201750Y119250D01*
X200525Y118000D01*
X199650Y116500D01*
X198950Y114000D01*
X198775Y111750D01*
X199125Y109500D01*
X199650Y108000D01*
X200700Y106500D01*
X201925Y105500D01*
X203150Y105000D01*
X204375D01*
X205600Y105500D01*
X206650Y106250D01*
X207525Y107250D01*
G01X220850Y105000D02*
X213850D01*
Y120000D01*
X220850D01*
G01X218050Y112750D02*
X213850D01*
G01X227525Y105000D02*
Y120000D01*
X235575Y105000D01*
Y120000D01*
G01X245750D02*
Y105000D01*
G01X241725Y120000D02*
X249775D01*
G01X255575Y105000D02*
X259950Y120000D01*
X264325Y105000D01*
G01X262750Y110250D02*
X257150D01*
G01X275200Y112500D02*
X278700D01*
Y108000D01*
X277650Y106500D01*
X276425Y105500D01*
X274675Y105000D01*
X272925Y105500D01*
X271700Y106500D01*
X270650Y108000D01*
X269950Y109750D01*
X269600Y111750D01*
Y113500D01*
X269950Y115000D01*
X270650Y116750D01*
X271700Y118250D01*
X272750Y119250D01*
X274150Y120000D01*
X275375D01*
X276775Y119500D01*
X277825Y118500D01*
G01X291850Y105000D02*
X284850D01*
Y120000D01*
X291850D01*
G01X289050Y112750D02*
X284850D01*
G01X316750Y105000D02*
X315350Y105250D01*
X314125Y106250D01*
X313075Y107750D01*
X312375Y109500D01*
X312025Y111500D01*
Y113500D01*
X312375Y115500D01*
X313075Y117250D01*
X314125Y118750D01*
X315350Y119750D01*
X316750Y120000D01*
X318150Y119750D01*
X319375Y118750D01*
X320425Y117250D01*
X321125Y115500D01*
X321475Y113500D01*
Y111500D01*
X321125Y109500D01*
X320425Y107750D01*
X319375Y106250D01*
X318150Y105250D01*
X316750Y105000D01*
G01X327625D02*
Y120000D01*
X334275D01*
G01X331825Y112750D02*
X327625D01*
G01X359350Y120000D02*
Y105000D01*
G01X355325Y120000D02*
X363375D01*
G01X369875Y105000D02*
Y120000D01*
G01X377225D02*
Y105000D01*
G01Y112500D02*
X369875D01*
G01X391250Y105000D02*
X384250D01*
Y120000D01*
X391250D01*
G01X388450Y112750D02*
X384250D01*
G01X412475Y107000D02*
X413875Y105750D01*
X415450Y105000D01*
X416850D01*
X418250Y105750D01*
X419300Y107000D01*
X419825Y108750D01*
X419475Y110500D01*
X418600Y112000D01*
X417025Y113000D01*
X414925Y113500D01*
X413700Y114500D01*
X413175Y116250D01*
X413525Y118000D01*
X414400Y119250D01*
X415625Y120000D01*
X416850D01*
X418075Y119500D01*
X419125Y118250D01*
G01X430350Y120000D02*
Y105000D01*
G01X426325Y120000D02*
X434375D01*
G01X440700D02*
Y109250D01*
X441400Y107000D01*
X442800Y105500D01*
X444550Y105000D01*
X446300Y105500D01*
X447700Y107000D01*
X448400Y109250D01*
Y120000D01*
G01X455425Y105000D02*
Y120000D01*
X462075D01*
G01X459625Y112750D02*
X455425D01*
G01X469625Y105000D02*
Y120000D01*
X476275D01*
G01X473825Y112750D02*
X469625D01*
G01X485050Y120000D02*
X489250D01*
G01X487150D02*
Y105000D01*
G01X485050D02*
X489250D01*
G01X497325D02*
Y120000D01*
X505375Y105000D01*
Y120000D01*
G01X516600Y112500D02*
X520100D01*
Y108000D01*
X519050Y106500D01*
X517825Y105500D01*
X516075Y105000D01*
X514325Y105500D01*
X513100Y106500D01*
X512050Y108000D01*
X511350Y109750D01*
X511000Y111750D01*
Y113500D01*
X511350Y115000D01*
X512050Y116750D01*
X513100Y118250D01*
X514150Y119250D01*
X515550Y120000D01*
X516775D01*
X518175Y119500D01*
X519225Y118500D01*
G01X541850Y120000D02*
X546050D01*
G01X543950D02*
Y105000D01*
G01X541850D02*
X546050D01*
G01X554125D02*
Y120000D01*
X562175Y105000D01*
Y120000D01*
G01X586550D02*
Y105000D01*
G01X582525Y120000D02*
X590575D01*
G01X597075Y105000D02*
Y120000D01*
G01X604425D02*
Y105000D01*
G01Y112500D02*
X597075D01*
G01X618450Y105000D02*
X611450D01*
Y120000D01*
X618450D01*
G01X615650Y112750D02*
X611450D01*
G01X639850Y105000D02*
Y120000D01*
X644050D01*
X645450Y119250D01*
X646500Y117500D01*
X646850Y115500D01*
X646500Y113500D01*
X645625Y112000D01*
X644050Y111250D01*
X639850D01*
G01X654050Y120000D02*
Y105000D01*
X661050D01*
G01X667900Y120000D02*
Y109250D01*
X668600Y107000D01*
X670000Y105500D01*
X671750Y105000D01*
X673500Y105500D01*
X674900Y107000D01*
X675600Y109250D01*
Y120000D01*
G01X687000Y112500D02*
X690500D01*
Y108000D01*
X689450Y106500D01*
X688225Y105500D01*
X686475Y105000D01*
X684725Y105500D01*
X683500Y106500D01*
X682450Y108000D01*
X681750Y109750D01*
X681400Y111750D01*
Y113500D01*
X681750Y115000D01*
X682450Y116750D01*
X683500Y118250D01*
X684550Y119250D01*
X685950Y120000D01*
X687175D01*
X688575Y119500D01*
X689625Y118500D01*
G01X701200Y112500D02*
X704700D01*
Y108000D01*
X703650Y106500D01*
X702425Y105500D01*
X700675Y105000D01*
X698925Y105500D01*
X697700Y106500D01*
X696650Y108000D01*
X695950Y109750D01*
X695600Y111750D01*
Y113500D01*
X695950Y115000D01*
X696650Y116750D01*
X697700Y118250D01*
X698750Y119250D01*
X700150Y120000D01*
X701375D01*
X702775Y119500D01*
X703825Y118500D01*
G01X717850Y105000D02*
X710850D01*
Y120000D01*
X717850D01*
G01X715050Y112750D02*
X710850D01*
G01X724700Y105000D02*
Y120000D01*
X728200D01*
X729600Y119250D01*
X730650Y118250D01*
X731525Y116750D01*
X732225Y115000D01*
X732400Y112500D01*
X732225Y110000D01*
X731525Y108250D01*
X730650Y106750D01*
X729600Y105750D01*
X728200Y105000D01*
X724700D01*
G01X-219000Y148750D02*
X-220050Y149500D01*
X-221275Y150000D01*
X-222675D01*
X-224250Y149250D01*
X-225475Y148000D01*
X-226350Y146500D01*
X-227050Y144000D01*
X-227225Y141750D01*
X-226875Y139500D01*
X-226350Y138000D01*
X-225300Y136500D01*
X-224075Y135500D01*
X-222850Y135000D01*
X-221625D01*
X-220400Y135500D01*
X-219350Y136250D01*
X-218475Y137250D01*
G01X-208650Y135000D02*
X-210050Y135250D01*
X-211275Y136250D01*
X-212325Y137750D01*
X-213025Y139500D01*
X-213375Y141500D01*
Y143500D01*
X-213025Y145500D01*
X-212325Y147250D01*
X-211275Y148750D01*
X-210050Y149750D01*
X-208650Y150000D01*
X-207250Y149750D01*
X-206025Y148750D01*
X-204975Y147250D01*
X-204275Y145500D01*
X-203925Y143500D01*
Y141500D01*
X-204275Y139500D01*
X-204975Y137750D01*
X-206025Y136250D01*
X-207250Y135250D01*
X-208650Y135000D01*
G01X-197950D02*
Y150000D01*
X-193575D01*
X-192175Y149250D01*
X-191300Y148250D01*
X-190950Y146250D01*
X-191300Y144250D01*
X-192350Y143000D01*
X-193575Y142250D01*
X-197950D01*
G01X-193575D02*
X-190950Y135000D01*
G01X-184275D02*
Y150000D01*
X-176225Y135000D01*
Y150000D01*
G01X-162550Y135000D02*
X-169550D01*
Y150000D01*
X-162550D01*
G01X-165350Y142750D02*
X-169550D01*
G01X-155350Y135000D02*
Y150000D01*
X-150975D01*
X-149575Y149250D01*
X-148700Y148250D01*
X-148350Y146250D01*
X-148700Y144250D01*
X-149750Y143000D01*
X-150975Y142250D01*
X-155350D01*
G01X-150975D02*
X-148350Y135000D01*
G01X-137650Y134500D02*
X-138000Y134750D01*
Y135250D01*
X-137650Y135500D01*
X-137300Y135250D01*
Y134750D01*
X-137650Y134500D01*
G01X-112750Y135000D02*
Y150000D01*
X-108550D01*
X-107150Y149250D01*
X-106100Y147500D01*
X-105750Y145500D01*
X-106100Y143500D01*
X-106975Y142000D01*
X-108550Y141250D01*
X-112750D01*
G01X-97150Y150000D02*
X-92950D01*
G01X-95050D02*
Y135000D01*
G01X-97150D02*
X-92950D01*
G01X-77000Y148750D02*
X-78050Y149500D01*
X-79275Y150000D01*
X-80675D01*
X-82250Y149250D01*
X-83475Y148000D01*
X-84350Y146500D01*
X-85050Y144000D01*
X-85225Y141750D01*
X-84875Y139500D01*
X-84350Y138000D01*
X-83300Y136500D01*
X-82075Y135500D01*
X-80850Y135000D01*
X-79625D01*
X-78400Y135500D01*
X-77350Y136250D01*
X-76475Y137250D01*
G01X-66650Y150000D02*
Y135000D01*
G01X-70675Y150000D02*
X-62625D01*
G01X-56300D02*
Y139250D01*
X-55600Y137000D01*
X-54200Y135500D01*
X-52450Y135000D01*
X-50700Y135500D01*
X-49300Y137000D01*
X-48600Y139250D01*
Y150000D01*
G01X-41750Y135000D02*
Y150000D01*
X-37375D01*
X-35975Y149250D01*
X-35100Y148250D01*
X-34750Y146250D01*
X-35100Y144250D01*
X-36150Y143000D01*
X-37375Y142250D01*
X-41750D01*
G01X-37375D02*
X-34750Y135000D01*
G01X-20550D02*
X-27550D01*
Y150000D01*
X-20550D01*
G01X-23350Y142750D02*
X-27550D01*
G01X-13525Y137000D02*
X-12125Y135750D01*
X-10550Y135000D01*
X-9150D01*
X-7750Y135750D01*
X-6700Y137000D01*
X-6175Y138750D01*
X-6525Y140500D01*
X-7400Y142000D01*
X-8975Y143000D01*
X-11075Y143500D01*
X-12300Y144500D01*
X-12825Y146250D01*
X-12475Y148000D01*
X-11600Y149250D01*
X-10375Y150000D01*
X-9150D01*
X-7925Y149500D01*
X-6875Y148250D01*
G01X18550Y135000D02*
X17150Y135250D01*
X15925Y136250D01*
X14875Y137750D01*
X14175Y139500D01*
X13825Y141500D01*
Y143500D01*
X14175Y145500D01*
X14875Y147250D01*
X15925Y148750D01*
X17150Y149750D01*
X18550Y150000D01*
X19950Y149750D01*
X21175Y148750D01*
X22225Y147250D01*
X22925Y145500D01*
X23275Y143500D01*
Y141500D01*
X22925Y139500D01*
X22225Y137750D01*
X21175Y136250D01*
X19950Y135250D01*
X18550Y135000D01*
G01X29425D02*
Y150000D01*
X36075D01*
G01X33625Y142750D02*
X29425D01*
G01X61150Y150000D02*
Y135000D01*
G01X57125Y150000D02*
X65175D01*
G01X71675Y135000D02*
Y150000D01*
G01X79025D02*
Y135000D01*
G01Y142500D02*
X71675D01*
G01X93050Y135000D02*
X86050D01*
Y150000D01*
X93050D01*
G01X90250Y142750D02*
X86050D01*
G01X121800Y148750D02*
X120750Y149500D01*
X119525Y150000D01*
X118125D01*
X116550Y149250D01*
X115325Y148000D01*
X114450Y146500D01*
X113750Y144000D01*
X113575Y141750D01*
X113925Y139500D01*
X114450Y138000D01*
X115500Y136500D01*
X116725Y135500D01*
X117950Y135000D01*
X119175D01*
X120400Y135500D01*
X121450Y136250D01*
X122325Y137250D01*
G01X128650Y135000D02*
Y150000D01*
X133025D01*
X134425Y149250D01*
X135300Y148250D01*
X135650Y146250D01*
X135300Y144250D01*
X134250Y143000D01*
X133025Y142250D01*
X128650D01*
G01X133025D02*
X135650Y135000D01*
G01X146350D02*
X144950Y135250D01*
X143725Y136250D01*
X142675Y137750D01*
X141975Y139500D01*
X141625Y141500D01*
Y143500D01*
X141975Y145500D01*
X142675Y147250D01*
X143725Y148750D01*
X144950Y149750D01*
X146350Y150000D01*
X147750Y149750D01*
X148975Y148750D01*
X150025Y147250D01*
X150725Y145500D01*
X151075Y143500D01*
Y141500D01*
X150725Y139500D01*
X150025Y137750D01*
X148975Y136250D01*
X147750Y135250D01*
X146350Y135000D01*
G01X156875Y137000D02*
X158275Y135750D01*
X159850Y135000D01*
X161250D01*
X162650Y135750D01*
X163700Y137000D01*
X164225Y138750D01*
X163875Y140500D01*
X163000Y142000D01*
X161425Y143000D01*
X159325Y143500D01*
X158100Y144500D01*
X157575Y146250D01*
X157925Y148000D01*
X158800Y149250D01*
X160025Y150000D01*
X161250D01*
X162475Y149500D01*
X163525Y148250D01*
G01X171075Y137000D02*
X172475Y135750D01*
X174050Y135000D01*
X175450D01*
X176850Y135750D01*
X177900Y137000D01*
X178425Y138750D01*
X178075Y140500D01*
X177200Y142000D01*
X175625Y143000D01*
X173525Y143500D01*
X172300Y144500D01*
X171775Y146250D01*
X172125Y148000D01*
X173000Y149250D01*
X174225Y150000D01*
X175450D01*
X176675Y149500D01*
X177725Y148250D01*
G01X199475Y137000D02*
X200875Y135750D01*
X202450Y135000D01*
X203850D01*
X205250Y135750D01*
X206300Y137000D01*
X206825Y138750D01*
X206475Y140500D01*
X205600Y142000D01*
X204025Y143000D01*
X201925Y143500D01*
X200700Y144500D01*
X200175Y146250D01*
X200525Y148000D01*
X201400Y149250D01*
X202625Y150000D01*
X203850D01*
X205075Y149500D01*
X206125Y148250D01*
G01X220850Y135000D02*
X213850D01*
Y150000D01*
X220850D01*
G01X218050Y142750D02*
X213850D01*
G01X235400Y148750D02*
X234350Y149500D01*
X233125Y150000D01*
X231725D01*
X230150Y149250D01*
X228925Y148000D01*
X228050Y146500D01*
X227350Y144000D01*
X227175Y141750D01*
X227525Y139500D01*
X228050Y138000D01*
X229100Y136500D01*
X230325Y135500D01*
X231550Y135000D01*
X232775D01*
X234000Y135500D01*
X235050Y136250D01*
X235925Y137250D01*
G01X245750Y150000D02*
Y135000D01*
G01X241725Y150000D02*
X249775D01*
G01X257850D02*
X262050D01*
G01X259950D02*
Y135000D01*
G01X257850D02*
X262050D01*
G01X274150D02*
X272750Y135250D01*
X271525Y136250D01*
X270475Y137750D01*
X269775Y139500D01*
X269425Y141500D01*
Y143500D01*
X269775Y145500D01*
X270475Y147250D01*
X271525Y148750D01*
X272750Y149750D01*
X274150Y150000D01*
X275550Y149750D01*
X276775Y148750D01*
X277825Y147250D01*
X278525Y145500D01*
X278875Y143500D01*
Y141500D01*
X278525Y139500D01*
X277825Y137750D01*
X276775Y136250D01*
X275550Y135250D01*
X274150Y135000D01*
G01X284325D02*
Y150000D01*
X292375Y135000D01*
Y150000D01*
G01X313075Y137000D02*
X314475Y135750D01*
X316050Y135000D01*
X317450D01*
X318850Y135750D01*
X319900Y137000D01*
X320425Y138750D01*
X320075Y140500D01*
X319200Y142000D01*
X317625Y143000D01*
X315525Y143500D01*
X314300Y144500D01*
X313775Y146250D01*
X314125Y148000D01*
X315000Y149250D01*
X316225Y150000D01*
X317450D01*
X318675Y149500D01*
X319725Y148250D01*
G01X327275Y135000D02*
Y150000D01*
G01X334625D02*
Y135000D01*
G01Y142500D02*
X327275D01*
G01X345150Y135000D02*
X343750Y135250D01*
X342525Y136250D01*
X341475Y137750D01*
X340775Y139500D01*
X340425Y141500D01*
Y143500D01*
X340775Y145500D01*
X341475Y147250D01*
X342525Y148750D01*
X343750Y149750D01*
X345150Y150000D01*
X346550Y149750D01*
X347775Y148750D01*
X348825Y147250D01*
X349525Y145500D01*
X349875Y143500D01*
Y141500D01*
X349525Y139500D01*
X348825Y137750D01*
X347775Y136250D01*
X346550Y135250D01*
X345150Y135000D01*
G01X354100Y150000D02*
X356550Y135000D01*
X359350Y150000D01*
X362150Y135000D01*
X364600Y150000D01*
G01X371450D02*
X375650D01*
G01X373550D02*
Y135000D01*
G01X371450D02*
X375650D01*
G01X383725D02*
Y150000D01*
X391775Y135000D01*
Y150000D01*
G01X403000Y142500D02*
X406500D01*
Y138000D01*
X405450Y136500D01*
X404225Y135500D01*
X402475Y135000D01*
X400725Y135500D01*
X399500Y136500D01*
X398450Y138000D01*
X397750Y139750D01*
X397400Y141750D01*
Y143500D01*
X397750Y145000D01*
X398450Y146750D01*
X399500Y148250D01*
X400550Y149250D01*
X401950Y150000D01*
X403175D01*
X404575Y149500D01*
X405625Y148500D01*
G01X430350Y150000D02*
Y135000D01*
G01X426325Y150000D02*
X434375D01*
G01X440875Y135000D02*
Y150000D01*
G01X448225D02*
Y135000D01*
G01Y142500D02*
X440875D01*
G01X462250Y135000D02*
X455250D01*
Y150000D01*
X462250D01*
G01X459450Y142750D02*
X455250D01*
G01X483475Y137000D02*
X484875Y135750D01*
X486450Y135000D01*
X487850D01*
X489250Y135750D01*
X490300Y137000D01*
X490825Y138750D01*
X490475Y140500D01*
X489600Y142000D01*
X488025Y143000D01*
X485925Y143500D01*
X484700Y144500D01*
X484175Y146250D01*
X484525Y148000D01*
X485400Y149250D01*
X486625Y150000D01*
X487850D01*
X489075Y149500D01*
X490125Y148250D01*
G01X501350Y150000D02*
Y135000D01*
G01X497325Y150000D02*
X505375D01*
G01X511700D02*
Y139250D01*
X512400Y137000D01*
X513800Y135500D01*
X515550Y135000D01*
X517300Y135500D01*
X518700Y137000D01*
X519400Y139250D01*
Y150000D01*
G01X526425Y135000D02*
Y150000D01*
X533075D01*
G01X530625Y142750D02*
X526425D01*
G01X540625Y135000D02*
Y150000D01*
X547275D01*
G01X544825Y142750D02*
X540625D01*
G01X556050Y150000D02*
X560250D01*
G01X558150D02*
Y135000D01*
G01X556050D02*
X560250D01*
G01X568325D02*
Y150000D01*
X576375Y135000D01*
Y150000D01*
G01X587600Y142500D02*
X591100D01*
Y138000D01*
X590050Y136500D01*
X588825Y135500D01*
X587075Y135000D01*
X585325Y135500D01*
X584100Y136500D01*
X583050Y138000D01*
X582350Y139750D01*
X582000Y141750D01*
Y143500D01*
X582350Y145000D01*
X583050Y146750D01*
X584100Y148250D01*
X585150Y149250D01*
X586550Y150000D01*
X587775D01*
X589175Y149500D01*
X590225Y148500D01*
G01X610575Y135000D02*
X614950Y150000D01*
X619325Y135000D01*
G01X617750Y140250D02*
X612150D01*
G01X625650Y135000D02*
Y150000D01*
X630025D01*
X631425Y149250D01*
X632300Y148250D01*
X632650Y146250D01*
X632300Y144250D01*
X631250Y143000D01*
X630025Y142250D01*
X625650D01*
G01X630025D02*
X632650Y135000D01*
G01X646850D02*
X639850D01*
Y150000D01*
X646850D01*
G01X644050Y142750D02*
X639850D01*
G01X668250Y135000D02*
Y150000D01*
X672625D01*
X674025Y149250D01*
X674900Y148250D01*
X675250Y146250D01*
X674900Y144250D01*
X673850Y143000D01*
X672625Y142250D01*
X668250D01*
G01X672625D02*
X675250Y135000D01*
G01X689450D02*
X682450D01*
Y150000D01*
X689450D01*
G01X686650Y142750D02*
X682450D01*
G01X700150Y135000D02*
X698750Y135250D01*
X697525Y136250D01*
X696475Y137750D01*
X695775Y139500D01*
X695425Y141500D01*
Y143500D01*
X695775Y145500D01*
X696475Y147250D01*
X697525Y148750D01*
X698750Y149750D01*
X700150Y150000D01*
X701550Y149750D01*
X702775Y148750D01*
X703825Y147250D01*
X704525Y145500D01*
X704875Y143500D01*
Y141500D01*
X704525Y139500D01*
X703825Y137750D01*
X702775Y136250D01*
X701550Y135250D01*
X700150Y135000D01*
G01X701550Y139000D02*
X703650Y135000D01*
G01X710500Y150000D02*
Y139250D01*
X711200Y137000D01*
X712600Y135500D01*
X714350Y135000D01*
X716100Y135500D01*
X717500Y137000D01*
X718200Y139250D01*
Y150000D01*
G01X726450D02*
X730650D01*
G01X728550D02*
Y135000D01*
G01X726450D02*
X730650D01*
G01X739250D02*
Y150000D01*
X743625D01*
X745025Y149250D01*
X745900Y148250D01*
X746250Y146250D01*
X745900Y144250D01*
X744850Y143000D01*
X743625Y142250D01*
X739250D01*
G01X743625D02*
X746250Y135000D01*
G01X760450D02*
X753450D01*
Y150000D01*
X760450D01*
G01X757650Y142750D02*
X753450D01*
G01X767300Y135000D02*
Y150000D01*
X770800D01*
X772200Y149250D01*
X773250Y148250D01*
X774125Y146750D01*
X774825Y145000D01*
X775000Y142500D01*
X774825Y140000D01*
X774125Y138250D01*
X773250Y136750D01*
X772200Y135750D01*
X770800Y135000D01*
X767300D01*
G01X-222850Y180000D02*
Y165000D01*
G01X-226875Y180000D02*
X-218825D01*
G01X-208650Y165000D02*
X-210050Y165250D01*
X-211275Y166250D01*
X-212325Y167750D01*
X-213025Y169500D01*
X-213375Y171500D01*
Y173500D01*
X-213025Y175500D01*
X-212325Y177250D01*
X-211275Y178750D01*
X-210050Y179750D01*
X-208650Y180000D01*
X-207250Y179750D01*
X-206025Y178750D01*
X-204975Y177250D01*
X-204275Y175500D01*
X-203925Y173500D01*
Y171500D01*
X-204275Y169500D01*
X-204975Y167750D01*
X-206025Y166250D01*
X-207250Y165250D01*
X-208650Y165000D01*
G01X-194450Y180000D02*
Y165000D01*
G01X-198475Y180000D02*
X-190425D01*
G01X-184625Y165000D02*
X-180250Y180000D01*
X-175875Y165000D01*
G01X-177450Y170250D02*
X-183050D01*
G01X-169550Y180000D02*
Y165000D01*
X-162550D01*
G01X-150975Y160000D02*
X-149225Y162500D01*
X-148350Y165000D01*
Y175000D01*
X-149225Y177500D01*
X-150975Y180000D01*
G01X-137650Y164500D02*
X-138000Y164750D01*
Y165250D01*
X-137650Y165500D01*
X-137300Y165250D01*
Y164750D01*
X-137650Y164500D01*
G01X-109250Y180000D02*
Y165000D01*
G01X-113275Y180000D02*
X-105225D01*
G01X-98725Y165000D02*
Y180000D01*
G01X-91375D02*
Y165000D01*
G01Y172500D02*
X-98725D01*
G01X-77350Y165000D02*
X-84350D01*
Y180000D01*
X-77350D01*
G01X-80150Y172750D02*
X-84350D01*
G01X-66650Y165000D02*
Y171750D01*
X-70150Y180000D01*
G01X-63150D02*
X-66650Y171750D01*
G01X-41925Y165000D02*
Y180000D01*
G01X-34575D02*
Y165000D01*
G01Y172500D02*
X-41925D01*
G01X-28425Y165000D02*
X-24050Y180000D01*
X-19675Y165000D01*
G01X-21250Y170250D02*
X-26850D01*
G01X-14225Y180000D02*
X-9850Y165000D01*
X-5475Y180000D01*
G01X7850Y165000D02*
X850D01*
Y180000D01*
X7850D01*
G01X5050Y172750D02*
X850D01*
G01X32750Y180000D02*
Y165000D01*
G01X28725Y180000D02*
X36775D01*
G01X46950Y165000D02*
X45550Y165250D01*
X44325Y166250D01*
X43275Y167750D01*
X42575Y169500D01*
X42225Y171500D01*
Y173500D01*
X42575Y175500D01*
X43275Y177250D01*
X44325Y178750D01*
X45550Y179750D01*
X46950Y180000D01*
X48350Y179750D01*
X49575Y178750D01*
X50625Y177250D01*
X51325Y175500D01*
X51675Y173500D01*
Y171500D01*
X51325Y169500D01*
X50625Y167750D01*
X49575Y166250D01*
X48350Y165250D01*
X46950Y165000D01*
G01X76750Y173000D02*
X77450Y173750D01*
X77975Y175000D01*
X78325Y176750D01*
X77975Y178250D01*
X77275Y179250D01*
X76050Y180000D01*
X71325D01*
Y165000D01*
X77100D01*
X78325Y166000D01*
X79025Y167500D01*
X79375Y169250D01*
X79025Y171000D01*
X77975Y172500D01*
X76750Y173000D01*
X71325D01*
G01X93050Y165000D02*
X86050D01*
Y180000D01*
X93050D01*
G01X90250Y172750D02*
X86050D01*
G01X114450Y165000D02*
Y180000D01*
X118650D01*
X120050Y179250D01*
X121100Y177500D01*
X121450Y175500D01*
X121100Y173500D01*
X120225Y172000D01*
X118650Y171250D01*
X114450D01*
G01X130050Y180000D02*
X134250D01*
G01X132150D02*
Y165000D01*
G01X130050D02*
X134250D01*
G01X150200Y178750D02*
X149150Y179500D01*
X147925Y180000D01*
X146525D01*
X144950Y179250D01*
X143725Y178000D01*
X142850Y176500D01*
X142150Y174000D01*
X141975Y171750D01*
X142325Y169500D01*
X142850Y168000D01*
X143900Y166500D01*
X145125Y165500D01*
X146350Y165000D01*
X147575D01*
X148800Y165500D01*
X149850Y166250D01*
X150725Y167250D01*
G01X156700Y165000D02*
Y180000D01*
G01X163350D02*
X156700Y170750D01*
G01X164400Y165000D02*
X159675Y175000D01*
G01X178250Y165000D02*
X171250D01*
Y180000D01*
X178250D01*
G01X175450Y172750D02*
X171250D01*
G01X185100Y165000D02*
Y180000D01*
X188600D01*
X190000Y179250D01*
X191050Y178250D01*
X191925Y176750D01*
X192625Y175000D01*
X192800Y172500D01*
X192625Y170000D01*
X191925Y168250D01*
X191050Y166750D01*
X190000Y165750D01*
X188600Y165000D01*
X185100D01*
G01X214025D02*
Y180000D01*
X220675D01*
G01X218225Y172750D02*
X214025D01*
G01X228050Y165000D02*
Y180000D01*
X232425D01*
X233825Y179250D01*
X234700Y178250D01*
X235050Y176250D01*
X234700Y174250D01*
X233650Y173000D01*
X232425Y172250D01*
X228050D01*
G01X232425D02*
X235050Y165000D01*
G01X245750D02*
X244350Y165250D01*
X243125Y166250D01*
X242075Y167750D01*
X241375Y169500D01*
X241025Y171500D01*
Y173500D01*
X241375Y175500D01*
X242075Y177250D01*
X243125Y178750D01*
X244350Y179750D01*
X245750Y180000D01*
X247150Y179750D01*
X248375Y178750D01*
X249425Y177250D01*
X250125Y175500D01*
X250475Y173500D01*
Y171500D01*
X250125Y169500D01*
X249425Y167750D01*
X248375Y166250D01*
X247150Y165250D01*
X245750Y165000D01*
G01X255400D02*
Y180000D01*
X259950Y167500D01*
X264500Y180000D01*
Y165000D01*
G01X288350Y180000D02*
Y165000D01*
G01X284325Y180000D02*
X292375D01*
G01X306050Y165000D02*
X299050D01*
Y180000D01*
X306050D01*
G01X303250Y172750D02*
X299050D01*
G01X313075Y167000D02*
X314475Y165750D01*
X316050Y165000D01*
X317450D01*
X318850Y165750D01*
X319900Y167000D01*
X320425Y168750D01*
X320075Y170500D01*
X319200Y172000D01*
X317625Y173000D01*
X315525Y173500D01*
X314300Y174500D01*
X313775Y176250D01*
X314125Y178000D01*
X315000Y179250D01*
X316225Y180000D01*
X317450D01*
X318675Y179500D01*
X319725Y178250D01*
G01X330950Y180000D02*
Y165000D01*
G01X326925Y180000D02*
X334975D01*
G01X355850Y165000D02*
Y180000D01*
X360050D01*
X361450Y179250D01*
X362500Y177500D01*
X362850Y175500D01*
X362500Y173500D01*
X361625Y172000D01*
X360050Y171250D01*
X355850D01*
G01X369175Y165000D02*
X373550Y180000D01*
X377925Y165000D01*
G01X376350Y170250D02*
X370750D01*
G01X383900Y165000D02*
Y180000D01*
X387400D01*
X388800Y179250D01*
X389850Y178250D01*
X390725Y176750D01*
X391425Y175000D01*
X391600Y172500D01*
X391425Y170000D01*
X390725Y168250D01*
X389850Y166750D01*
X388800Y165750D01*
X387400Y165000D01*
X383900D01*
G01X411775Y180000D02*
X416150Y165000D01*
X420525Y180000D01*
G01X428250D02*
X432450D01*
G01X430350D02*
Y165000D01*
G01X428250D02*
X432450D01*
G01X440175D02*
X444550Y180000D01*
X448925Y165000D01*
G01X447350Y170250D02*
X441750D01*
G01X455075Y167000D02*
X456475Y165750D01*
X458050Y165000D01*
X459450D01*
X460850Y165750D01*
X461900Y167000D01*
X462425Y168750D01*
X462075Y170500D01*
X461200Y172000D01*
X459625Y173000D01*
X457525Y173500D01*
X456300Y174500D01*
X455775Y176250D01*
X456125Y178000D01*
X457000Y179250D01*
X458225Y180000D01*
X459450D01*
X460675Y179500D01*
X461725Y178250D01*
G01X487150Y180000D02*
Y165000D01*
G01X483125Y180000D02*
X491175D01*
G01X497675Y165000D02*
Y180000D01*
G01X505025D02*
Y165000D01*
G01Y172500D02*
X497675D01*
G01X511175Y165000D02*
X515550Y180000D01*
X519925Y165000D01*
G01X518350Y170250D02*
X512750D01*
G01X529750Y180000D02*
Y165000D01*
G01X525725Y180000D02*
X533775D01*
G01X553775Y165000D02*
X558150Y180000D01*
X562525Y165000D01*
G01X560950Y170250D02*
X555350D01*
G01X568850Y165000D02*
Y180000D01*
X573225D01*
X574625Y179250D01*
X575500Y178250D01*
X575850Y176250D01*
X575500Y174250D01*
X574450Y173000D01*
X573225Y172250D01*
X568850D01*
G01X573225D02*
X575850Y165000D01*
G01X590050D02*
X583050D01*
Y180000D01*
X590050D01*
G01X587250Y172750D02*
X583050D01*
G01X618800Y178750D02*
X617750Y179500D01*
X616525Y180000D01*
X615125D01*
X613550Y179250D01*
X612325Y178000D01*
X611450Y176500D01*
X610750Y174000D01*
X610575Y171750D01*
X610925Y169500D01*
X611450Y168000D01*
X612500Y166500D01*
X613725Y165500D01*
X614950Y165000D01*
X616175D01*
X617400Y165500D01*
X618450Y166250D01*
X619325Y167250D01*
G01X625650Y180000D02*
Y165000D01*
X632650D01*
G01X643350D02*
X641950Y165250D01*
X640725Y166250D01*
X639675Y167750D01*
X638975Y169500D01*
X638625Y171500D01*
Y173500D01*
X638975Y175500D01*
X639675Y177250D01*
X640725Y178750D01*
X641950Y179750D01*
X643350Y180000D01*
X644750Y179750D01*
X645975Y178750D01*
X647025Y177250D01*
X647725Y175500D01*
X648075Y173500D01*
Y171500D01*
X647725Y169500D01*
X647025Y167750D01*
X645975Y166250D01*
X644750Y165250D01*
X643350Y165000D01*
G01X653875Y167000D02*
X655275Y165750D01*
X656850Y165000D01*
X658250D01*
X659650Y165750D01*
X660700Y167000D01*
X661225Y168750D01*
X660875Y170500D01*
X660000Y172000D01*
X658425Y173000D01*
X656325Y173500D01*
X655100Y174500D01*
X654575Y176250D01*
X654925Y178000D01*
X655800Y179250D01*
X657025Y180000D01*
X658250D01*
X659475Y179500D01*
X660525Y178250D01*
G01X675250Y165000D02*
X668250D01*
Y180000D01*
X675250D01*
G01X672450Y172750D02*
X668250D01*
G01X700150Y180000D02*
Y165000D01*
G01X696125Y180000D02*
X704175D01*
G01X714350Y165000D02*
X712950Y165250D01*
X711725Y166250D01*
X710675Y167750D01*
X709975Y169500D01*
X709625Y171500D01*
Y173500D01*
X709975Y175500D01*
X710675Y177250D01*
X711725Y178750D01*
X712950Y179750D01*
X714350Y180000D01*
X715750Y179750D01*
X716975Y178750D01*
X718025Y177250D01*
X718725Y175500D01*
X719075Y173500D01*
Y171500D01*
X718725Y169500D01*
X718025Y167750D01*
X716975Y166250D01*
X715750Y165250D01*
X714350Y165000D01*
G01X746250D02*
X739250D01*
Y180000D01*
X746250D01*
G01X743450Y172750D02*
X739250D01*
G01X752575Y165000D02*
X756950Y180000D01*
X761325Y165000D01*
G01X759750Y170250D02*
X754150D01*
G01X775000Y178750D02*
X773950Y179500D01*
X772725Y180000D01*
X771325D01*
X769750Y179250D01*
X768525Y178000D01*
X767650Y176500D01*
X766950Y174000D01*
X766775Y171750D01*
X767125Y169500D01*
X767650Y168000D01*
X768700Y166500D01*
X769925Y165500D01*
X771150Y165000D01*
X772375D01*
X773600Y165500D01*
X774650Y166250D01*
X775525Y167250D01*
G01X781675Y165000D02*
Y180000D01*
G01X789025D02*
Y165000D01*
G01Y172500D02*
X781675D01*
G01X-276850Y203750D02*
X-278075Y204750D01*
X-279125Y205000D01*
X-280525Y204500D01*
X-281575Y203500D01*
X-282275Y201750D01*
X-282450Y200000D01*
X-282275Y198250D01*
X-281575Y196750D01*
X-280525Y195500D01*
X-279125Y195000D01*
X-277900Y195500D01*
X-276850Y196500D01*
G01X-265450Y194500D02*
X-265800Y194750D01*
Y195250D01*
X-265450Y195500D01*
X-265100Y195250D01*
Y194750D01*
X-265450Y194500D01*
G01X-219000Y208750D02*
X-220050Y209500D01*
X-221275Y210000D01*
X-222675D01*
X-224250Y209250D01*
X-225475Y208000D01*
X-226350Y206500D01*
X-227050Y204000D01*
X-227225Y201750D01*
X-226875Y199500D01*
X-226350Y198000D01*
X-225300Y196500D01*
X-224075Y195500D01*
X-222850Y195000D01*
X-221625D01*
X-220400Y195500D01*
X-219350Y196250D01*
X-218475Y197250D01*
G01X-212150Y195000D02*
Y210000D01*
X-207775D01*
X-206375Y209250D01*
X-205500Y208250D01*
X-205150Y206250D01*
X-205500Y204250D01*
X-206550Y203000D01*
X-207775Y202250D01*
X-212150D01*
G01X-207775D02*
X-205150Y195000D01*
G01X-194450D02*
X-195850Y195250D01*
X-197075Y196250D01*
X-198125Y197750D01*
X-198825Y199500D01*
X-199175Y201500D01*
Y203500D01*
X-198825Y205500D01*
X-198125Y207250D01*
X-197075Y208750D01*
X-195850Y209750D01*
X-194450Y210000D01*
X-193050Y209750D01*
X-191825Y208750D01*
X-190775Y207250D01*
X-190075Y205500D01*
X-189725Y203500D01*
Y201500D01*
X-190075Y199500D01*
X-190775Y197750D01*
X-191825Y196250D01*
X-193050Y195250D01*
X-194450Y195000D01*
G01X-183925Y197000D02*
X-182525Y195750D01*
X-180950Y195000D01*
X-179550D01*
X-178150Y195750D01*
X-177100Y197000D01*
X-176575Y198750D01*
X-176925Y200500D01*
X-177800Y202000D01*
X-179375Y203000D01*
X-181475Y203500D01*
X-182700Y204500D01*
X-183225Y206250D01*
X-182875Y208000D01*
X-182000Y209250D01*
X-180775Y210000D01*
X-179550D01*
X-178325Y209500D01*
X-177275Y208250D01*
G01X-169725Y197000D02*
X-168325Y195750D01*
X-166750Y195000D01*
X-165350D01*
X-163950Y195750D01*
X-162900Y197000D01*
X-162375Y198750D01*
X-162725Y200500D01*
X-163600Y202000D01*
X-165175Y203000D01*
X-167275Y203500D01*
X-168500Y204500D01*
X-169025Y206250D01*
X-168675Y208000D01*
X-167800Y209250D01*
X-166575Y210000D01*
X-165350D01*
X-164125Y209500D01*
X-163075Y208250D01*
G01X-141325Y197000D02*
X-139925Y195750D01*
X-138350Y195000D01*
X-136950D01*
X-135550Y195750D01*
X-134500Y197000D01*
X-133975Y198750D01*
X-134325Y200500D01*
X-135200Y202000D01*
X-136775Y203000D01*
X-138875Y203500D01*
X-140100Y204500D01*
X-140625Y206250D01*
X-140275Y208000D01*
X-139400Y209250D01*
X-138175Y210000D01*
X-136950D01*
X-135725Y209500D01*
X-134675Y208250D01*
G01X-119950Y195000D02*
X-126950D01*
Y210000D01*
X-119950D01*
G01X-122750Y202750D02*
X-126950D01*
G01X-105400Y208750D02*
X-106450Y209500D01*
X-107675Y210000D01*
X-109075D01*
X-110650Y209250D01*
X-111875Y208000D01*
X-112750Y206500D01*
X-113450Y204000D01*
X-113625Y201750D01*
X-113275Y199500D01*
X-112750Y198000D01*
X-111700Y196500D01*
X-110475Y195500D01*
X-109250Y195000D01*
X-108025D01*
X-106800Y195500D01*
X-105750Y196250D01*
X-104875Y197250D01*
G01X-95050Y210000D02*
Y195000D01*
G01X-99075Y210000D02*
X-91025D01*
G01X-82950D02*
X-78750D01*
G01X-80850D02*
Y195000D01*
G01X-82950D02*
X-78750D01*
G01X-66650D02*
X-68050Y195250D01*
X-69275Y196250D01*
X-70325Y197750D01*
X-71025Y199500D01*
X-71375Y201500D01*
Y203500D01*
X-71025Y205500D01*
X-70325Y207250D01*
X-69275Y208750D01*
X-68050Y209750D01*
X-66650Y210000D01*
X-65250Y209750D01*
X-64025Y208750D01*
X-62975Y207250D01*
X-62275Y205500D01*
X-61925Y203500D01*
Y201500D01*
X-62275Y199500D01*
X-62975Y197750D01*
X-64025Y196250D01*
X-65250Y195250D01*
X-66650Y195000D01*
G01X-56475D02*
Y210000D01*
X-48425Y195000D01*
Y210000D01*
G01X-28425Y195000D02*
X-24050Y210000D01*
X-19675Y195000D01*
G01X-21250Y200250D02*
X-26850D01*
G01X4350Y210000D02*
Y195000D01*
G01X325Y210000D02*
X8375D01*
G01X22050Y195000D02*
X15050D01*
Y210000D01*
X22050D01*
G01X19250Y202750D02*
X15050D01*
G01X29075Y197000D02*
X30475Y195750D01*
X32050Y195000D01*
X33450D01*
X34850Y195750D01*
X35900Y197000D01*
X36425Y198750D01*
X36075Y200500D01*
X35200Y202000D01*
X33625Y203000D01*
X31525Y203500D01*
X30300Y204500D01*
X29775Y206250D01*
X30125Y208000D01*
X31000Y209250D01*
X32225Y210000D01*
X33450D01*
X34675Y209500D01*
X35725Y208250D01*
G01X46950Y210000D02*
Y195000D01*
G01X42925Y210000D02*
X50975D01*
G01X71850Y195000D02*
Y210000D01*
X76050D01*
X77450Y209250D01*
X78500Y207500D01*
X78850Y205500D01*
X78500Y203500D01*
X77625Y202000D01*
X76050Y201250D01*
X71850D01*
G01X85175Y195000D02*
X89550Y210000D01*
X93925Y195000D01*
G01X92350Y200250D02*
X86750D01*
G01X99900Y195000D02*
Y210000D01*
X103400D01*
X104800Y209250D01*
X105850Y208250D01*
X106725Y206750D01*
X107425Y205000D01*
X107600Y202500D01*
X107425Y200000D01*
X106725Y198250D01*
X105850Y196750D01*
X104800Y195750D01*
X103400Y195000D01*
X99900D01*
G01X127775Y210000D02*
X132150Y195000D01*
X136525Y210000D01*
G01X144250D02*
X148450D01*
G01X146350D02*
Y195000D01*
G01X144250D02*
X148450D01*
G01X156175D02*
X160550Y210000D01*
X164925Y195000D01*
G01X163350Y200250D02*
X157750D01*
G01X185625Y195000D02*
Y210000D01*
X192275D01*
G01X189825Y202750D02*
X185625D01*
G01X199650Y195000D02*
Y210000D01*
X204025D01*
X205425Y209250D01*
X206300Y208250D01*
X206650Y206250D01*
X206300Y204250D01*
X205250Y203000D01*
X204025Y202250D01*
X199650D01*
G01X204025D02*
X206650Y195000D01*
G01X217350D02*
X215950Y195250D01*
X214725Y196250D01*
X213675Y197750D01*
X212975Y199500D01*
X212625Y201500D01*
Y203500D01*
X212975Y205500D01*
X213675Y207250D01*
X214725Y208750D01*
X215950Y209750D01*
X217350Y210000D01*
X218750Y209750D01*
X219975Y208750D01*
X221025Y207250D01*
X221725Y205500D01*
X222075Y203500D01*
Y201500D01*
X221725Y199500D01*
X221025Y197750D01*
X219975Y196250D01*
X218750Y195250D01*
X217350Y195000D01*
G01X227000D02*
Y210000D01*
X231550Y197500D01*
X236100Y210000D01*
Y195000D01*
G01X263450D02*
X256450D01*
Y210000D01*
X263450D01*
G01X260650Y202750D02*
X256450D01*
G01X269775Y195000D02*
X274150Y210000D01*
X278525Y195000D01*
G01X276950Y200250D02*
X271350D01*
G01X292200Y208750D02*
X291150Y209500D01*
X289925Y210000D01*
X288525D01*
X286950Y209250D01*
X285725Y208000D01*
X284850Y206500D01*
X284150Y204000D01*
X283975Y201750D01*
X284325Y199500D01*
X284850Y198000D01*
X285900Y196500D01*
X287125Y195500D01*
X288350Y195000D01*
X289575D01*
X290800Y195500D01*
X291850Y196250D01*
X292725Y197250D01*
G01X298875Y195000D02*
Y210000D01*
G01X306225D02*
Y195000D01*
G01Y202500D02*
X298875D01*
G01X334800Y208750D02*
X333750Y209500D01*
X332525Y210000D01*
X331125D01*
X329550Y209250D01*
X328325Y208000D01*
X327450Y206500D01*
X326750Y204000D01*
X326575Y201750D01*
X326925Y199500D01*
X327450Y198000D01*
X328500Y196500D01*
X329725Y195500D01*
X330950Y195000D01*
X332175D01*
X333400Y195500D01*
X334450Y196250D01*
X335325Y197250D01*
G01X345150Y195000D02*
X343750Y195250D01*
X342525Y196250D01*
X341475Y197750D01*
X340775Y199500D01*
X340425Y201500D01*
Y203500D01*
X340775Y205500D01*
X341475Y207250D01*
X342525Y208750D01*
X343750Y209750D01*
X345150Y210000D01*
X346550Y209750D01*
X347775Y208750D01*
X348825Y207250D01*
X349525Y205500D01*
X349875Y203500D01*
Y201500D01*
X349525Y199500D01*
X348825Y197750D01*
X347775Y196250D01*
X346550Y195250D01*
X345150Y195000D01*
G01X355850D02*
Y210000D01*
X360225D01*
X361625Y209250D01*
X362500Y208250D01*
X362850Y206250D01*
X362500Y204250D01*
X361450Y203000D01*
X360225Y202250D01*
X355850D01*
G01X360225D02*
X362850Y195000D01*
G01X369525D02*
Y210000D01*
X377575Y195000D01*
Y210000D01*
G01X391250Y195000D02*
X384250D01*
Y210000D01*
X391250D01*
G01X388450Y202750D02*
X384250D01*
G01X398450Y195000D02*
Y210000D01*
X402825D01*
X404225Y209250D01*
X405100Y208250D01*
X405450Y206250D01*
X405100Y204250D01*
X404050Y203000D01*
X402825Y202250D01*
X398450D01*
G01X402825D02*
X405450Y195000D01*
G01X430350D02*
X428950Y195250D01*
X427725Y196250D01*
X426675Y197750D01*
X425975Y199500D01*
X425625Y201500D01*
Y203500D01*
X425975Y205500D01*
X426675Y207250D01*
X427725Y208750D01*
X428950Y209750D01*
X430350Y210000D01*
X431750Y209750D01*
X432975Y208750D01*
X434025Y207250D01*
X434725Y205500D01*
X435075Y203500D01*
Y201500D01*
X434725Y199500D01*
X434025Y197750D01*
X432975Y196250D01*
X431750Y195250D01*
X430350Y195000D01*
G01X441225D02*
Y210000D01*
X447875D01*
G01X445425Y202750D02*
X441225D01*
G01X472950Y195000D02*
X471550Y195250D01*
X470325Y196250D01*
X469275Y197750D01*
X468575Y199500D01*
X468225Y201500D01*
Y203500D01*
X468575Y205500D01*
X469275Y207250D01*
X470325Y208750D01*
X471550Y209750D01*
X472950Y210000D01*
X474350Y209750D01*
X475575Y208750D01*
X476625Y207250D01*
X477325Y205500D01*
X477675Y203500D01*
Y201500D01*
X477325Y199500D01*
X476625Y197750D01*
X475575Y196250D01*
X474350Y195250D01*
X472950Y195000D01*
G01X483125D02*
Y210000D01*
X491175Y195000D01*
Y210000D01*
G01X504850Y195000D02*
X497850D01*
Y210000D01*
X504850D01*
G01X502050Y202750D02*
X497850D01*
G01X526250Y195000D02*
Y210000D01*
X530450D01*
X531850Y209250D01*
X532900Y207500D01*
X533250Y205500D01*
X532900Y203500D01*
X532025Y202000D01*
X530450Y201250D01*
X526250D01*
G01X547800Y208750D02*
X546750Y209500D01*
X545525Y210000D01*
X544125D01*
X542550Y209250D01*
X541325Y208000D01*
X540450Y206500D01*
X539750Y204000D01*
X539575Y201750D01*
X539925Y199500D01*
X540450Y198000D01*
X541500Y196500D01*
X542725Y195500D01*
X543950Y195000D01*
X545175D01*
X546400Y195500D01*
X547450Y196250D01*
X548325Y197250D01*
G01X559550Y203000D02*
X560250Y203750D01*
X560775Y205000D01*
X561125Y206750D01*
X560775Y208250D01*
X560075Y209250D01*
X558850Y210000D01*
X554125D01*
Y195000D01*
X559900D01*
X561125Y196000D01*
X561825Y197500D01*
X562175Y199250D01*
X561825Y201000D01*
X560775Y202500D01*
X559550Y203000D01*
X554125D01*
G01X585675Y190000D02*
X583925Y192500D01*
X583050Y195000D01*
Y205000D01*
X583925Y207500D01*
X585675Y210000D01*
G01X602850Y195000D02*
Y210000D01*
X596375Y199250D01*
X605125D01*
G01X629150Y210000D02*
Y195000D01*
G01X625125Y210000D02*
X633175D01*
G01X646850Y195000D02*
X639850D01*
Y210000D01*
X646850D01*
G01X644050Y202750D02*
X639850D01*
G01X653875Y197000D02*
X655275Y195750D01*
X656850Y195000D01*
X658250D01*
X659650Y195750D01*
X660700Y197000D01*
X661225Y198750D01*
X660875Y200500D01*
X660000Y202000D01*
X658425Y203000D01*
X656325Y203500D01*
X655100Y204500D01*
X654575Y206250D01*
X654925Y208000D01*
X655800Y209250D01*
X657025Y210000D01*
X658250D01*
X659475Y209500D01*
X660525Y208250D01*
G01X671750Y210000D02*
Y195000D01*
G01X667725Y210000D02*
X675775D01*
G01X696650Y195000D02*
Y210000D01*
X700850D01*
X702250Y209250D01*
X703300Y207500D01*
X703650Y205500D01*
X703300Y203500D01*
X702425Y202000D01*
X700850Y201250D01*
X696650D01*
G01X709975Y195000D02*
X714350Y210000D01*
X718725Y195000D01*
G01X717150Y200250D02*
X711550D01*
G01X724700Y195000D02*
Y210000D01*
X728200D01*
X729600Y209250D01*
X730650Y208250D01*
X731525Y206750D01*
X732225Y205000D01*
X732400Y202500D01*
X732225Y200000D01*
X731525Y198250D01*
X730650Y196750D01*
X729600Y195750D01*
X728200Y195000D01*
X724700D01*
G01X739075Y197000D02*
X740475Y195750D01*
X742050Y195000D01*
X743450D01*
X744850Y195750D01*
X745900Y197000D01*
X746425Y198750D01*
X746075Y200500D01*
X745200Y202000D01*
X743625Y203000D01*
X741525Y203500D01*
X740300Y204500D01*
X739775Y206250D01*
X740125Y208000D01*
X741000Y209250D01*
X742225Y210000D01*
X743450D01*
X744675Y209500D01*
X745725Y208250D01*
G01X766775Y210000D02*
X771150Y195000D01*
X775525Y210000D01*
G01X783250D02*
X787450D01*
G01X785350D02*
Y195000D01*
G01X783250D02*
X787450D01*
G01X795175D02*
X799550Y210000D01*
X803925Y195000D01*
G01X802350Y200250D02*
X796750D01*
G01X810075Y197000D02*
X811475Y195750D01*
X813050Y195000D01*
X814450D01*
X815850Y195750D01*
X816900Y197000D01*
X817425Y198750D01*
X817075Y200500D01*
X816200Y202000D01*
X814625Y203000D01*
X812525Y203500D01*
X811300Y204500D01*
X810775Y206250D01*
X811125Y208000D01*
X812000Y209250D01*
X813225Y210000D01*
X814450D01*
X815675Y209500D01*
X816725Y208250D01*
G01X-226525Y225000D02*
Y240000D01*
G01X-219175D02*
Y225000D01*
G01Y232500D02*
X-226525D01*
G01X-213025Y225000D02*
X-208650Y240000D01*
X-204275Y225000D01*
G01X-205850Y230250D02*
X-211450D01*
G01X-198125Y227000D02*
X-196725Y225750D01*
X-195150Y225000D01*
X-193750D01*
X-192350Y225750D01*
X-191300Y227000D01*
X-190775Y228750D01*
X-191125Y230500D01*
X-192000Y232000D01*
X-193575Y233000D01*
X-195675Y233500D01*
X-196900Y234500D01*
X-197425Y236250D01*
X-197075Y238000D01*
X-196200Y239250D01*
X-194975Y240000D01*
X-193750D01*
X-192525Y239500D01*
X-191475Y238250D01*
G01X-166050Y240000D02*
Y225000D01*
G01X-170075Y240000D02*
X-162025D01*
G01X-151850Y225000D02*
X-153250Y225250D01*
X-154475Y226250D01*
X-155525Y227750D01*
X-156225Y229500D01*
X-156575Y231500D01*
Y233500D01*
X-156225Y235500D01*
X-155525Y237250D01*
X-154475Y238750D01*
X-153250Y239750D01*
X-151850Y240000D01*
X-150450Y239750D01*
X-149225Y238750D01*
X-148175Y237250D01*
X-147475Y235500D01*
X-147125Y233500D01*
Y231500D01*
X-147475Y229500D01*
X-148175Y227750D01*
X-149225Y226250D01*
X-150450Y225250D01*
X-151850Y225000D01*
G01X-122050Y233000D02*
X-121350Y233750D01*
X-120825Y235000D01*
X-120475Y236750D01*
X-120825Y238250D01*
X-121525Y239250D01*
X-122750Y240000D01*
X-127475D01*
Y225000D01*
X-121700D01*
X-120475Y226000D01*
X-119775Y227500D01*
X-119425Y229250D01*
X-119775Y231000D01*
X-120825Y232500D01*
X-122050Y233000D01*
X-127475D01*
G01X-105750Y225000D02*
X-112750D01*
Y240000D01*
X-105750D01*
G01X-108550Y232750D02*
X-112750D01*
G01X-79800Y232500D02*
X-76300D01*
Y228000D01*
X-77350Y226500D01*
X-78575Y225500D01*
X-80325Y225000D01*
X-82075Y225500D01*
X-83300Y226500D01*
X-84350Y228000D01*
X-85050Y229750D01*
X-85400Y231750D01*
Y233500D01*
X-85050Y235000D01*
X-84350Y236750D01*
X-83300Y238250D01*
X-82250Y239250D01*
X-80850Y240000D01*
X-79625D01*
X-78225Y239500D01*
X-77175Y238500D01*
G01X-70150Y225000D02*
Y240000D01*
X-65775D01*
X-64375Y239250D01*
X-63500Y238250D01*
X-63150Y236250D01*
X-63500Y234250D01*
X-64550Y233000D01*
X-65775Y232250D01*
X-70150D01*
G01X-65775D02*
X-63150Y225000D01*
G01X-48950D02*
X-55950D01*
Y240000D01*
X-48950D01*
G01X-51750Y232750D02*
X-55950D01*
G01X-42625Y225000D02*
X-38250Y240000D01*
X-33875Y225000D01*
G01X-35450Y230250D02*
X-41050D01*
G01X-24050Y240000D02*
Y225000D01*
G01X-28075Y240000D02*
X-20025D01*
G01X-6350Y225000D02*
X-13350D01*
Y240000D01*
X-6350D01*
G01X-9150Y232750D02*
X-13350D01*
G01X850Y225000D02*
Y240000D01*
X5225D01*
X6625Y239250D01*
X7500Y238250D01*
X7850Y236250D01*
X7500Y234250D01*
X6450Y233000D01*
X5225Y232250D01*
X850D01*
G01X5225D02*
X7850Y225000D01*
G01X32750Y240000D02*
Y225000D01*
G01X28725Y240000D02*
X36775D01*
G01X43275Y225000D02*
Y240000D01*
G01X50625D02*
Y225000D01*
G01Y232500D02*
X43275D01*
G01X56775Y225000D02*
X61150Y240000D01*
X65525Y225000D01*
G01X63950Y230250D02*
X58350D01*
G01X71325Y225000D02*
Y240000D01*
X79375Y225000D01*
Y240000D01*
G01X103750Y224500D02*
X103400Y224750D01*
Y225250D01*
X103750Y225500D01*
X104100Y225250D01*
Y224750D01*
X103750Y224500D01*
G01X117950Y225000D02*
Y240000D01*
X115850Y237000D01*
G01Y225000D02*
X120050D01*
G01X134250D02*
Y240000D01*
X127775Y229250D01*
X136525D01*
G01X142500Y227250D02*
X143550Y226000D01*
X144775Y225250D01*
X146350Y225000D01*
X147925Y225500D01*
X149150Y226500D01*
X150025Y228250D01*
X150200Y230250D01*
X149850Y232250D01*
X148975Y233500D01*
X147750Y234500D01*
X146525Y234750D01*
X145300Y234500D01*
X143725Y233500D01*
X144250Y240000D01*
X148975D01*
G01X160550Y224500D02*
X160200Y224750D01*
Y225250D01*
X160550Y225500D01*
X160900Y225250D01*
Y224750D01*
X160550Y224500D01*
G01X-282800Y255000D02*
Y270000D01*
G01Y262500D02*
X-281925Y264000D01*
X-280875Y264750D01*
X-279825Y265000D01*
X-278250Y264500D01*
X-277200Y263500D01*
X-276500Y261750D01*
Y259750D01*
X-276850Y257750D01*
X-277550Y256250D01*
X-278775Y255250D01*
X-279825Y255000D01*
X-280875Y255250D01*
X-281925Y256000D01*
X-282800Y257250D01*
G01X-265450Y254500D02*
X-265800Y254750D01*
Y255250D01*
X-265450Y255500D01*
X-265100Y255250D01*
Y254750D01*
X-265450Y254500D01*
G01X-227400Y255000D02*
Y270000D01*
X-222850Y257500D01*
X-218300Y270000D01*
Y255000D01*
G01X-205150D02*
X-212150D01*
Y270000D01*
X-205150D01*
G01X-207950Y262750D02*
X-212150D01*
G01X-198825Y255000D02*
X-194450Y270000D01*
X-190075Y255000D01*
G01X-191650Y260250D02*
X-197250D01*
G01X-183925Y257000D02*
X-182525Y255750D01*
X-180950Y255000D01*
X-179550D01*
X-178150Y255750D01*
X-177100Y257000D01*
X-176575Y258750D01*
X-176925Y260500D01*
X-177800Y262000D01*
X-179375Y263000D01*
X-181475Y263500D01*
X-182700Y264500D01*
X-183225Y266250D01*
X-182875Y268000D01*
X-182000Y269250D01*
X-180775Y270000D01*
X-179550D01*
X-178325Y269500D01*
X-177275Y268250D01*
G01X-169900Y270000D02*
Y259250D01*
X-169200Y257000D01*
X-167800Y255500D01*
X-166050Y255000D01*
X-164300Y255500D01*
X-162900Y257000D01*
X-162200Y259250D01*
Y270000D01*
G01X-155350Y255000D02*
Y270000D01*
X-150975D01*
X-149575Y269250D01*
X-148700Y268250D01*
X-148350Y266250D01*
X-148700Y264250D01*
X-149750Y263000D01*
X-150975Y262250D01*
X-155350D01*
G01X-150975D02*
X-148350Y255000D01*
G01X-134150D02*
X-141150D01*
Y270000D01*
X-134150D01*
G01X-136950Y262750D02*
X-141150D01*
G01X-109250Y270000D02*
Y255000D01*
G01X-113275Y270000D02*
X-105225D01*
G01X-98725Y255000D02*
Y270000D01*
G01X-91375D02*
Y255000D01*
G01Y262500D02*
X-98725D01*
G01X-77350Y255000D02*
X-84350D01*
Y270000D01*
X-77350D01*
G01X-80150Y262750D02*
X-84350D01*
G01X-52450Y270000D02*
Y255000D01*
G01X-56475Y270000D02*
X-48425D01*
G01X-40700Y251250D02*
X-39475Y250250D01*
X-38075Y250000D01*
X-36850Y250250D01*
X-35800Y251500D01*
X-35100Y253250D01*
Y265000D01*
G01Y263000D02*
X-35800Y264000D01*
X-36850Y264750D01*
X-38075Y265000D01*
X-39475Y264500D01*
X-40350Y263500D01*
X-41050Y261750D01*
X-41400Y260000D01*
X-41225Y258500D01*
X-40525Y256750D01*
X-39475Y255500D01*
X-38075Y255000D01*
X-37025Y255250D01*
X-35800Y256250D01*
X-35100Y257250D01*
G01X-9850Y255000D02*
X-11250Y255250D01*
X-12475Y256250D01*
X-13525Y257750D01*
X-14225Y259500D01*
X-14575Y261500D01*
Y263500D01*
X-14225Y265500D01*
X-13525Y267250D01*
X-12475Y268750D01*
X-11250Y269750D01*
X-9850Y270000D01*
X-8450Y269750D01*
X-7225Y268750D01*
X-6175Y267250D01*
X-5475Y265500D01*
X-5125Y263500D01*
Y261500D01*
X-5475Y259500D01*
X-6175Y257750D01*
X-7225Y256250D01*
X-8450Y255250D01*
X-9850Y255000D01*
G01X1025D02*
Y270000D01*
X7675D01*
G01X5225Y262750D02*
X1025D01*
G01X28375Y255000D02*
X32750Y270000D01*
X37125Y255000D01*
G01X35550Y260250D02*
X29950D01*
G01X57650Y255000D02*
Y270000D01*
X61850D01*
X63250Y269250D01*
X64300Y267500D01*
X64650Y265500D01*
X64300Y263500D01*
X63425Y262000D01*
X61850Y261250D01*
X57650D01*
G01X73250Y270000D02*
X77450D01*
G01X75350D02*
Y255000D01*
G01X73250D02*
X77450D01*
G01X93050D02*
X86050D01*
Y270000D01*
X93050D01*
G01X90250Y262750D02*
X86050D01*
G01X107600Y268750D02*
X106550Y269500D01*
X105325Y270000D01*
X103925D01*
X102350Y269250D01*
X101125Y268000D01*
X100250Y266500D01*
X99550Y264000D01*
X99375Y261750D01*
X99725Y259500D01*
X100250Y258000D01*
X101300Y256500D01*
X102525Y255500D01*
X103750Y255000D01*
X104975D01*
X106200Y255500D01*
X107250Y256250D01*
X108125Y257250D01*
G01X121450Y255000D02*
X114450D01*
Y270000D01*
X121450D01*
G01X118650Y262750D02*
X114450D01*
G01X146350Y255000D02*
X144950Y255250D01*
X143725Y256250D01*
X142675Y257750D01*
X141975Y259500D01*
X141625Y261500D01*
Y263500D01*
X141975Y265500D01*
X142675Y267250D01*
X143725Y268750D01*
X144950Y269750D01*
X146350Y270000D01*
X147750Y269750D01*
X148975Y268750D01*
X150025Y267250D01*
X150725Y265500D01*
X151075Y263500D01*
Y261500D01*
X150725Y259500D01*
X150025Y257750D01*
X148975Y256250D01*
X147750Y255250D01*
X146350Y255000D01*
G01X157225D02*
Y270000D01*
X163875D01*
G01X161425Y262750D02*
X157225D01*
G01X184400Y255000D02*
Y270000D01*
X188950Y257500D01*
X193500Y270000D01*
Y255000D01*
G01X198775D02*
X203150Y270000D01*
X207525Y255000D01*
G01X205950Y260250D02*
X200350D01*
G01X217350Y270000D02*
Y255000D01*
G01X213325Y270000D02*
X221375D01*
G01X235050Y255000D02*
X228050D01*
Y270000D01*
X235050D01*
G01X232250Y262750D02*
X228050D01*
G01X242250Y255000D02*
Y270000D01*
X246625D01*
X248025Y269250D01*
X248900Y268250D01*
X249250Y266250D01*
X248900Y264250D01*
X247850Y263000D01*
X246625Y262250D01*
X242250D01*
G01X246625D02*
X249250Y255000D01*
G01X257850Y270000D02*
X262050D01*
G01X259950D02*
Y255000D01*
G01X257850D02*
X262050D01*
G01X269775D02*
X274150Y270000D01*
X278525Y255000D01*
G01X276950Y260250D02*
X271350D01*
G01X284850Y270000D02*
Y255000D01*
X291850D01*
G01X313425D02*
Y270000D01*
X320075D01*
G01X317625Y262750D02*
X313425D01*
G01X327450Y255000D02*
Y270000D01*
X331825D01*
X333225Y269250D01*
X334100Y268250D01*
X334450Y266250D01*
X334100Y264250D01*
X333050Y263000D01*
X331825Y262250D01*
X327450D01*
G01X331825D02*
X334450Y255000D01*
G01X345150D02*
X343750Y255250D01*
X342525Y256250D01*
X341475Y257750D01*
X340775Y259500D01*
X340425Y261500D01*
Y263500D01*
X340775Y265500D01*
X341475Y267250D01*
X342525Y268750D01*
X343750Y269750D01*
X345150Y270000D01*
X346550Y269750D01*
X347775Y268750D01*
X348825Y267250D01*
X349525Y265500D01*
X349875Y263500D01*
Y261500D01*
X349525Y259500D01*
X348825Y257750D01*
X347775Y256250D01*
X346550Y255250D01*
X345150Y255000D01*
G01X354800D02*
Y270000D01*
X359350Y257500D01*
X363900Y270000D01*
Y255000D01*
G01X387750Y270000D02*
Y255000D01*
G01X383725Y270000D02*
X391775D01*
G01X398275Y255000D02*
Y270000D01*
G01X405625D02*
Y255000D01*
G01Y262500D02*
X398275D01*
G01X419650Y255000D02*
X412650D01*
Y270000D01*
X419650D01*
G01X416850Y262750D02*
X412650D01*
G01X445950Y263000D02*
X446650Y263750D01*
X447175Y265000D01*
X447525Y266750D01*
X447175Y268250D01*
X446475Y269250D01*
X445250Y270000D01*
X440525D01*
Y255000D01*
X446300D01*
X447525Y256000D01*
X448225Y257500D01*
X448575Y259250D01*
X448225Y261000D01*
X447175Y262500D01*
X445950Y263000D01*
X440525D01*
G01X458750Y255000D02*
X457350Y255250D01*
X456125Y256250D01*
X455075Y257750D01*
X454375Y259500D01*
X454025Y261500D01*
Y263500D01*
X454375Y265500D01*
X455075Y267250D01*
X456125Y268750D01*
X457350Y269750D01*
X458750Y270000D01*
X460150Y269750D01*
X461375Y268750D01*
X462425Y267250D01*
X463125Y265500D01*
X463475Y263500D01*
Y261500D01*
X463125Y259500D01*
X462425Y257750D01*
X461375Y256250D01*
X460150Y255250D01*
X458750Y255000D01*
G01X468575D02*
X472950Y270000D01*
X477325Y255000D01*
G01X475750Y260250D02*
X470150D01*
G01X483650Y255000D02*
Y270000D01*
X488025D01*
X489425Y269250D01*
X490300Y268250D01*
X490650Y266250D01*
X490300Y264250D01*
X489250Y263000D01*
X488025Y262250D01*
X483650D01*
G01X488025D02*
X490650Y255000D01*
G01X497500D02*
Y270000D01*
X501000D01*
X502400Y269250D01*
X503450Y268250D01*
X504325Y266750D01*
X505025Y265000D01*
X505200Y262500D01*
X505025Y260000D01*
X504325Y258250D01*
X503450Y256750D01*
X502400Y255750D01*
X501000Y255000D01*
X497500D01*
G01X526250D02*
Y270000D01*
X530450D01*
X531850Y269250D01*
X532900Y267500D01*
X533250Y265500D01*
X532900Y263500D01*
X532025Y262000D01*
X530450Y261250D01*
X526250D01*
G01X539575Y255000D02*
X543950Y270000D01*
X548325Y255000D01*
G01X546750Y260250D02*
X541150D01*
G01X554125Y255000D02*
Y270000D01*
X562175Y255000D01*
Y270000D01*
G01X575850Y255000D02*
X568850D01*
Y270000D01*
X575850D01*
G01X573050Y262750D02*
X568850D01*
G01X583050Y270000D02*
Y255000D01*
X590050D01*
G01X600750Y254500D02*
X600400Y254750D01*
Y255250D01*
X600750Y255500D01*
X601100Y255250D01*
Y254750D01*
X600750Y254500D01*
G01X629150Y270000D02*
Y255000D01*
G01X625125Y270000D02*
X633175D01*
G01X639675Y255000D02*
Y270000D01*
G01X647025D02*
Y255000D01*
G01Y262500D02*
X639675D01*
G01X661050Y255000D02*
X654050D01*
Y270000D01*
X661050D01*
G01X658250Y262750D02*
X654050D01*
G01X685950Y270000D02*
Y255000D01*
G01X681925Y270000D02*
X689975D01*
G01X697700Y251250D02*
X698925Y250250D01*
X700325Y250000D01*
X701550Y250250D01*
X702600Y251500D01*
X703300Y253250D01*
Y265000D01*
G01Y263000D02*
X702600Y264000D01*
X701550Y264750D01*
X700325Y265000D01*
X698925Y264500D01*
X698050Y263500D01*
X697350Y261750D01*
X697000Y260000D01*
X697175Y258500D01*
X697875Y256750D01*
X698925Y255500D01*
X700325Y255000D01*
X701375Y255250D01*
X702600Y256250D01*
X703300Y257250D01*
G01X724175Y270000D02*
X728550Y255000D01*
X732925Y270000D01*
G01X738375Y255000D02*
X742750Y270000D01*
X747125Y255000D01*
G01X745550Y260250D02*
X739950D01*
G01X753450Y270000D02*
Y255000D01*
X760450D01*
G01X767300Y270000D02*
Y259250D01*
X768000Y257000D01*
X769400Y255500D01*
X771150Y255000D01*
X772900Y255500D01*
X774300Y257000D01*
X775000Y259250D01*
Y270000D01*
G01X788850Y255000D02*
X781850D01*
Y270000D01*
X788850D01*
G01X786050Y262750D02*
X781850D01*
G01X-156225Y285000D02*
X-151850Y300000D01*
X-147475Y285000D01*
G01X-149050Y290250D02*
X-154650D01*
G01X-141675Y285000D02*
Y300000D01*
X-133625Y285000D01*
Y300000D01*
G01X-127300Y285000D02*
Y300000D01*
X-123800D01*
X-122400Y299250D01*
X-121350Y298250D01*
X-120475Y296750D01*
X-119775Y295000D01*
X-119600Y292500D01*
X-119775Y290000D01*
X-120475Y288250D01*
X-121350Y286750D01*
X-122400Y285750D01*
X-123800Y285000D01*
X-127300D01*
G01X-98550Y300000D02*
Y285000D01*
X-91550D01*
G01X-85225D02*
X-80850Y300000D01*
X-76475Y285000D01*
G01X-78050Y290250D02*
X-83650D01*
G01X-66650Y285000D02*
Y291750D01*
X-70150Y300000D01*
G01X-63150D02*
X-66650Y291750D01*
G01X-48950Y285000D02*
X-55950D01*
Y300000D01*
X-48950D01*
G01X-51750Y292750D02*
X-55950D01*
G01X-41750Y285000D02*
Y300000D01*
X-37375D01*
X-35975Y299250D01*
X-35100Y298250D01*
X-34750Y296250D01*
X-35100Y294250D01*
X-36150Y293000D01*
X-37375Y292250D01*
X-41750D01*
G01X-37375D02*
X-34750Y285000D01*
G01X-27725Y287000D02*
X-26325Y285750D01*
X-24750Y285000D01*
X-23350D01*
X-21950Y285750D01*
X-20900Y287000D01*
X-20375Y288750D01*
X-20725Y290500D01*
X-21600Y292000D01*
X-23175Y293000D01*
X-25275Y293500D01*
X-26500Y294500D01*
X-27025Y296250D01*
X-26675Y298000D01*
X-25800Y299250D01*
X-24575Y300000D01*
X-23350D01*
X-22125Y299500D01*
X-21075Y298250D01*
G01X4350Y300000D02*
Y285000D01*
G01X325Y300000D02*
X8375D01*
G01X18550Y285000D02*
X17150Y285250D01*
X15925Y286250D01*
X14875Y287750D01*
X14175Y289500D01*
X13825Y291500D01*
Y293500D01*
X14175Y295500D01*
X14875Y297250D01*
X15925Y298750D01*
X17150Y299750D01*
X18550Y300000D01*
X19950Y299750D01*
X21175Y298750D01*
X22225Y297250D01*
X22925Y295500D01*
X23275Y293500D01*
Y291500D01*
X22925Y289500D01*
X22225Y287750D01*
X21175Y286250D01*
X19950Y285250D01*
X18550Y285000D01*
G01X48350Y293000D02*
X49050Y293750D01*
X49575Y295000D01*
X49925Y296750D01*
X49575Y298250D01*
X48875Y299250D01*
X47650Y300000D01*
X42925D01*
Y285000D01*
X48700D01*
X49925Y286000D01*
X50625Y287500D01*
X50975Y289250D01*
X50625Y291000D01*
X49575Y292500D01*
X48350Y293000D01*
X42925D01*
G01X64650Y285000D02*
X57650D01*
Y300000D01*
X64650D01*
G01X61850Y292750D02*
X57650D01*
G01X85000Y285000D02*
Y300000D01*
X89550Y287500D01*
X94100Y300000D01*
Y285000D01*
G01X107250D02*
X100250D01*
Y300000D01*
X107250D01*
G01X104450Y292750D02*
X100250D01*
G01X113575Y285000D02*
X117950Y300000D01*
X122325Y285000D01*
G01X120750Y290250D02*
X115150D01*
G01X128475Y287000D02*
X129875Y285750D01*
X131450Y285000D01*
X132850D01*
X134250Y285750D01*
X135300Y287000D01*
X135825Y288750D01*
X135475Y290500D01*
X134600Y292000D01*
X133025Y293000D01*
X130925Y293500D01*
X129700Y294500D01*
X129175Y296250D01*
X129525Y298000D01*
X130400Y299250D01*
X131625Y300000D01*
X132850D01*
X134075Y299500D01*
X135125Y298250D01*
G01X142500Y300000D02*
Y289250D01*
X143200Y287000D01*
X144600Y285500D01*
X146350Y285000D01*
X148100Y285500D01*
X149500Y287000D01*
X150200Y289250D01*
Y300000D01*
G01X157050Y285000D02*
Y300000D01*
X161425D01*
X162825Y299250D01*
X163700Y298250D01*
X164050Y296250D01*
X163700Y294250D01*
X162650Y293000D01*
X161425Y292250D01*
X157050D01*
G01X161425D02*
X164050Y285000D01*
G01X178250D02*
X171250D01*
Y300000D01*
X178250D01*
G01X175450Y292750D02*
X171250D01*
G01X185100Y285000D02*
Y300000D01*
X188600D01*
X190000Y299250D01*
X191050Y298250D01*
X191925Y296750D01*
X192625Y295000D01*
X192800Y292500D01*
X192625Y290000D01*
X191925Y288250D01*
X191050Y286750D01*
X190000Y285750D01*
X188600Y285000D01*
X185100D01*
G01X-194450Y325000D02*
Y315000D01*
G01Y329000D02*
X-194800Y329250D01*
Y329750D01*
X-194450Y330000D01*
X-194100Y329750D01*
Y329250D01*
X-194450Y329000D01*
G01X-180250Y314500D02*
X-180600Y314750D01*
Y315250D01*
X-180250Y315500D01*
X-179900Y315250D01*
Y314750D01*
X-180250Y314500D01*
G01X-155525Y317000D02*
X-154125Y315750D01*
X-152550Y315000D01*
X-151150D01*
X-149750Y315750D01*
X-148700Y317000D01*
X-148175Y318750D01*
X-148525Y320500D01*
X-149400Y322000D01*
X-150975Y323000D01*
X-153075Y323500D01*
X-154300Y324500D01*
X-154825Y326250D01*
X-154475Y328000D01*
X-153600Y329250D01*
X-152375Y330000D01*
X-151150D01*
X-149925Y329500D01*
X-148875Y328250D01*
G01X-134150Y315000D02*
X-141150D01*
Y330000D01*
X-134150D01*
G01X-136950Y322750D02*
X-141150D01*
G01X-119950Y315000D02*
X-126950D01*
Y330000D01*
X-119950D01*
G01X-122750Y322750D02*
X-126950D01*
G01X-98375Y315000D02*
Y330000D01*
X-91725D01*
G01X-94175Y322750D02*
X-98375D01*
G01X-85225Y315000D02*
X-80850Y330000D01*
X-76475Y315000D01*
G01X-78050Y320250D02*
X-83650D01*
G01X-65250Y323000D02*
X-64550Y323750D01*
X-64025Y325000D01*
X-63675Y326750D01*
X-64025Y328250D01*
X-64725Y329250D01*
X-65950Y330000D01*
X-70675D01*
Y315000D01*
X-64900D01*
X-63675Y316000D01*
X-62975Y317500D01*
X-62625Y319250D01*
X-62975Y321000D01*
X-64025Y322500D01*
X-65250Y323000D01*
X-70675D01*
G01X-55950Y315000D02*
Y330000D01*
X-51575D01*
X-50175Y329250D01*
X-49300Y328250D01*
X-48950Y326250D01*
X-49300Y324250D01*
X-50350Y323000D01*
X-51575Y322250D01*
X-55950D01*
G01X-51575D02*
X-48950Y315000D01*
G01X-40350Y330000D02*
X-36150D01*
G01X-38250D02*
Y315000D01*
G01X-40350D02*
X-36150D01*
G01X-20200Y328750D02*
X-21250Y329500D01*
X-22475Y330000D01*
X-23875D01*
X-25450Y329250D01*
X-26675Y328000D01*
X-27550Y326500D01*
X-28250Y324000D01*
X-28425Y321750D01*
X-28075Y319500D01*
X-27550Y318000D01*
X-26500Y316500D01*
X-25275Y315500D01*
X-24050Y315000D01*
X-22825D01*
X-21600Y315500D01*
X-20550Y316250D01*
X-19675Y317250D01*
G01X-14225Y315000D02*
X-9850Y330000D01*
X-5475Y315000D01*
G01X-7050Y320250D02*
X-12650D01*
G01X4350Y330000D02*
Y315000D01*
G01X325Y330000D02*
X8375D01*
G01X16450D02*
X20650D01*
G01X18550D02*
Y315000D01*
G01X16450D02*
X20650D01*
G01X32750D02*
X31350Y315250D01*
X30125Y316250D01*
X29075Y317750D01*
X28375Y319500D01*
X28025Y321500D01*
Y323500D01*
X28375Y325500D01*
X29075Y327250D01*
X30125Y328750D01*
X31350Y329750D01*
X32750Y330000D01*
X34150Y329750D01*
X35375Y328750D01*
X36425Y327250D01*
X37125Y325500D01*
X37475Y323500D01*
Y321500D01*
X37125Y319500D01*
X36425Y317750D01*
X35375Y316250D01*
X34150Y315250D01*
X32750Y315000D01*
G01X42925D02*
Y330000D01*
X50975Y315000D01*
Y330000D01*
G01X71500Y315000D02*
Y330000D01*
X75000D01*
X76400Y329250D01*
X77450Y328250D01*
X78325Y326750D01*
X79025Y325000D01*
X79200Y322500D01*
X79025Y320000D01*
X78325Y318250D01*
X77450Y316750D01*
X76400Y315750D01*
X75000Y315000D01*
X71500D01*
G01X86050D02*
Y330000D01*
X90425D01*
X91825Y329250D01*
X92700Y328250D01*
X93050Y326250D01*
X92700Y324250D01*
X91650Y323000D01*
X90425Y322250D01*
X86050D01*
G01X90425D02*
X93050Y315000D01*
G01X99375D02*
X103750Y330000D01*
X108125Y315000D01*
G01X106550Y320250D02*
X100950D01*
G01X112700Y330000D02*
X115150Y315000D01*
X117950Y330000D01*
X120750Y315000D01*
X123200Y330000D01*
G01X130050D02*
X134250D01*
G01X132150D02*
Y315000D01*
G01X130050D02*
X134250D01*
G01X142325D02*
Y330000D01*
X150375Y315000D01*
Y330000D01*
G01X161600Y322500D02*
X165100D01*
Y318000D01*
X164050Y316500D01*
X162825Y315500D01*
X161075Y315000D01*
X159325Y315500D01*
X158100Y316500D01*
X157050Y318000D01*
X156350Y319750D01*
X156000Y321750D01*
Y323500D01*
X156350Y325000D01*
X157050Y326750D01*
X158100Y328250D01*
X159150Y329250D01*
X160550Y330000D01*
X161775D01*
X163175Y329500D01*
X164225Y328500D01*
G01X185275Y317000D02*
X186675Y315750D01*
X188250Y315000D01*
X189650D01*
X191050Y315750D01*
X192100Y317000D01*
X192625Y318750D01*
X192275Y320500D01*
X191400Y322000D01*
X189825Y323000D01*
X187725Y323500D01*
X186500Y324500D01*
X185975Y326250D01*
X186325Y328000D01*
X187200Y329250D01*
X188425Y330000D01*
X189650D01*
X190875Y329500D01*
X191925Y328250D01*
G01X199475Y315000D02*
Y330000D01*
G01X206825D02*
Y315000D01*
G01Y322500D02*
X199475D01*
G01X220850Y315000D02*
X213850D01*
Y330000D01*
X220850D01*
G01X218050Y322750D02*
X213850D01*
G01X235050Y315000D02*
X228050D01*
Y330000D01*
X235050D01*
G01X232250Y322750D02*
X228050D01*
G01X245750Y330000D02*
Y315000D01*
G01X241725Y330000D02*
X249775D01*
G01X270825Y327500D02*
X271875Y329000D01*
X273100Y329750D01*
X274500Y330000D01*
X276250Y329500D01*
X277475Y328250D01*
X277825Y326750D01*
X277650Y325250D01*
X276950Y324000D01*
X273450Y321500D01*
X271875Y319750D01*
X270825Y317250D01*
X270475Y315000D01*
X277825D01*
G01X299225D02*
Y330000D01*
X305875D01*
G01X303425Y322750D02*
X299225D01*
G01X316750Y315000D02*
X315350Y315250D01*
X314125Y316250D01*
X313075Y317750D01*
X312375Y319500D01*
X312025Y321500D01*
Y323500D01*
X312375Y325500D01*
X313075Y327250D01*
X314125Y328750D01*
X315350Y329750D01*
X316750Y330000D01*
X318150Y329750D01*
X319375Y328750D01*
X320425Y327250D01*
X321125Y325500D01*
X321475Y323500D01*
Y321500D01*
X321125Y319500D01*
X320425Y317750D01*
X319375Y316250D01*
X318150Y315250D01*
X316750Y315000D01*
G01X327450D02*
Y330000D01*
X331825D01*
X333225Y329250D01*
X334100Y328250D01*
X334450Y326250D01*
X334100Y324250D01*
X333050Y323000D01*
X331825Y322250D01*
X327450D01*
G01X331825D02*
X334450Y315000D01*
G01X355850D02*
Y330000D01*
X360225D01*
X361625Y329250D01*
X362500Y328250D01*
X362850Y326250D01*
X362500Y324250D01*
X361450Y323000D01*
X360225Y322250D01*
X355850D01*
G01X360225D02*
X362850Y315000D01*
G01X377050D02*
X370050D01*
Y330000D01*
X377050D01*
G01X374250Y322750D02*
X370050D01*
G01X387750Y315000D02*
X386350Y315250D01*
X385125Y316250D01*
X384075Y317750D01*
X383375Y319500D01*
X383025Y321500D01*
Y323500D01*
X383375Y325500D01*
X384075Y327250D01*
X385125Y328750D01*
X386350Y329750D01*
X387750Y330000D01*
X389150Y329750D01*
X390375Y328750D01*
X391425Y327250D01*
X392125Y325500D01*
X392475Y323500D01*
Y321500D01*
X392125Y319500D01*
X391425Y317750D01*
X390375Y316250D01*
X389150Y315250D01*
X387750Y315000D01*
G01X389150Y319000D02*
X391250Y315000D01*
G01X398100Y330000D02*
Y319250D01*
X398800Y317000D01*
X400200Y315500D01*
X401950Y315000D01*
X403700Y315500D01*
X405100Y317000D01*
X405800Y319250D01*
Y330000D01*
G01X414050D02*
X418250D01*
G01X416150D02*
Y315000D01*
G01X414050D02*
X418250D01*
G01X426850D02*
Y330000D01*
X431225D01*
X432625Y329250D01*
X433500Y328250D01*
X433850Y326250D01*
X433500Y324250D01*
X432450Y323000D01*
X431225Y322250D01*
X426850D01*
G01X431225D02*
X433850Y315000D01*
G01X448050D02*
X441050D01*
Y330000D01*
X448050D01*
G01X445250Y322750D02*
X441050D01*
G01X454900Y315000D02*
Y330000D01*
X458400D01*
X459800Y329250D01*
X460850Y328250D01*
X461725Y326750D01*
X462425Y325000D01*
X462600Y322500D01*
X462425Y320000D01*
X461725Y318250D01*
X460850Y316750D01*
X459800Y315750D01*
X458400Y315000D01*
X454900D01*
G01X485050Y330000D02*
X489250D01*
G01X487150D02*
Y315000D01*
G01X485050D02*
X489250D01*
G01X496800D02*
Y330000D01*
X501350Y317500D01*
X505900Y330000D01*
Y315000D01*
G01X512050D02*
Y330000D01*
X516250D01*
X517650Y329250D01*
X518700Y327500D01*
X519050Y325500D01*
X518700Y323500D01*
X517825Y322000D01*
X516250Y321250D01*
X512050D01*
G01X533250Y315000D02*
X526250D01*
Y330000D01*
X533250D01*
G01X530450Y322750D02*
X526250D01*
G01X540100Y315000D02*
Y330000D01*
X543600D01*
X545000Y329250D01*
X546050Y328250D01*
X546925Y326750D01*
X547625Y325000D01*
X547800Y322500D01*
X547625Y320000D01*
X546925Y318250D01*
X546050Y316750D01*
X545000Y315750D01*
X543600Y315000D01*
X540100D01*
G01X553775D02*
X558150Y330000D01*
X562525Y315000D01*
G01X560950Y320250D02*
X555350D01*
G01X568325Y315000D02*
Y330000D01*
X576375Y315000D01*
Y330000D01*
G01X590400Y328750D02*
X589350Y329500D01*
X588125Y330000D01*
X586725D01*
X585150Y329250D01*
X583925Y328000D01*
X583050Y326500D01*
X582350Y324000D01*
X582175Y321750D01*
X582525Y319500D01*
X583050Y318000D01*
X584100Y316500D01*
X585325Y315500D01*
X586550Y315000D01*
X587775D01*
X589000Y315500D01*
X590050Y316250D01*
X590925Y317250D01*
G01X604250Y315000D02*
X597250D01*
Y330000D01*
X604250D01*
G01X601450Y322750D02*
X597250D01*
G01X611275Y317000D02*
X612675Y315750D01*
X614250Y315000D01*
X615650D01*
X617050Y315750D01*
X618100Y317000D01*
X618625Y318750D01*
X618275Y320500D01*
X617400Y322000D01*
X615825Y323000D01*
X613725Y323500D01*
X612500Y324500D01*
X611975Y326250D01*
X612325Y328000D01*
X613200Y329250D01*
X614425Y330000D01*
X615650D01*
X616875Y329500D01*
X617925Y328250D01*
G01X-276500Y345000D02*
Y355000D01*
G01Y353250D02*
X-277200Y354250D01*
X-278250Y354750D01*
X-279475Y355000D01*
X-280700Y354500D01*
X-281750Y353500D01*
X-282450Y352000D01*
X-282800Y350000D01*
X-282450Y348000D01*
X-281750Y346500D01*
X-280700Y345500D01*
X-279475Y345000D01*
X-278250Y345250D01*
X-277200Y346000D01*
X-276500Y347000D01*
G01X-265450Y344500D02*
X-265800Y344750D01*
Y345250D01*
X-265450Y345500D01*
X-265100Y345250D01*
Y344750D01*
X-265450Y344500D01*
G01X-227400Y345000D02*
Y360000D01*
X-222850Y347500D01*
X-218300Y360000D01*
Y345000D01*
G01X-205150D02*
X-212150D01*
Y360000D01*
X-205150D01*
G01X-207950Y352750D02*
X-212150D01*
G01X-198825Y345000D02*
X-194450Y360000D01*
X-190075Y345000D01*
G01X-191650Y350250D02*
X-197250D01*
G01X-183925Y347000D02*
X-182525Y345750D01*
X-180950Y345000D01*
X-179550D01*
X-178150Y345750D01*
X-177100Y347000D01*
X-176575Y348750D01*
X-176925Y350500D01*
X-177800Y352000D01*
X-179375Y353000D01*
X-181475Y353500D01*
X-182700Y354500D01*
X-183225Y356250D01*
X-182875Y358000D01*
X-182000Y359250D01*
X-180775Y360000D01*
X-179550D01*
X-178325Y359500D01*
X-177275Y358250D01*
G01X-169900Y360000D02*
Y349250D01*
X-169200Y347000D01*
X-167800Y345500D01*
X-166050Y345000D01*
X-164300Y345500D01*
X-162900Y347000D01*
X-162200Y349250D01*
Y360000D01*
G01X-155350Y345000D02*
Y360000D01*
X-150975D01*
X-149575Y359250D01*
X-148700Y358250D01*
X-148350Y356250D01*
X-148700Y354250D01*
X-149750Y353000D01*
X-150975Y352250D01*
X-155350D01*
G01X-150975D02*
X-148350Y345000D01*
G01X-134150D02*
X-141150D01*
Y360000D01*
X-134150D01*
G01X-136950Y352750D02*
X-141150D01*
G01X-109250Y360000D02*
Y345000D01*
G01X-113275Y360000D02*
X-105225D01*
G01X-98725Y345000D02*
Y360000D01*
G01X-91375D02*
Y345000D01*
G01Y352500D02*
X-98725D01*
G01X-77350Y345000D02*
X-84350D01*
Y360000D01*
X-77350D01*
G01X-80150Y352750D02*
X-84350D01*
G01X-55775Y345000D02*
Y360000D01*
X-49125D01*
G01X-51575Y352750D02*
X-55775D01*
G01X-38250Y345000D02*
X-39650Y345250D01*
X-40875Y346250D01*
X-41925Y347750D01*
X-42625Y349500D01*
X-42975Y351500D01*
Y353500D01*
X-42625Y355500D01*
X-41925Y357250D01*
X-40875Y358750D01*
X-39650Y359750D01*
X-38250Y360000D01*
X-36850Y359750D01*
X-35625Y358750D01*
X-34575Y357250D01*
X-33875Y355500D01*
X-33525Y353500D01*
Y351500D01*
X-33875Y349500D01*
X-34575Y347750D01*
X-35625Y346250D01*
X-36850Y345250D01*
X-38250Y345000D01*
G01X-27550Y360000D02*
Y345000D01*
X-20550D01*
G01X-13350Y360000D02*
Y345000D01*
X-6350D01*
G01X4350D02*
X2950Y345250D01*
X1725Y346250D01*
X675Y347750D01*
X-25Y349500D01*
X-375Y351500D01*
Y353500D01*
X-25Y355500D01*
X675Y357250D01*
X1725Y358750D01*
X2950Y359750D01*
X4350Y360000D01*
X5750Y359750D01*
X6975Y358750D01*
X8025Y357250D01*
X8725Y355500D01*
X9075Y353500D01*
Y351500D01*
X8725Y349500D01*
X8025Y347750D01*
X6975Y346250D01*
X5750Y345250D01*
X4350Y345000D01*
G01X13300Y360000D02*
X15750Y345000D01*
X18550Y360000D01*
X21350Y345000D01*
X23800Y360000D01*
G01X30650D02*
X34850D01*
G01X32750D02*
Y345000D01*
G01X30650D02*
X34850D01*
G01X42925D02*
Y360000D01*
X50975Y345000D01*
Y360000D01*
G01X62200Y352500D02*
X65700D01*
Y348000D01*
X64650Y346500D01*
X63425Y345500D01*
X61675Y345000D01*
X59925Y345500D01*
X58700Y346500D01*
X57650Y348000D01*
X56950Y349750D01*
X56600Y351750D01*
Y353500D01*
X56950Y355000D01*
X57650Y356750D01*
X58700Y358250D01*
X59750Y359250D01*
X61150Y360000D01*
X62375D01*
X63775Y359500D01*
X64825Y358500D01*
G01X87450Y360000D02*
X91650D01*
G01X89550D02*
Y345000D01*
G01X87450D02*
X91650D01*
G01X99200D02*
Y360000D01*
X103750Y347500D01*
X108300Y360000D01*
Y345000D01*
G01X114450D02*
Y360000D01*
X118650D01*
X120050Y359250D01*
X121100Y357500D01*
X121450Y355500D01*
X121100Y353500D01*
X120225Y352000D01*
X118650Y351250D01*
X114450D01*
G01X135650Y345000D02*
X128650D01*
Y360000D01*
X135650D01*
G01X132850Y352750D02*
X128650D01*
G01X142500Y345000D02*
Y360000D01*
X146000D01*
X147400Y359250D01*
X148450Y358250D01*
X149325Y356750D01*
X150025Y355000D01*
X150200Y352500D01*
X150025Y350000D01*
X149325Y348250D01*
X148450Y346750D01*
X147400Y345750D01*
X146000Y345000D01*
X142500D01*
G01X156175D02*
X160550Y360000D01*
X164925Y345000D01*
G01X163350Y350250D02*
X157750D01*
G01X170725Y345000D02*
Y360000D01*
X178775Y345000D01*
Y360000D01*
G01X192800Y358750D02*
X191750Y359500D01*
X190525Y360000D01*
X189125D01*
X187550Y359250D01*
X186325Y358000D01*
X185450Y356500D01*
X184750Y354000D01*
X184575Y351750D01*
X184925Y349500D01*
X185450Y348000D01*
X186500Y346500D01*
X187725Y345500D01*
X188950Y345000D01*
X190175D01*
X191400Y345500D01*
X192450Y346250D01*
X193325Y347250D01*
G01X206650Y345000D02*
X199650D01*
Y360000D01*
X206650D01*
G01X203850Y352750D02*
X199650D01*
G01X213675Y347000D02*
X215075Y345750D01*
X216650Y345000D01*
X218050D01*
X219450Y345750D01*
X220500Y347000D01*
X221025Y348750D01*
X220675Y350500D01*
X219800Y352000D01*
X218225Y353000D01*
X216125Y353500D01*
X214900Y354500D01*
X214375Y356250D01*
X214725Y358000D01*
X215600Y359250D01*
X216825Y360000D01*
X218050D01*
X219275Y359500D01*
X220325Y358250D01*
G01X245750Y345000D02*
X244350Y345250D01*
X243125Y346250D01*
X242075Y347750D01*
X241375Y349500D01*
X241025Y351500D01*
Y353500D01*
X241375Y355500D01*
X242075Y357250D01*
X243125Y358750D01*
X244350Y359750D01*
X245750Y360000D01*
X247150Y359750D01*
X248375Y358750D01*
X249425Y357250D01*
X250125Y355500D01*
X250475Y353500D01*
Y351500D01*
X250125Y349500D01*
X249425Y347750D01*
X248375Y346250D01*
X247150Y345250D01*
X245750Y345000D01*
G01X256625D02*
Y360000D01*
X263275D01*
G01X260825Y352750D02*
X256625D01*
G01X284500Y348000D02*
X285550Y346250D01*
X286950Y345250D01*
X288525Y345000D01*
X289925Y345250D01*
X291325Y346500D01*
X292200Y348000D01*
X292375Y349500D01*
X292025Y351250D01*
X290800Y352500D01*
X289575Y353000D01*
X288000D01*
G01X289575D02*
X290625Y353750D01*
X291500Y355000D01*
X291850Y356500D01*
X291500Y358000D01*
X290625Y359250D01*
X289050Y360000D01*
X287475Y359750D01*
X285900Y358750D01*
G01X302550Y360000D02*
X301150Y359500D01*
X300100Y358250D01*
X299400Y356750D01*
X298875Y354750D01*
X298700Y352500D01*
X298875Y350250D01*
X299400Y348250D01*
X300100Y346750D01*
X301150Y345500D01*
X302550Y345000D01*
X303950Y345500D01*
X305000Y346750D01*
X305700Y348250D01*
X306225Y350250D01*
X306400Y352500D01*
X306225Y354750D01*
X305700Y356750D01*
X305000Y358250D01*
X303950Y359500D01*
X302550Y360000D01*
G01X327450Y345000D02*
Y360000D01*
X331825D01*
X333225Y359250D01*
X334100Y358250D01*
X334450Y356250D01*
X334100Y354250D01*
X333050Y353000D01*
X331825Y352250D01*
X327450D01*
G01X331825D02*
X334450Y345000D01*
G01X340775D02*
X345150Y360000D01*
X349525Y345000D01*
G01X347950Y350250D02*
X342350D01*
G01X355325Y345000D02*
Y360000D01*
X363375Y345000D01*
Y360000D01*
G01X369700Y345000D02*
Y360000D01*
X373200D01*
X374600Y359250D01*
X375650Y358250D01*
X376525Y356750D01*
X377225Y355000D01*
X377400Y352500D01*
X377225Y350000D01*
X376525Y348250D01*
X375650Y346750D01*
X374600Y345750D01*
X373200Y345000D01*
X369700D01*
G01X387750D02*
X386350Y345250D01*
X385125Y346250D01*
X384075Y347750D01*
X383375Y349500D01*
X383025Y351500D01*
Y353500D01*
X383375Y355500D01*
X384075Y357250D01*
X385125Y358750D01*
X386350Y359750D01*
X387750Y360000D01*
X389150Y359750D01*
X390375Y358750D01*
X391425Y357250D01*
X392125Y355500D01*
X392475Y353500D01*
Y351500D01*
X392125Y349500D01*
X391425Y347750D01*
X390375Y346250D01*
X389150Y345250D01*
X387750Y345000D01*
G01X397400D02*
Y360000D01*
X401950Y347500D01*
X406500Y360000D01*
Y345000D01*
G01X412650Y360000D02*
Y345000D01*
X419650D01*
G01X430350D02*
Y351750D01*
X426850Y360000D01*
G01X433850D02*
X430350Y351750D01*
G01X455250Y345000D02*
Y360000D01*
X459450D01*
X460850Y359250D01*
X461900Y357500D01*
X462250Y355500D01*
X461900Y353500D01*
X461025Y352000D01*
X459450Y351250D01*
X455250D01*
G01X470850Y360000D02*
X475050D01*
G01X472950D02*
Y345000D01*
G01X470850D02*
X475050D01*
G01X491000Y358750D02*
X489950Y359500D01*
X488725Y360000D01*
X487325D01*
X485750Y359250D01*
X484525Y358000D01*
X483650Y356500D01*
X482950Y354000D01*
X482775Y351750D01*
X483125Y349500D01*
X483650Y348000D01*
X484700Y346500D01*
X485925Y345500D01*
X487150Y345000D01*
X488375D01*
X489600Y345500D01*
X490650Y346250D01*
X491525Y347250D01*
G01X497500Y345000D02*
Y360000D01*
G01X504150D02*
X497500Y350750D01*
G01X505200Y345000D02*
X500475Y355000D01*
G01X519050Y345000D02*
X512050D01*
Y360000D01*
X519050D01*
G01X516250Y352750D02*
X512050D01*
G01X525900Y345000D02*
Y360000D01*
X529400D01*
X530800Y359250D01*
X531850Y358250D01*
X532725Y356750D01*
X533425Y355000D01*
X533600Y352500D01*
X533425Y350000D01*
X532725Y348250D01*
X531850Y346750D01*
X530800Y345750D01*
X529400Y345000D01*
X525900D01*
G01X559550Y353000D02*
X560250Y353750D01*
X560775Y355000D01*
X561125Y356750D01*
X560775Y358250D01*
X560075Y359250D01*
X558850Y360000D01*
X554125D01*
Y345000D01*
X559900D01*
X561125Y346000D01*
X561825Y347500D01*
X562175Y349250D01*
X561825Y351000D01*
X560775Y352500D01*
X559550Y353000D01*
X554125D01*
G01X572350Y345000D02*
X570950Y345250D01*
X569725Y346250D01*
X568675Y347750D01*
X567975Y349500D01*
X567625Y351500D01*
Y353500D01*
X567975Y355500D01*
X568675Y357250D01*
X569725Y358750D01*
X570950Y359750D01*
X572350Y360000D01*
X573750Y359750D01*
X574975Y358750D01*
X576025Y357250D01*
X576725Y355500D01*
X577075Y353500D01*
Y351500D01*
X576725Y349500D01*
X576025Y347750D01*
X574975Y346250D01*
X573750Y345250D01*
X572350Y345000D01*
G01X582175D02*
X586550Y360000D01*
X590925Y345000D01*
G01X589350Y350250D02*
X583750D01*
G01X597250Y345000D02*
Y360000D01*
X601625D01*
X603025Y359250D01*
X603900Y358250D01*
X604250Y356250D01*
X603900Y354250D01*
X602850Y353000D01*
X601625Y352250D01*
X597250D01*
G01X601625D02*
X604250Y345000D01*
G01X611100D02*
Y360000D01*
X614600D01*
X616000Y359250D01*
X617050Y358250D01*
X617925Y356750D01*
X618625Y355000D01*
X618800Y352500D01*
X618625Y350000D01*
X617925Y348250D01*
X617050Y346750D01*
X616000Y345750D01*
X614600Y345000D01*
X611100D01*
G01X625475Y347000D02*
X626875Y345750D01*
X628450Y345000D01*
X629850D01*
X631250Y345750D01*
X632300Y347000D01*
X632825Y348750D01*
X632475Y350500D01*
X631600Y352000D01*
X630025Y353000D01*
X627925Y353500D01*
X626700Y354500D01*
X626175Y356250D01*
X626525Y358000D01*
X627400Y359250D01*
X628625Y360000D01*
X629850D01*
X631075Y359500D01*
X632125Y358250D01*
G01X643350Y344500D02*
X643000Y344750D01*
Y345250D01*
X643350Y345500D01*
X643700Y345250D01*
Y344750D01*
X643350Y344500D01*
G01Y351250D02*
X643000Y351500D01*
Y352000D01*
X643350Y352250D01*
X643700Y352000D01*
Y351500D01*
X643350Y351250D01*
G01X-336450Y390000D02*
Y375000D01*
G01X-340475Y390000D02*
X-332425D01*
G01X-322250Y375000D02*
X-323650Y375250D01*
X-324875Y376250D01*
X-325925Y377750D01*
X-326625Y379500D01*
X-326975Y381500D01*
Y383500D01*
X-326625Y385500D01*
X-325925Y387250D01*
X-324875Y388750D01*
X-323650Y389750D01*
X-322250Y390000D01*
X-320850Y389750D01*
X-319625Y388750D01*
X-318575Y387250D01*
X-317875Y385500D01*
X-317525Y383500D01*
Y381500D01*
X-317875Y379500D01*
X-318575Y377750D01*
X-319625Y376250D01*
X-320850Y375250D01*
X-322250Y375000D01*
G01X-292450Y383000D02*
X-291750Y383750D01*
X-291225Y385000D01*
X-290875Y386750D01*
X-291225Y388250D01*
X-291925Y389250D01*
X-293150Y390000D01*
X-297875D01*
Y375000D01*
X-292100D01*
X-290875Y376000D01*
X-290175Y377500D01*
X-289825Y379250D01*
X-290175Y381000D01*
X-291225Y382500D01*
X-292450Y383000D01*
X-297875D01*
G01X-276150Y375000D02*
X-283150D01*
Y390000D01*
X-276150D01*
G01X-278950Y382750D02*
X-283150D01*
G01X-254925Y377000D02*
X-253525Y375750D01*
X-251950Y375000D01*
X-250550D01*
X-249150Y375750D01*
X-248100Y377000D01*
X-247575Y378750D01*
X-247925Y380500D01*
X-248800Y382000D01*
X-250375Y383000D01*
X-252475Y383500D01*
X-253700Y384500D01*
X-254225Y386250D01*
X-253875Y388000D01*
X-253000Y389250D01*
X-251775Y390000D01*
X-250550D01*
X-249325Y389500D01*
X-248275Y388250D01*
G01X-233550Y375000D02*
X-240550D01*
Y390000D01*
X-233550D01*
G01X-236350Y382750D02*
X-240550D01*
G01X-226875Y375000D02*
Y390000D01*
X-218825Y375000D01*
Y390000D01*
G01X-208650D02*
Y375000D01*
G01X-212675Y390000D02*
X-204625D01*
G01X-180250D02*
Y375000D01*
G01X-184275Y390000D02*
X-176225D01*
G01X-166050Y375000D02*
X-167450Y375250D01*
X-168675Y376250D01*
X-169725Y377750D01*
X-170425Y379500D01*
X-170775Y381500D01*
Y383500D01*
X-170425Y385500D01*
X-169725Y387250D01*
X-168675Y388750D01*
X-167450Y389750D01*
X-166050Y390000D01*
X-164650Y389750D01*
X-163425Y388750D01*
X-162375Y387250D01*
X-161675Y385500D01*
X-161325Y383500D01*
Y381500D01*
X-161675Y379500D01*
X-162375Y377750D01*
X-163425Y376250D01*
X-164650Y375250D01*
X-166050Y375000D01*
G01X-137650Y390000D02*
Y375000D01*
G01X-141675Y390000D02*
X-133625D01*
G01X-127125Y375000D02*
Y390000D01*
G01X-119775D02*
Y375000D01*
G01Y382500D02*
X-127125D01*
G01X-105750Y375000D02*
X-112750D01*
Y390000D01*
X-105750D01*
G01X-108550Y382750D02*
X-112750D01*
G01X-85400Y375000D02*
Y390000D01*
X-80850Y377500D01*
X-76300Y390000D01*
Y375000D01*
G01X-70325Y377000D02*
X-68925Y375750D01*
X-67350Y375000D01*
X-65950D01*
X-64550Y375750D01*
X-63500Y377000D01*
X-62975Y378750D01*
X-63325Y380500D01*
X-64200Y382000D01*
X-65775Y383000D01*
X-67875Y383500D01*
X-69100Y384500D01*
X-69625Y386250D01*
X-69275Y388000D01*
X-68400Y389250D01*
X-67175Y390000D01*
X-65950D01*
X-64725Y389500D01*
X-63675Y388250D01*
G01X-34750Y375000D02*
X-41750D01*
Y390000D01*
X-34750D01*
G01X-37550Y382750D02*
X-41750D01*
G01X-28075Y375000D02*
Y390000D01*
X-20025Y375000D01*
Y390000D01*
G01X-8800Y382500D02*
X-5300D01*
Y378000D01*
X-6350Y376500D01*
X-7575Y375500D01*
X-9325Y375000D01*
X-11075Y375500D01*
X-12300Y376500D01*
X-13350Y378000D01*
X-14050Y379750D01*
X-14400Y381750D01*
Y383500D01*
X-14050Y385000D01*
X-13350Y386750D01*
X-12300Y388250D01*
X-11250Y389250D01*
X-9850Y390000D01*
X-8625D01*
X-7225Y389500D01*
X-6175Y388500D01*
G01X2250Y390000D02*
X6450D01*
G01X4350D02*
Y375000D01*
G01X2250D02*
X6450D01*
G01X14525D02*
Y390000D01*
X22575Y375000D01*
Y390000D01*
G01X36250Y375000D02*
X29250D01*
Y390000D01*
X36250D01*
G01X33450Y382750D02*
X29250D01*
G01X50450Y375000D02*
X43450D01*
Y390000D01*
X50450D01*
G01X47650Y382750D02*
X43450D01*
G01X57650Y375000D02*
Y390000D01*
X62025D01*
X63425Y389250D01*
X64300Y388250D01*
X64650Y386250D01*
X64300Y384250D01*
X63250Y383000D01*
X62025Y382250D01*
X57650D01*
G01X62025D02*
X64650Y375000D01*
G01X87450Y390000D02*
X91650D01*
G01X89550D02*
Y375000D01*
G01X87450D02*
X91650D01*
G01X99725D02*
Y390000D01*
X107775Y375000D01*
Y390000D01*
G01X113575D02*
X117950Y375000D01*
X122325Y390000D01*
G01X132150Y375000D02*
X130750Y375250D01*
X129525Y376250D01*
X128475Y377750D01*
X127775Y379500D01*
X127425Y381500D01*
Y383500D01*
X127775Y385500D01*
X128475Y387250D01*
X129525Y388750D01*
X130750Y389750D01*
X132150Y390000D01*
X133550Y389750D01*
X134775Y388750D01*
X135825Y387250D01*
X136525Y385500D01*
X136875Y383500D01*
Y381500D01*
X136525Y379500D01*
X135825Y377750D01*
X134775Y376250D01*
X133550Y375250D01*
X132150Y375000D01*
G01X142850Y390000D02*
Y375000D01*
X149850D01*
G01X156175Y390000D02*
X160550Y375000D01*
X164925Y390000D01*
G01X178250Y375000D02*
X171250D01*
Y390000D01*
X178250D01*
G01X175450Y382750D02*
X171250D01*
G01X185100Y375000D02*
Y390000D01*
X188600D01*
X190000Y389250D01*
X191050Y388250D01*
X191925Y386750D01*
X192625Y385000D01*
X192800Y382500D01*
X192625Y380000D01*
X191925Y378250D01*
X191050Y376750D01*
X190000Y375750D01*
X188600Y375000D01*
X185100D01*
G01X203150Y374500D02*
X202800Y374750D01*
Y375250D01*
X203150Y375500D01*
X203500Y375250D01*
Y374750D01*
X203150Y374500D01*
G01X-335050Y413000D02*
X-334350Y413750D01*
X-333825Y415000D01*
X-333475Y416750D01*
X-333825Y418250D01*
X-334525Y419250D01*
X-335750Y420000D01*
X-340475D01*
Y405000D01*
X-334700D01*
X-333475Y406000D01*
X-332775Y407500D01*
X-332425Y409250D01*
X-332775Y411000D01*
X-333825Y412500D01*
X-335050Y413000D01*
X-340475D01*
G01X-318750Y405000D02*
X-325750D01*
Y420000D01*
X-318750D01*
G01X-321550Y412750D02*
X-325750D01*
G01X-311375Y405000D02*
Y420000D01*
X-304725D01*
G01X-307175Y412750D02*
X-311375D01*
G01X-293850Y405000D02*
X-295250Y405250D01*
X-296475Y406250D01*
X-297525Y407750D01*
X-298225Y409500D01*
X-298575Y411500D01*
Y413500D01*
X-298225Y415500D01*
X-297525Y417250D01*
X-296475Y418750D01*
X-295250Y419750D01*
X-293850Y420000D01*
X-292450Y419750D01*
X-291225Y418750D01*
X-290175Y417250D01*
X-289475Y415500D01*
X-289125Y413500D01*
Y411500D01*
X-289475Y409500D01*
X-290175Y407750D01*
X-291225Y406250D01*
X-292450Y405250D01*
X-293850Y405000D01*
G01X-283150D02*
Y420000D01*
X-278775D01*
X-277375Y419250D01*
X-276500Y418250D01*
X-276150Y416250D01*
X-276500Y414250D01*
X-277550Y413000D01*
X-278775Y412250D01*
X-283150D01*
G01X-278775D02*
X-276150Y405000D01*
G01X-261950D02*
X-268950D01*
Y420000D01*
X-261950D01*
G01X-264750Y412750D02*
X-268950D01*
G01X-237050Y420000D02*
Y405000D01*
G01X-241075Y420000D02*
X-233025D01*
G01X-226525Y405000D02*
Y420000D01*
G01X-219175D02*
Y405000D01*
G01Y412500D02*
X-226525D01*
G01X-205150Y405000D02*
X-212150D01*
Y420000D01*
X-205150D01*
G01X-207950Y412750D02*
X-212150D01*
G01X-178850Y413000D02*
X-178150Y413750D01*
X-177625Y415000D01*
X-177275Y416750D01*
X-177625Y418250D01*
X-178325Y419250D01*
X-179550Y420000D01*
X-184275D01*
Y405000D01*
X-178500D01*
X-177275Y406000D01*
X-176575Y407500D01*
X-176225Y409250D01*
X-176575Y411000D01*
X-177625Y412500D01*
X-178850Y413000D01*
X-184275D01*
G01X-166050Y405000D02*
X-167450Y405250D01*
X-168675Y406250D01*
X-169725Y407750D01*
X-170425Y409500D01*
X-170775Y411500D01*
Y413500D01*
X-170425Y415500D01*
X-169725Y417250D01*
X-168675Y418750D01*
X-167450Y419750D01*
X-166050Y420000D01*
X-164650Y419750D01*
X-163425Y418750D01*
X-162375Y417250D01*
X-161675Y415500D01*
X-161325Y413500D01*
Y411500D01*
X-161675Y409500D01*
X-162375Y407750D01*
X-163425Y406250D01*
X-164650Y405250D01*
X-166050Y405000D01*
G01X-156225D02*
X-151850Y420000D01*
X-147475Y405000D01*
G01X-149050Y410250D02*
X-154650D01*
G01X-141150Y405000D02*
Y420000D01*
X-136775D01*
X-135375Y419250D01*
X-134500Y418250D01*
X-134150Y416250D01*
X-134500Y414250D01*
X-135550Y413000D01*
X-136775Y412250D01*
X-141150D01*
G01X-136775D02*
X-134150Y405000D01*
G01X-127300D02*
Y420000D01*
X-123800D01*
X-122400Y419250D01*
X-121350Y418250D01*
X-120475Y416750D01*
X-119775Y415000D01*
X-119600Y412500D01*
X-119775Y410000D01*
X-120475Y408250D01*
X-121350Y406750D01*
X-122400Y405750D01*
X-123800Y405000D01*
X-127300D01*
G01X-112925Y407000D02*
X-111525Y405750D01*
X-109950Y405000D01*
X-108550D01*
X-107150Y405750D01*
X-106100Y407000D01*
X-105575Y408750D01*
X-105925Y410500D01*
X-106800Y412000D01*
X-108375Y413000D01*
X-110475Y413500D01*
X-111700Y414500D01*
X-112225Y416250D01*
X-111875Y418000D01*
X-111000Y419250D01*
X-109775Y420000D01*
X-108550D01*
X-107325Y419500D01*
X-106275Y418250D01*
G01X-85225Y405000D02*
X-80850Y420000D01*
X-76475Y405000D01*
G01X-78050Y410250D02*
X-83650D01*
G01X-70150Y405000D02*
Y420000D01*
X-65775D01*
X-64375Y419250D01*
X-63500Y418250D01*
X-63150Y416250D01*
X-63500Y414250D01*
X-64550Y413000D01*
X-65775Y412250D01*
X-70150D01*
G01X-65775D02*
X-63150Y405000D01*
G01X-48950D02*
X-55950D01*
Y420000D01*
X-48950D01*
G01X-51750Y412750D02*
X-55950D01*
G01X-27725Y407000D02*
X-26325Y405750D01*
X-24750Y405000D01*
X-23350D01*
X-21950Y405750D01*
X-20900Y407000D01*
X-20375Y408750D01*
X-20725Y410500D01*
X-21600Y412000D01*
X-23175Y413000D01*
X-25275Y413500D01*
X-26500Y414500D01*
X-27025Y416250D01*
X-26675Y418000D01*
X-25800Y419250D01*
X-24575Y420000D01*
X-23350D01*
X-22125Y419500D01*
X-21075Y418250D01*
G01X-13525Y405000D02*
Y420000D01*
G01X-6175D02*
Y405000D01*
G01Y412500D02*
X-13525D01*
G01X2250Y420000D02*
X6450D01*
G01X4350D02*
Y405000D01*
G01X2250D02*
X6450D01*
G01X15050D02*
Y420000D01*
X19250D01*
X20650Y419250D01*
X21700Y417500D01*
X22050Y415500D01*
X21700Y413500D01*
X20825Y412000D01*
X19250Y411250D01*
X15050D01*
G01X29250Y405000D02*
Y420000D01*
X33450D01*
X34850Y419250D01*
X35900Y417500D01*
X36250Y415500D01*
X35900Y413500D01*
X35025Y412000D01*
X33450Y411250D01*
X29250D01*
G01X50450Y405000D02*
X43450D01*
Y420000D01*
X50450D01*
G01X47650Y412750D02*
X43450D01*
G01X57300Y405000D02*
Y420000D01*
X60800D01*
X62200Y419250D01*
X63250Y418250D01*
X64125Y416750D01*
X64825Y415000D01*
X65000Y412500D01*
X64825Y410000D01*
X64125Y408250D01*
X63250Y406750D01*
X62200Y405750D01*
X60800Y405000D01*
X57300D01*
G01X89550D02*
X88150Y405250D01*
X86925Y406250D01*
X85875Y407750D01*
X85175Y409500D01*
X84825Y411500D01*
Y413500D01*
X85175Y415500D01*
X85875Y417250D01*
X86925Y418750D01*
X88150Y419750D01*
X89550Y420000D01*
X90950Y419750D01*
X92175Y418750D01*
X93225Y417250D01*
X93925Y415500D01*
X94275Y413500D01*
Y411500D01*
X93925Y409500D01*
X93225Y407750D01*
X92175Y406250D01*
X90950Y405250D01*
X89550Y405000D01*
G01X99900Y420000D02*
Y409250D01*
X100600Y407000D01*
X102000Y405500D01*
X103750Y405000D01*
X105500Y405500D01*
X106900Y407000D01*
X107600Y409250D01*
Y420000D01*
G01X117950D02*
Y405000D01*
G01X113925Y420000D02*
X121975D01*
G01X132150Y404500D02*
X131800Y404750D01*
Y405250D01*
X132150Y405500D01*
X132500Y405250D01*
Y404750D01*
X132150Y404500D01*
G01X156175Y405000D02*
X160550Y420000D01*
X164925Y405000D01*
G01X163350Y410250D02*
X157750D01*
G01X192800Y418750D02*
X191750Y419500D01*
X190525Y420000D01*
X189125D01*
X187550Y419250D01*
X186325Y418000D01*
X185450Y416500D01*
X184750Y414000D01*
X184575Y411750D01*
X184925Y409500D01*
X185450Y408000D01*
X186500Y406500D01*
X187725Y405500D01*
X188950Y405000D01*
X190175D01*
X191400Y405500D01*
X192450Y406250D01*
X193325Y407250D01*
G01X203150Y405000D02*
X201750Y405250D01*
X200525Y406250D01*
X199475Y407750D01*
X198775Y409500D01*
X198425Y411500D01*
Y413500D01*
X198775Y415500D01*
X199475Y417250D01*
X200525Y418750D01*
X201750Y419750D01*
X203150Y420000D01*
X204550Y419750D01*
X205775Y418750D01*
X206825Y417250D01*
X207525Y415500D01*
X207875Y413500D01*
Y411500D01*
X207525Y409500D01*
X206825Y407750D01*
X205775Y406250D01*
X204550Y405250D01*
X203150Y405000D01*
G01X213850D02*
Y420000D01*
X218050D01*
X219450Y419250D01*
X220500Y417500D01*
X220850Y415500D01*
X220500Y413500D01*
X219625Y412000D01*
X218050Y411250D01*
X213850D01*
G01X231550Y405000D02*
Y411750D01*
X228050Y420000D01*
G01X235050D02*
X231550Y411750D01*
G01X259950Y405000D02*
X258550Y405250D01*
X257325Y406250D01*
X256275Y407750D01*
X255575Y409500D01*
X255225Y411500D01*
Y413500D01*
X255575Y415500D01*
X256275Y417250D01*
X257325Y418750D01*
X258550Y419750D01*
X259950Y420000D01*
X261350Y419750D01*
X262575Y418750D01*
X263625Y417250D01*
X264325Y415500D01*
X264675Y413500D01*
Y411500D01*
X264325Y409500D01*
X263625Y407750D01*
X262575Y406250D01*
X261350Y405250D01*
X259950Y405000D01*
G01X270825D02*
Y420000D01*
X277475D01*
G01X275025Y412750D02*
X270825D01*
G01X302550Y420000D02*
Y405000D01*
G01X298525Y420000D02*
X306575D01*
G01X313075Y405000D02*
Y420000D01*
G01X320425D02*
Y405000D01*
G01Y412500D02*
X313075D01*
G01X334450Y405000D02*
X327450D01*
Y420000D01*
X334450D01*
G01X331650Y412750D02*
X327450D01*
G01X355850Y405000D02*
Y420000D01*
X360225D01*
X361625Y419250D01*
X362500Y418250D01*
X362850Y416250D01*
X362500Y414250D01*
X361450Y413000D01*
X360225Y412250D01*
X355850D01*
G01X360225D02*
X362850Y405000D01*
G01X377050D02*
X370050D01*
Y420000D01*
X377050D01*
G01X374250Y412750D02*
X370050D01*
G01X384250Y405000D02*
Y420000D01*
X388450D01*
X389850Y419250D01*
X390900Y417500D01*
X391250Y415500D01*
X390900Y413500D01*
X390025Y412000D01*
X388450Y411250D01*
X384250D01*
G01X401950Y405000D02*
X400550Y405250D01*
X399325Y406250D01*
X398275Y407750D01*
X397575Y409500D01*
X397225Y411500D01*
Y413500D01*
X397575Y415500D01*
X398275Y417250D01*
X399325Y418750D01*
X400550Y419750D01*
X401950Y420000D01*
X403350Y419750D01*
X404575Y418750D01*
X405625Y417250D01*
X406325Y415500D01*
X406675Y413500D01*
Y411500D01*
X406325Y409500D01*
X405625Y407750D01*
X404575Y406250D01*
X403350Y405250D01*
X401950Y405000D01*
G01X412650D02*
Y420000D01*
X417025D01*
X418425Y419250D01*
X419300Y418250D01*
X419650Y416250D01*
X419300Y414250D01*
X418250Y413000D01*
X417025Y412250D01*
X412650D01*
G01X417025D02*
X419650Y405000D01*
G01X430350Y420000D02*
Y405000D01*
G01X426325Y420000D02*
X434375D01*
G01X454375Y405000D02*
X458750Y420000D01*
X463125Y405000D01*
G01X461550Y410250D02*
X455950D01*
G01X468925Y405000D02*
Y420000D01*
X476975Y405000D01*
Y420000D01*
G01X483300Y405000D02*
Y420000D01*
X486800D01*
X488200Y419250D01*
X489250Y418250D01*
X490125Y416750D01*
X490825Y415000D01*
X491000Y412500D01*
X490825Y410000D01*
X490125Y408250D01*
X489250Y406750D01*
X488200Y405750D01*
X486800Y405000D01*
X483300D01*
G01X513450Y420000D02*
X517650D01*
G01X515550D02*
Y405000D01*
G01X513450D02*
X517650D01*
G01X525200D02*
Y420000D01*
X529750Y407500D01*
X534300Y420000D01*
Y405000D01*
G01X540450D02*
Y420000D01*
X544650D01*
X546050Y419250D01*
X547100Y417500D01*
X547450Y415500D01*
X547100Y413500D01*
X546225Y412000D01*
X544650Y411250D01*
X540450D01*
G01X561650Y405000D02*
X554650D01*
Y420000D01*
X561650D01*
G01X558850Y412750D02*
X554650D01*
G01X568500Y405000D02*
Y420000D01*
X572000D01*
X573400Y419250D01*
X574450Y418250D01*
X575325Y416750D01*
X576025Y415000D01*
X576200Y412500D01*
X576025Y410000D01*
X575325Y408250D01*
X574450Y406750D01*
X573400Y405750D01*
X572000Y405000D01*
X568500D01*
G01X582175D02*
X586550Y420000D01*
X590925Y405000D01*
G01X589350Y410250D02*
X583750D01*
G01X596725Y405000D02*
Y420000D01*
X604775Y405000D01*
Y420000D01*
G01X618800Y418750D02*
X617750Y419500D01*
X616525Y420000D01*
X615125D01*
X613550Y419250D01*
X612325Y418000D01*
X611450Y416500D01*
X610750Y414000D01*
X610575Y411750D01*
X610925Y409500D01*
X611450Y408000D01*
X612500Y406500D01*
X613725Y405500D01*
X614950Y405000D01*
X616175D01*
X617400Y405500D01*
X618450Y406250D01*
X619325Y407250D01*
G01X632650Y405000D02*
X625650D01*
Y420000D01*
X632650D01*
G01X629850Y412750D02*
X625650D01*
G01X661400Y418750D02*
X660350Y419500D01*
X659125Y420000D01*
X657725D01*
X656150Y419250D01*
X654925Y418000D01*
X654050Y416500D01*
X653350Y414000D01*
X653175Y411750D01*
X653525Y409500D01*
X654050Y408000D01*
X655100Y406500D01*
X656325Y405500D01*
X657550Y405000D01*
X658775D01*
X660000Y405500D01*
X661050Y406250D01*
X661925Y407250D01*
G01X671750Y405000D02*
X670350Y405250D01*
X669125Y406250D01*
X668075Y407750D01*
X667375Y409500D01*
X667025Y411500D01*
Y413500D01*
X667375Y415500D01*
X668075Y417250D01*
X669125Y418750D01*
X670350Y419750D01*
X671750Y420000D01*
X673150Y419750D01*
X674375Y418750D01*
X675425Y417250D01*
X676125Y415500D01*
X676475Y413500D01*
Y411500D01*
X676125Y409500D01*
X675425Y407750D01*
X674375Y406250D01*
X673150Y405250D01*
X671750Y405000D01*
G01X682100Y420000D02*
Y409250D01*
X682800Y407000D01*
X684200Y405500D01*
X685950Y405000D01*
X687700Y405500D01*
X689100Y407000D01*
X689800Y409250D01*
Y420000D01*
G01X696650Y405000D02*
Y420000D01*
X700850D01*
X702250Y419250D01*
X703300Y417500D01*
X703650Y415500D01*
X703300Y413500D01*
X702425Y412000D01*
X700850Y411250D01*
X696650D01*
G01X714350Y405000D02*
X712950Y405250D01*
X711725Y406250D01*
X710675Y407750D01*
X709975Y409500D01*
X709625Y411500D01*
Y413500D01*
X709975Y415500D01*
X710675Y417250D01*
X711725Y418750D01*
X712950Y419750D01*
X714350Y420000D01*
X715750Y419750D01*
X716975Y418750D01*
X718025Y417250D01*
X718725Y415500D01*
X719075Y413500D01*
Y411500D01*
X718725Y409500D01*
X718025Y407750D01*
X716975Y406250D01*
X715750Y405250D01*
X714350Y405000D01*
G01X724525D02*
Y420000D01*
X732575Y405000D01*
Y420000D01*
G01X-332950Y435000D02*
X-339950D01*
Y450000D01*
X-332950D01*
G01X-335750Y442750D02*
X-339950D01*
G01X-326625Y450000D02*
X-322250Y435000D01*
X-317875Y450000D01*
G01X-304550Y435000D02*
X-311550D01*
Y450000D01*
X-304550D01*
G01X-307350Y442750D02*
X-311550D01*
G01X-297350Y435000D02*
Y450000D01*
X-292975D01*
X-291575Y449250D01*
X-290700Y448250D01*
X-290350Y446250D01*
X-290700Y444250D01*
X-291750Y443000D01*
X-292975Y442250D01*
X-297350D01*
G01X-292975D02*
X-290350Y435000D01*
G01X-279650D02*
Y441750D01*
X-283150Y450000D01*
G01X-276150D02*
X-279650Y441750D01*
G01X-255100Y438000D02*
X-254050Y436250D01*
X-252650Y435250D01*
X-251075Y435000D01*
X-249675Y435250D01*
X-248275Y436500D01*
X-247400Y438000D01*
X-247225Y439500D01*
X-247575Y441250D01*
X-248800Y442500D01*
X-250025Y443000D01*
X-251600D01*
G01X-250025D02*
X-248975Y443750D01*
X-248100Y445000D01*
X-247750Y446500D01*
X-248100Y448000D01*
X-248975Y449250D01*
X-250550Y450000D01*
X-252125Y449750D01*
X-253700Y448750D01*
G01X-222850Y435000D02*
X-224250Y435250D01*
X-225475Y436250D01*
X-226525Y437750D01*
X-227225Y439500D01*
X-227575Y441500D01*
Y443500D01*
X-227225Y445500D01*
X-226525Y447250D01*
X-225475Y448750D01*
X-224250Y449750D01*
X-222850Y450000D01*
X-221450Y449750D01*
X-220225Y448750D01*
X-219175Y447250D01*
X-218475Y445500D01*
X-218125Y443500D01*
Y441500D01*
X-218475Y439500D01*
X-219175Y437750D01*
X-220225Y436250D01*
X-221450Y435250D01*
X-222850Y435000D01*
G01X-212150D02*
Y450000D01*
X-207775D01*
X-206375Y449250D01*
X-205500Y448250D01*
X-205150Y446250D01*
X-205500Y444250D01*
X-206550Y443000D01*
X-207775Y442250D01*
X-212150D01*
G01X-207775D02*
X-205150Y435000D01*
G01X-183750Y450000D02*
Y435000D01*
X-176750D01*
G01X-162550D02*
X-169550D01*
Y450000D01*
X-162550D01*
G01X-165350Y442750D02*
X-169550D01*
G01X-155525Y437000D02*
X-154125Y435750D01*
X-152550Y435000D01*
X-151150D01*
X-149750Y435750D01*
X-148700Y437000D01*
X-148175Y438750D01*
X-148525Y440500D01*
X-149400Y442000D01*
X-150975Y443000D01*
X-153075Y443500D01*
X-154300Y444500D01*
X-154825Y446250D01*
X-154475Y448000D01*
X-153600Y449250D01*
X-152375Y450000D01*
X-151150D01*
X-149925Y449500D01*
X-148875Y448250D01*
G01X-141325Y437000D02*
X-139925Y435750D01*
X-138350Y435000D01*
X-136950D01*
X-135550Y435750D01*
X-134500Y437000D01*
X-133975Y438750D01*
X-134325Y440500D01*
X-135200Y442000D01*
X-136775Y443000D01*
X-138875Y443500D01*
X-140100Y444500D01*
X-140625Y446250D01*
X-140275Y448000D01*
X-139400Y449250D01*
X-138175Y450000D01*
X-136950D01*
X-135725Y449500D01*
X-134675Y448250D01*
G01X-112750Y450000D02*
Y435000D01*
X-105750D01*
G01X-95050D02*
X-96450Y435250D01*
X-97675Y436250D01*
X-98725Y437750D01*
X-99425Y439500D01*
X-99775Y441500D01*
Y443500D01*
X-99425Y445500D01*
X-98725Y447250D01*
X-97675Y448750D01*
X-96450Y449750D01*
X-95050Y450000D01*
X-93650Y449750D01*
X-92425Y448750D01*
X-91375Y447250D01*
X-90675Y445500D01*
X-90325Y443500D01*
Y441500D01*
X-90675Y439500D01*
X-91375Y437750D01*
X-92425Y436250D01*
X-93650Y435250D01*
X-95050Y435000D01*
G01X-80850Y450000D02*
Y435000D01*
G01X-84875Y450000D02*
X-76825D01*
G01X-70325Y437000D02*
X-68925Y435750D01*
X-67350Y435000D01*
X-65950D01*
X-64550Y435750D01*
X-63500Y437000D01*
X-62975Y438750D01*
X-63325Y440500D01*
X-64200Y442000D01*
X-65775Y443000D01*
X-67875Y443500D01*
X-69100Y444500D01*
X-69625Y446250D01*
X-69275Y448000D01*
X-68400Y449250D01*
X-67175Y450000D01*
X-65950D01*
X-64725Y449500D01*
X-63675Y448250D01*
G01X-42625Y435000D02*
X-38250Y450000D01*
X-33875Y435000D01*
G01X-35450Y440250D02*
X-41050D01*
G01X-28075Y435000D02*
Y450000D01*
X-20025Y435000D01*
Y450000D01*
G01X-13700Y435000D02*
Y450000D01*
X-10200D01*
X-8800Y449250D01*
X-7750Y448250D01*
X-6875Y446750D01*
X-6175Y445000D01*
X-6000Y442500D01*
X-6175Y440000D01*
X-6875Y438250D01*
X-7750Y436750D01*
X-8800Y435750D01*
X-10200Y435000D01*
X-13700D01*
G01X14700Y437250D02*
X15750Y436000D01*
X16975Y435250D01*
X18550Y435000D01*
X20125Y435500D01*
X21350Y436500D01*
X22225Y438250D01*
X22400Y440250D01*
X22050Y442250D01*
X21175Y443500D01*
X19950Y444500D01*
X18725Y444750D01*
X17500Y444500D01*
X15925Y443500D01*
X16450Y450000D01*
X21175D01*
G01X32750D02*
X31350Y449500D01*
X30300Y448250D01*
X29600Y446750D01*
X29075Y444750D01*
X28900Y442500D01*
X29075Y440250D01*
X29600Y438250D01*
X30300Y436750D01*
X31350Y435500D01*
X32750Y435000D01*
X34150Y435500D01*
X35200Y436750D01*
X35900Y438250D01*
X36425Y440250D01*
X36600Y442500D01*
X36425Y444750D01*
X35900Y446750D01*
X35200Y448250D01*
X34150Y449500D01*
X32750Y450000D01*
G01X46950D02*
X45550Y449500D01*
X44500Y448250D01*
X43800Y446750D01*
X43275Y444750D01*
X43100Y442500D01*
X43275Y440250D01*
X43800Y438250D01*
X44500Y436750D01*
X45550Y435500D01*
X46950Y435000D01*
X48350Y435500D01*
X49400Y436750D01*
X50100Y438250D01*
X50625Y440250D01*
X50800Y442500D01*
X50625Y444750D01*
X50100Y446750D01*
X49400Y448250D01*
X48350Y449500D01*
X46950Y450000D01*
G01X61150D02*
X59750Y449500D01*
X58700Y448250D01*
X58000Y446750D01*
X57475Y444750D01*
X57300Y442500D01*
X57475Y440250D01*
X58000Y438250D01*
X58700Y436750D01*
X59750Y435500D01*
X61150Y435000D01*
X62550Y435500D01*
X63600Y436750D01*
X64300Y438250D01*
X64825Y440250D01*
X65000Y442500D01*
X64825Y444750D01*
X64300Y446750D01*
X63600Y448250D01*
X62550Y449500D01*
X61150Y450000D01*
G01X89550Y435000D02*
X88150Y435250D01*
X86925Y436250D01*
X85875Y437750D01*
X85175Y439500D01*
X84825Y441500D01*
Y443500D01*
X85175Y445500D01*
X85875Y447250D01*
X86925Y448750D01*
X88150Y449750D01*
X89550Y450000D01*
X90950Y449750D01*
X92175Y448750D01*
X93225Y447250D01*
X93925Y445500D01*
X94275Y443500D01*
Y441500D01*
X93925Y439500D01*
X93225Y437750D01*
X92175Y436250D01*
X90950Y435250D01*
X89550Y435000D01*
G01X100250D02*
Y450000D01*
X104625D01*
X106025Y449250D01*
X106900Y448250D01*
X107250Y446250D01*
X106900Y444250D01*
X105850Y443000D01*
X104625Y442250D01*
X100250D01*
G01X104625D02*
X107250Y435000D01*
G01X128650Y450000D02*
Y435000D01*
X135650D01*
G01X149850D02*
X142850D01*
Y450000D01*
X149850D01*
G01X147050Y442750D02*
X142850D01*
G01X156875Y437000D02*
X158275Y435750D01*
X159850Y435000D01*
X161250D01*
X162650Y435750D01*
X163700Y437000D01*
X164225Y438750D01*
X163875Y440500D01*
X163000Y442000D01*
X161425Y443000D01*
X159325Y443500D01*
X158100Y444500D01*
X157575Y446250D01*
X157925Y448000D01*
X158800Y449250D01*
X160025Y450000D01*
X161250D01*
X162475Y449500D01*
X163525Y448250D01*
G01X171075Y437000D02*
X172475Y435750D01*
X174050Y435000D01*
X175450D01*
X176850Y435750D01*
X177900Y437000D01*
X178425Y438750D01*
X178075Y440500D01*
X177200Y442000D01*
X175625Y443000D01*
X173525Y443500D01*
X172300Y444500D01*
X171775Y446250D01*
X172125Y448000D01*
X173000Y449250D01*
X174225Y450000D01*
X175450D01*
X176675Y449500D01*
X177725Y448250D01*
G01X204550Y443000D02*
X205250Y443750D01*
X205775Y445000D01*
X206125Y446750D01*
X205775Y448250D01*
X205075Y449250D01*
X203850Y450000D01*
X199125D01*
Y435000D01*
X204900D01*
X206125Y436000D01*
X206825Y437500D01*
X207175Y439250D01*
X206825Y441000D01*
X205775Y442500D01*
X204550Y443000D01*
X199125D01*
G01X217350Y435000D02*
X215950Y435250D01*
X214725Y436250D01*
X213675Y437750D01*
X212975Y439500D01*
X212625Y441500D01*
Y443500D01*
X212975Y445500D01*
X213675Y447250D01*
X214725Y448750D01*
X215950Y449750D01*
X217350Y450000D01*
X218750Y449750D01*
X219975Y448750D01*
X221025Y447250D01*
X221725Y445500D01*
X222075Y443500D01*
Y441500D01*
X221725Y439500D01*
X221025Y437750D01*
X219975Y436250D01*
X218750Y435250D01*
X217350Y435000D01*
G01X227175D02*
X231550Y450000D01*
X235925Y435000D01*
G01X234350Y440250D02*
X228750D01*
G01X242250Y435000D02*
Y450000D01*
X246625D01*
X248025Y449250D01*
X248900Y448250D01*
X249250Y446250D01*
X248900Y444250D01*
X247850Y443000D01*
X246625Y442250D01*
X242250D01*
G01X246625D02*
X249250Y435000D01*
G01X256100D02*
Y450000D01*
X259600D01*
X261000Y449250D01*
X262050Y448250D01*
X262925Y446750D01*
X263625Y445000D01*
X263800Y442500D01*
X263625Y440000D01*
X262925Y438250D01*
X262050Y436750D01*
X261000Y435750D01*
X259600Y435000D01*
X256100D01*
G01X270475Y437000D02*
X271875Y435750D01*
X273450Y435000D01*
X274850D01*
X276250Y435750D01*
X277300Y437000D01*
X277825Y438750D01*
X277475Y440500D01*
X276600Y442000D01*
X275025Y443000D01*
X272925Y443500D01*
X271700Y444500D01*
X271175Y446250D01*
X271525Y448000D01*
X272400Y449250D01*
X273625Y450000D01*
X274850D01*
X276075Y449500D01*
X277125Y448250D01*
G01X288000Y432250D02*
X288700Y435500D01*
G01X316750Y450000D02*
Y435000D01*
G01X312725Y450000D02*
X320775D01*
G01X327275Y435000D02*
Y450000D01*
G01X334625D02*
Y435000D01*
G01Y442500D02*
X327275D01*
G01X348650Y435000D02*
X341650D01*
Y450000D01*
X348650D01*
G01X345850Y442750D02*
X341650D01*
G01X370225Y435000D02*
Y450000D01*
X376875D01*
G01X374425Y442750D02*
X370225D01*
G01X387750Y435000D02*
X386350Y435250D01*
X385125Y436250D01*
X384075Y437750D01*
X383375Y439500D01*
X383025Y441500D01*
Y443500D01*
X383375Y445500D01*
X384075Y447250D01*
X385125Y448750D01*
X386350Y449750D01*
X387750Y450000D01*
X389150Y449750D01*
X390375Y448750D01*
X391425Y447250D01*
X392125Y445500D01*
X392475Y443500D01*
Y441500D01*
X392125Y439500D01*
X391425Y437750D01*
X390375Y436250D01*
X389150Y435250D01*
X387750Y435000D01*
G01X398450Y450000D02*
Y435000D01*
X405450D01*
G01X412650Y450000D02*
Y435000D01*
X419650D01*
G01X430350D02*
X428950Y435250D01*
X427725Y436250D01*
X426675Y437750D01*
X425975Y439500D01*
X425625Y441500D01*
Y443500D01*
X425975Y445500D01*
X426675Y447250D01*
X427725Y448750D01*
X428950Y449750D01*
X430350Y450000D01*
X431750Y449750D01*
X432975Y448750D01*
X434025Y447250D01*
X434725Y445500D01*
X435075Y443500D01*
Y441500D01*
X434725Y439500D01*
X434025Y437750D01*
X432975Y436250D01*
X431750Y435250D01*
X430350Y435000D01*
G01X439300Y450000D02*
X441750Y435000D01*
X444550Y450000D01*
X447350Y435000D01*
X449800Y450000D01*
G01X456650D02*
X460850D01*
G01X458750D02*
Y435000D01*
G01X456650D02*
X460850D01*
G01X468925D02*
Y450000D01*
X476975Y435000D01*
Y450000D01*
G01X488200Y442500D02*
X491700D01*
Y438000D01*
X490650Y436500D01*
X489425Y435500D01*
X487675Y435000D01*
X485925Y435500D01*
X484700Y436500D01*
X483650Y438000D01*
X482950Y439750D01*
X482600Y441750D01*
Y443500D01*
X482950Y445000D01*
X483650Y446750D01*
X484700Y448250D01*
X485750Y449250D01*
X487150Y450000D01*
X488375D01*
X489775Y449500D01*
X490825Y448500D01*
G01X515550Y450000D02*
Y435000D01*
G01X511525Y450000D02*
X519575D01*
G01X533250Y435000D02*
X526250D01*
Y450000D01*
X533250D01*
G01X530450Y442750D02*
X526250D01*
G01X540275Y437000D02*
X541675Y435750D01*
X543250Y435000D01*
X544650D01*
X546050Y435750D01*
X547100Y437000D01*
X547625Y438750D01*
X547275Y440500D01*
X546400Y442000D01*
X544825Y443000D01*
X542725Y443500D01*
X541500Y444500D01*
X540975Y446250D01*
X541325Y448000D01*
X542200Y449250D01*
X543425Y450000D01*
X544650D01*
X545875Y449500D01*
X546925Y448250D01*
G01X558150Y450000D02*
Y435000D01*
G01X554125Y450000D02*
X562175D01*
G01X568675Y437000D02*
X570075Y435750D01*
X571650Y435000D01*
X573050D01*
X574450Y435750D01*
X575500Y437000D01*
X576025Y438750D01*
X575675Y440500D01*
X574800Y442000D01*
X573225Y443000D01*
X571125Y443500D01*
X569900Y444500D01*
X569375Y446250D01*
X569725Y448000D01*
X570600Y449250D01*
X571825Y450000D01*
X573050D01*
X574275Y449500D01*
X575325Y448250D01*
G01X596375Y435000D02*
X600750Y450000D01*
X605125Y435000D01*
G01X603550Y440250D02*
X597950D01*
G01X611450Y435000D02*
Y450000D01*
X615825D01*
X617225Y449250D01*
X618100Y448250D01*
X618450Y446250D01*
X618100Y444250D01*
X617050Y443000D01*
X615825Y442250D01*
X611450D01*
G01X615825D02*
X618450Y435000D01*
G01X632650D02*
X625650D01*
Y450000D01*
X632650D01*
G01X629850Y442750D02*
X625650D01*
G01X654050Y435000D02*
Y450000D01*
X658425D01*
X659825Y449250D01*
X660700Y448250D01*
X661050Y446250D01*
X660700Y444250D01*
X659650Y443000D01*
X658425Y442250D01*
X654050D01*
G01X658425D02*
X661050Y435000D01*
G01X675250D02*
X668250D01*
Y450000D01*
X675250D01*
G01X672450Y442750D02*
X668250D01*
G01X685950Y435000D02*
X684550Y435250D01*
X683325Y436250D01*
X682275Y437750D01*
X681575Y439500D01*
X681225Y441500D01*
Y443500D01*
X681575Y445500D01*
X682275Y447250D01*
X683325Y448750D01*
X684550Y449750D01*
X685950Y450000D01*
X687350Y449750D01*
X688575Y448750D01*
X689625Y447250D01*
X690325Y445500D01*
X690675Y443500D01*
Y441500D01*
X690325Y439500D01*
X689625Y437750D01*
X688575Y436250D01*
X687350Y435250D01*
X685950Y435000D01*
G01X687350Y439000D02*
X689450Y435000D01*
G01X696300Y450000D02*
Y439250D01*
X697000Y437000D01*
X698400Y435500D01*
X700150Y435000D01*
X701900Y435500D01*
X703300Y437000D01*
X704000Y439250D01*
Y450000D01*
G01X712250D02*
X716450D01*
G01X714350D02*
Y435000D01*
G01X712250D02*
X716450D01*
G01X725050D02*
Y450000D01*
X729425D01*
X730825Y449250D01*
X731700Y448250D01*
X732050Y446250D01*
X731700Y444250D01*
X730650Y443000D01*
X729425Y442250D01*
X725050D01*
G01X729425D02*
X732050Y435000D01*
G01X746250D02*
X739250D01*
Y450000D01*
X746250D01*
G01X743450Y442750D02*
X739250D01*
G01X753100Y435000D02*
Y450000D01*
X756600D01*
X758000Y449250D01*
X759050Y448250D01*
X759925Y446750D01*
X760625Y445000D01*
X760800Y442500D01*
X760625Y440000D01*
X759925Y438250D01*
X759050Y436750D01*
X758000Y435750D01*
X756600Y435000D01*
X753100D01*
G01X-396575Y477500D02*
X-395525Y479000D01*
X-394300Y479750D01*
X-392900Y480000D01*
X-391150Y479500D01*
X-389925Y478250D01*
X-389575Y476750D01*
X-389750Y475250D01*
X-390450Y474000D01*
X-393950Y471500D01*
X-395525Y469750D01*
X-396575Y467250D01*
X-396925Y465000D01*
X-389575D01*
G01X-382900Y467250D02*
X-381850Y466000D01*
X-380625Y465250D01*
X-379050Y465000D01*
X-377475Y465500D01*
X-376250Y466500D01*
X-375375Y468250D01*
X-375200Y470250D01*
X-375550Y472250D01*
X-376425Y473500D01*
X-377650Y474500D01*
X-378875Y474750D01*
X-380100Y474500D01*
X-381675Y473500D01*
X-381150Y480000D01*
X-376425D01*
G01X-364850Y464500D02*
X-365200Y464750D01*
Y465250D01*
X-364850Y465500D01*
X-364500Y465250D01*
Y464750D01*
X-364850Y464500D01*
G01X-339950Y465000D02*
Y480000D01*
X-335575D01*
X-334175Y479250D01*
X-333300Y478250D01*
X-332950Y476250D01*
X-333300Y474250D01*
X-334350Y473000D01*
X-335575Y472250D01*
X-339950D01*
G01X-335575D02*
X-332950Y465000D01*
G01X-318750D02*
X-325750D01*
Y480000D01*
X-318750D01*
G01X-321550Y472750D02*
X-325750D01*
G01X-308050Y465000D02*
X-309450Y465250D01*
X-310675Y466250D01*
X-311725Y467750D01*
X-312425Y469500D01*
X-312775Y471500D01*
Y473500D01*
X-312425Y475500D01*
X-311725Y477250D01*
X-310675Y478750D01*
X-309450Y479750D01*
X-308050Y480000D01*
X-306650Y479750D01*
X-305425Y478750D01*
X-304375Y477250D01*
X-303675Y475500D01*
X-303325Y473500D01*
Y471500D01*
X-303675Y469500D01*
X-304375Y467750D01*
X-305425Y466250D01*
X-306650Y465250D01*
X-308050Y465000D01*
G01X-306650Y469000D02*
X-304550Y465000D01*
G01X-297700Y480000D02*
Y469250D01*
X-297000Y467000D01*
X-295600Y465500D01*
X-293850Y465000D01*
X-292100Y465500D01*
X-290700Y467000D01*
X-290000Y469250D01*
Y480000D01*
G01X-281750D02*
X-277550D01*
G01X-279650D02*
Y465000D01*
G01X-281750D02*
X-277550D01*
G01X-268950D02*
Y480000D01*
X-264575D01*
X-263175Y479250D01*
X-262300Y478250D01*
X-261950Y476250D01*
X-262300Y474250D01*
X-263350Y473000D01*
X-264575Y472250D01*
X-268950D01*
G01X-264575D02*
X-261950Y465000D01*
G01X-247750D02*
X-254750D01*
Y480000D01*
X-247750D01*
G01X-250550Y472750D02*
X-254750D01*
G01X-240900Y465000D02*
Y480000D01*
X-237400D01*
X-236000Y479250D01*
X-234950Y478250D01*
X-234075Y476750D01*
X-233375Y475000D01*
X-233200Y472500D01*
X-233375Y470000D01*
X-234075Y468250D01*
X-234950Y466750D01*
X-236000Y465750D01*
X-237400Y465000D01*
X-240900D01*
G01X-212150D02*
Y480000D01*
X-207775D01*
X-206375Y479250D01*
X-205500Y478250D01*
X-205150Y476250D01*
X-205500Y474250D01*
X-206550Y473000D01*
X-207775Y472250D01*
X-212150D01*
G01X-207775D02*
X-205150Y465000D01*
G01X-190950D02*
X-197950D01*
Y480000D01*
X-190950D01*
G01X-193750Y472750D02*
X-197950D01*
G01X-183750Y465000D02*
Y480000D01*
X-179550D01*
X-178150Y479250D01*
X-177100Y477500D01*
X-176750Y475500D01*
X-177100Y473500D01*
X-177975Y472000D01*
X-179550Y471250D01*
X-183750D01*
G01X-166050Y465000D02*
X-167450Y465250D01*
X-168675Y466250D01*
X-169725Y467750D01*
X-170425Y469500D01*
X-170775Y471500D01*
Y473500D01*
X-170425Y475500D01*
X-169725Y477250D01*
X-168675Y478750D01*
X-167450Y479750D01*
X-166050Y480000D01*
X-164650Y479750D01*
X-163425Y478750D01*
X-162375Y477250D01*
X-161675Y475500D01*
X-161325Y473500D01*
Y471500D01*
X-161675Y469500D01*
X-162375Y467750D01*
X-163425Y466250D01*
X-164650Y465250D01*
X-166050Y465000D01*
G01X-155350D02*
Y480000D01*
X-150975D01*
X-149575Y479250D01*
X-148700Y478250D01*
X-148350Y476250D01*
X-148700Y474250D01*
X-149750Y473000D01*
X-150975Y472250D01*
X-155350D01*
G01X-150975D02*
X-148350Y465000D01*
G01X-137650Y480000D02*
Y465000D01*
G01X-141675Y480000D02*
X-133625D01*
G01X-109250Y465000D02*
X-110650Y465250D01*
X-111875Y466250D01*
X-112925Y467750D01*
X-113625Y469500D01*
X-113975Y471500D01*
Y473500D01*
X-113625Y475500D01*
X-112925Y477250D01*
X-111875Y478750D01*
X-110650Y479750D01*
X-109250Y480000D01*
X-107850Y479750D01*
X-106625Y478750D01*
X-105575Y477250D01*
X-104875Y475500D01*
X-104525Y473500D01*
Y471500D01*
X-104875Y469500D01*
X-105575Y467750D01*
X-106625Y466250D01*
X-107850Y465250D01*
X-109250Y465000D01*
G01X-98375D02*
Y480000D01*
X-91725D01*
G01X-94175Y472750D02*
X-98375D01*
G01X-70150Y465000D02*
Y480000D01*
X-65950D01*
X-64550Y479250D01*
X-63500Y477500D01*
X-63150Y475500D01*
X-63500Y473500D01*
X-64375Y472000D01*
X-65950Y471250D01*
X-70150D01*
G01X-55950Y465000D02*
Y480000D01*
X-51575D01*
X-50175Y479250D01*
X-49300Y478250D01*
X-48950Y476250D01*
X-49300Y474250D01*
X-50350Y473000D01*
X-51575Y472250D01*
X-55950D01*
G01X-51575D02*
X-48950Y465000D01*
G01X-38250D02*
X-39650Y465250D01*
X-40875Y466250D01*
X-41925Y467750D01*
X-42625Y469500D01*
X-42975Y471500D01*
Y473500D01*
X-42625Y475500D01*
X-41925Y477250D01*
X-40875Y478750D01*
X-39650Y479750D01*
X-38250Y480000D01*
X-36850Y479750D01*
X-35625Y478750D01*
X-34575Y477250D01*
X-33875Y475500D01*
X-33525Y473500D01*
Y471500D01*
X-33875Y469500D01*
X-34575Y467750D01*
X-35625Y466250D01*
X-36850Y465250D01*
X-38250Y465000D01*
G01X-27900D02*
Y480000D01*
X-24400D01*
X-23000Y479250D01*
X-21950Y478250D01*
X-21075Y476750D01*
X-20375Y475000D01*
X-20200Y472500D01*
X-20375Y470000D01*
X-21075Y468250D01*
X-21950Y466750D01*
X-23000Y465750D01*
X-24400Y465000D01*
X-27900D01*
G01X-13700Y480000D02*
Y469250D01*
X-13000Y467000D01*
X-11600Y465500D01*
X-9850Y465000D01*
X-8100Y465500D01*
X-6700Y467000D01*
X-6000Y469250D01*
Y480000D01*
G01X8200Y478750D02*
X7150Y479500D01*
X5925Y480000D01*
X4525D01*
X2950Y479250D01*
X1725Y478000D01*
X850Y476500D01*
X150Y474000D01*
X-25Y471750D01*
X325Y469500D01*
X850Y468000D01*
X1900Y466500D01*
X3125Y465500D01*
X4350Y465000D01*
X5575D01*
X6800Y465500D01*
X7850Y466250D01*
X8725Y467250D01*
G01X18550Y480000D02*
Y465000D01*
G01X14525Y480000D02*
X22575D01*
G01X30650D02*
X34850D01*
G01X32750D02*
Y465000D01*
G01X30650D02*
X34850D01*
G01X46950D02*
X45550Y465250D01*
X44325Y466250D01*
X43275Y467750D01*
X42575Y469500D01*
X42225Y471500D01*
Y473500D01*
X42575Y475500D01*
X43275Y477250D01*
X44325Y478750D01*
X45550Y479750D01*
X46950Y480000D01*
X48350Y479750D01*
X49575Y478750D01*
X50625Y477250D01*
X51325Y475500D01*
X51675Y473500D01*
Y471500D01*
X51325Y469500D01*
X50625Y467750D01*
X49575Y466250D01*
X48350Y465250D01*
X46950Y465000D01*
G01X57125D02*
Y480000D01*
X65175Y465000D01*
Y480000D01*
G01X90950Y473000D02*
X91650Y473750D01*
X92175Y475000D01*
X92525Y476750D01*
X92175Y478250D01*
X91475Y479250D01*
X90250Y480000D01*
X85525D01*
Y465000D01*
X91300D01*
X92525Y466000D01*
X93225Y467500D01*
X93575Y469250D01*
X93225Y471000D01*
X92175Y472500D01*
X90950Y473000D01*
X85525D01*
G01X103750Y465000D02*
X102350Y465250D01*
X101125Y466250D01*
X100075Y467750D01*
X99375Y469500D01*
X99025Y471500D01*
Y473500D01*
X99375Y475500D01*
X100075Y477250D01*
X101125Y478750D01*
X102350Y479750D01*
X103750Y480000D01*
X105150Y479750D01*
X106375Y478750D01*
X107425Y477250D01*
X108125Y475500D01*
X108475Y473500D01*
Y471500D01*
X108125Y469500D01*
X107425Y467750D01*
X106375Y466250D01*
X105150Y465250D01*
X103750Y465000D01*
G01X113575D02*
X117950Y480000D01*
X122325Y465000D01*
G01X120750Y470250D02*
X115150D01*
G01X128650Y465000D02*
Y480000D01*
X133025D01*
X134425Y479250D01*
X135300Y478250D01*
X135650Y476250D01*
X135300Y474250D01*
X134250Y473000D01*
X133025Y472250D01*
X128650D01*
G01X133025D02*
X135650Y465000D01*
G01X142500D02*
Y480000D01*
X146000D01*
X147400Y479250D01*
X148450Y478250D01*
X149325Y476750D01*
X150025Y475000D01*
X150200Y472500D01*
X150025Y470000D01*
X149325Y468250D01*
X148450Y466750D01*
X147400Y465750D01*
X146000Y465000D01*
X142500D01*
G01X156875Y467000D02*
X158275Y465750D01*
X159850Y465000D01*
X161250D01*
X162650Y465750D01*
X163700Y467000D01*
X164225Y468750D01*
X163875Y470500D01*
X163000Y472000D01*
X161425Y473000D01*
X159325Y473500D01*
X158100Y474500D01*
X157575Y476250D01*
X157925Y478000D01*
X158800Y479250D01*
X160025Y480000D01*
X161250D01*
X162475Y479500D01*
X163525Y478250D01*
G01X174750Y464500D02*
X174400Y464750D01*
Y465250D01*
X174750Y465500D01*
X175100Y465250D01*
Y464750D01*
X174750Y464500D01*
G01Y471250D02*
X174400Y471500D01*
Y472000D01*
X174750Y472250D01*
X175100Y472000D01*
Y471500D01*
X174750Y471250D01*
G01X-337325Y490000D02*
X-339075Y492500D01*
X-339950Y495000D01*
Y505000D01*
X-339075Y507500D01*
X-337325Y510000D01*
G01X-324350D02*
X-320150D01*
G01X-322250D02*
Y495000D01*
G01X-324350D02*
X-320150D01*
G01X-312600D02*
Y510000D01*
X-308050Y497500D01*
X-303500Y510000D01*
Y495000D01*
G01X-297350D02*
Y510000D01*
X-293150D01*
X-291750Y509250D01*
X-290700Y507500D01*
X-290350Y505500D01*
X-290700Y503500D01*
X-291575Y502000D01*
X-293150Y501250D01*
X-297350D01*
G01X-276150Y495000D02*
X-283150D01*
Y510000D01*
X-276150D01*
G01X-278950Y502750D02*
X-283150D01*
G01X-269300Y495000D02*
Y510000D01*
X-265800D01*
X-264400Y509250D01*
X-263350Y508250D01*
X-262475Y506750D01*
X-261775Y505000D01*
X-261600Y502500D01*
X-261775Y500000D01*
X-262475Y498250D01*
X-263350Y496750D01*
X-264400Y495750D01*
X-265800Y495000D01*
X-269300D01*
G01X-255625D02*
X-251250Y510000D01*
X-246875Y495000D01*
G01X-248450Y500250D02*
X-254050D01*
G01X-241075Y495000D02*
Y510000D01*
X-233025Y495000D01*
Y510000D01*
G01X-219000Y508750D02*
X-220050Y509500D01*
X-221275Y510000D01*
X-222675D01*
X-224250Y509250D01*
X-225475Y508000D01*
X-226350Y506500D01*
X-227050Y504000D01*
X-227225Y501750D01*
X-226875Y499500D01*
X-226350Y498000D01*
X-225300Y496500D01*
X-224075Y495500D01*
X-222850Y495000D01*
X-221625D01*
X-220400Y495500D01*
X-219350Y496250D01*
X-218475Y497250D01*
G01X-205150Y495000D02*
X-212150D01*
Y510000D01*
X-205150D01*
G01X-207950Y502750D02*
X-212150D01*
G01X-198125Y497000D02*
X-196725Y495750D01*
X-195150Y495000D01*
X-193750D01*
X-192350Y495750D01*
X-191300Y497000D01*
X-190775Y498750D01*
X-191125Y500500D01*
X-192000Y502000D01*
X-193575Y503000D01*
X-195675Y503500D01*
X-196900Y504500D01*
X-197425Y506250D01*
X-197075Y508000D01*
X-196200Y509250D01*
X-194975Y510000D01*
X-193750D01*
X-192525Y509500D01*
X-191475Y508250D01*
G01X-169725Y497000D02*
X-168325Y495750D01*
X-166750Y495000D01*
X-165350D01*
X-163950Y495750D01*
X-162900Y497000D01*
X-162375Y498750D01*
X-162725Y500500D01*
X-163600Y502000D01*
X-165175Y503000D01*
X-167275Y503500D01*
X-168500Y504500D01*
X-169025Y506250D01*
X-168675Y508000D01*
X-167800Y509250D01*
X-166575Y510000D01*
X-165350D01*
X-164125Y509500D01*
X-163075Y508250D01*
G01X-155700Y510000D02*
Y499250D01*
X-155000Y497000D01*
X-153600Y495500D01*
X-151850Y495000D01*
X-150100Y495500D01*
X-148700Y497000D01*
X-148000Y499250D01*
Y510000D01*
G01X-136250Y503000D02*
X-135550Y503750D01*
X-135025Y505000D01*
X-134675Y506750D01*
X-135025Y508250D01*
X-135725Y509250D01*
X-136950Y510000D01*
X-141675D01*
Y495000D01*
X-135900D01*
X-134675Y496000D01*
X-133975Y497500D01*
X-133625Y499250D01*
X-133975Y501000D01*
X-135025Y502500D01*
X-136250Y503000D01*
X-141675D01*
G01X-126950Y498000D02*
X-126075Y496500D01*
X-125025Y495500D01*
X-123800Y495000D01*
X-122400Y495500D01*
X-121350Y496500D01*
X-120300Y498000D01*
X-119950Y500000D01*
Y510000D01*
G01X-105750Y495000D02*
X-112750D01*
Y510000D01*
X-105750D01*
G01X-108550Y502750D02*
X-112750D01*
G01X-91200Y508750D02*
X-92250Y509500D01*
X-93475Y510000D01*
X-94875D01*
X-96450Y509250D01*
X-97675Y508000D01*
X-98550Y506500D01*
X-99250Y504000D01*
X-99425Y501750D01*
X-99075Y499500D01*
X-98550Y498000D01*
X-97500Y496500D01*
X-96275Y495500D01*
X-95050Y495000D01*
X-93825D01*
X-92600Y495500D01*
X-91550Y496250D01*
X-90675Y497250D01*
G01X-80850Y510000D02*
Y495000D01*
G01X-84875Y510000D02*
X-76825D01*
G01X-52450D02*
Y495000D01*
G01X-56475Y510000D02*
X-48425D01*
G01X-38250Y495000D02*
X-39650Y495250D01*
X-40875Y496250D01*
X-41925Y497750D01*
X-42625Y499500D01*
X-42975Y501500D01*
Y503500D01*
X-42625Y505500D01*
X-41925Y507250D01*
X-40875Y508750D01*
X-39650Y509750D01*
X-38250Y510000D01*
X-36850Y509750D01*
X-35625Y508750D01*
X-34575Y507250D01*
X-33875Y505500D01*
X-33525Y503500D01*
Y501500D01*
X-33875Y499500D01*
X-34575Y497750D01*
X-35625Y496250D01*
X-36850Y495250D01*
X-38250Y495000D01*
G01X-6000Y508750D02*
X-7050Y509500D01*
X-8275Y510000D01*
X-9675D01*
X-11250Y509250D01*
X-12475Y508000D01*
X-13350Y506500D01*
X-14050Y504000D01*
X-14225Y501750D01*
X-13875Y499500D01*
X-13350Y498000D01*
X-12300Y496500D01*
X-11075Y495500D01*
X-9850Y495000D01*
X-8625D01*
X-7400Y495500D01*
X-6350Y496250D01*
X-5475Y497250D01*
G01X675Y495000D02*
Y510000D01*
G01X8025D02*
Y495000D01*
G01Y502500D02*
X675D01*
G01X14175Y495000D02*
X18550Y510000D01*
X22925Y495000D01*
G01X21350Y500250D02*
X15750D01*
G01X28725Y495000D02*
Y510000D01*
X36775Y495000D01*
Y510000D01*
G01X48000Y502500D02*
X51500D01*
Y498000D01*
X50450Y496500D01*
X49225Y495500D01*
X47475Y495000D01*
X45725Y495500D01*
X44500Y496500D01*
X43450Y498000D01*
X42750Y499750D01*
X42400Y501750D01*
Y503500D01*
X42750Y505000D01*
X43450Y506750D01*
X44500Y508250D01*
X45550Y509250D01*
X46950Y510000D01*
X48175D01*
X49575Y509500D01*
X50625Y508500D01*
G01X64650Y495000D02*
X57650D01*
Y510000D01*
X64650D01*
G01X61850Y502750D02*
X57650D01*
G01X86050Y495000D02*
Y510000D01*
X90250D01*
X91650Y509250D01*
X92700Y507500D01*
X93050Y505500D01*
X92700Y503500D01*
X91825Y502000D01*
X90250Y501250D01*
X86050D01*
G01X107250Y495000D02*
X100250D01*
Y510000D01*
X107250D01*
G01X104450Y502750D02*
X100250D01*
G01X114450Y495000D02*
Y510000D01*
X118825D01*
X120225Y509250D01*
X121100Y508250D01*
X121450Y506250D01*
X121100Y504250D01*
X120050Y503000D01*
X118825Y502250D01*
X114450D01*
G01X118825D02*
X121450Y495000D01*
G01X142850D02*
Y510000D01*
X147050D01*
X148450Y509250D01*
X149500Y507500D01*
X149850Y505500D01*
X149500Y503500D01*
X148625Y502000D01*
X147050Y501250D01*
X142850D01*
G01X157050Y495000D02*
Y510000D01*
X161425D01*
X162825Y509250D01*
X163700Y508250D01*
X164050Y506250D01*
X163700Y504250D01*
X162650Y503000D01*
X161425Y502250D01*
X157050D01*
G01X161425D02*
X164050Y495000D01*
G01X174750D02*
X173350Y495250D01*
X172125Y496250D01*
X171075Y497750D01*
X170375Y499500D01*
X170025Y501500D01*
Y503500D01*
X170375Y505500D01*
X171075Y507250D01*
X172125Y508750D01*
X173350Y509750D01*
X174750Y510000D01*
X176150Y509750D01*
X177375Y508750D01*
X178425Y507250D01*
X179125Y505500D01*
X179475Y503500D01*
Y501500D01*
X179125Y499500D01*
X178425Y497750D01*
X177375Y496250D01*
X176150Y495250D01*
X174750Y495000D01*
G01X185450Y498000D02*
X186325Y496500D01*
X187375Y495500D01*
X188600Y495000D01*
X190000Y495500D01*
X191050Y496500D01*
X192100Y498000D01*
X192450Y500000D01*
Y510000D01*
G01X206650Y495000D02*
X199650D01*
Y510000D01*
X206650D01*
G01X203850Y502750D02*
X199650D01*
G01X221200Y508750D02*
X220150Y509500D01*
X218925Y510000D01*
X217525D01*
X215950Y509250D01*
X214725Y508000D01*
X213850Y506500D01*
X213150Y504000D01*
X212975Y501750D01*
X213325Y499500D01*
X213850Y498000D01*
X214900Y496500D01*
X216125Y495500D01*
X217350Y495000D01*
X218575D01*
X219800Y495500D01*
X220850Y496250D01*
X221725Y497250D01*
G01X231550Y510000D02*
Y495000D01*
G01X227525Y510000D02*
X235575D01*
G01X256450Y495000D02*
Y510000D01*
X260825D01*
X262225Y509250D01*
X263100Y508250D01*
X263450Y506250D01*
X263100Y504250D01*
X262050Y503000D01*
X260825Y502250D01*
X256450D01*
G01X260825D02*
X263450Y495000D01*
G01X277650D02*
X270650D01*
Y510000D01*
X277650D01*
G01X274850Y502750D02*
X270650D01*
G01X288350Y495000D02*
X286950Y495250D01*
X285725Y496250D01*
X284675Y497750D01*
X283975Y499500D01*
X283625Y501500D01*
Y503500D01*
X283975Y505500D01*
X284675Y507250D01*
X285725Y508750D01*
X286950Y509750D01*
X288350Y510000D01*
X289750Y509750D01*
X290975Y508750D01*
X292025Y507250D01*
X292725Y505500D01*
X293075Y503500D01*
Y501500D01*
X292725Y499500D01*
X292025Y497750D01*
X290975Y496250D01*
X289750Y495250D01*
X288350Y495000D01*
G01X289750Y499000D02*
X291850Y495000D01*
G01X298700Y510000D02*
Y499250D01*
X299400Y497000D01*
X300800Y495500D01*
X302550Y495000D01*
X304300Y495500D01*
X305700Y497000D01*
X306400Y499250D01*
Y510000D01*
G01X314650D02*
X318850D01*
G01X316750D02*
Y495000D01*
G01X314650D02*
X318850D01*
G01X327450D02*
Y510000D01*
X331825D01*
X333225Y509250D01*
X334100Y508250D01*
X334450Y506250D01*
X334100Y504250D01*
X333050Y503000D01*
X331825Y502250D01*
X327450D01*
G01X331825D02*
X334450Y495000D01*
G01X348650D02*
X341650D01*
Y510000D01*
X348650D01*
G01X345850Y502750D02*
X341650D01*
G01X354800Y495000D02*
Y510000D01*
X359350Y497500D01*
X363900Y510000D01*
Y495000D01*
G01X377050D02*
X370050D01*
Y510000D01*
X377050D01*
G01X374250Y502750D02*
X370050D01*
G01X383725Y495000D02*
Y510000D01*
X391775Y495000D01*
Y510000D01*
G01X401950D02*
Y495000D01*
G01X397925Y510000D02*
X405975D01*
G01X412475Y497000D02*
X413875Y495750D01*
X415450Y495000D01*
X416850D01*
X418250Y495750D01*
X419300Y497000D01*
X419825Y498750D01*
X419475Y500500D01*
X418600Y502000D01*
X417025Y503000D01*
X414925Y503500D01*
X413700Y504500D01*
X413175Y506250D01*
X413525Y508000D01*
X414400Y509250D01*
X415625Y510000D01*
X416850D01*
X418075Y509500D01*
X419125Y508250D01*
G01X431225Y490000D02*
X432975Y492500D01*
X433850Y495000D01*
Y505000D01*
X432975Y507500D01*
X431225Y510000D01*
G01X-237050Y545000D02*
Y530000D01*
G01X-241075Y545000D02*
X-233025D01*
G01X-226525Y530000D02*
Y545000D01*
G01X-219175D02*
Y530000D01*
G01Y537500D02*
X-226525D01*
G01X-205150Y530000D02*
X-212150D01*
Y545000D01*
X-205150D01*
G01X-207950Y537750D02*
X-212150D01*
G01X-183925Y532000D02*
X-182525Y530750D01*
X-180950Y530000D01*
X-179550D01*
X-178150Y530750D01*
X-177100Y532000D01*
X-176575Y533750D01*
X-176925Y535500D01*
X-177800Y537000D01*
X-179375Y538000D01*
X-181475Y538500D01*
X-182700Y539500D01*
X-183225Y541250D01*
X-182875Y543000D01*
X-182000Y544250D01*
X-180775Y545000D01*
X-179550D01*
X-178325Y544500D01*
X-177275Y543250D01*
G01X-166050Y530000D02*
X-167450Y530250D01*
X-168675Y531250D01*
X-169725Y532750D01*
X-170425Y534500D01*
X-170775Y536500D01*
Y538500D01*
X-170425Y540500D01*
X-169725Y542250D01*
X-168675Y543750D01*
X-167450Y544750D01*
X-166050Y545000D01*
X-164650Y544750D01*
X-163425Y543750D01*
X-162375Y542250D01*
X-161675Y540500D01*
X-161325Y538500D01*
Y536500D01*
X-161675Y534500D01*
X-162375Y532750D01*
X-163425Y531250D01*
X-164650Y530250D01*
X-166050Y530000D01*
G01X-155350Y545000D02*
Y530000D01*
X-148350D01*
G01X-141500D02*
Y545000D01*
X-138000D01*
X-136600Y544250D01*
X-135550Y543250D01*
X-134675Y541750D01*
X-133975Y540000D01*
X-133800Y537500D01*
X-133975Y535000D01*
X-134675Y533250D01*
X-135550Y531750D01*
X-136600Y530750D01*
X-138000Y530000D01*
X-141500D01*
G01X-119950D02*
X-126950D01*
Y545000D01*
X-119950D01*
G01X-122750Y537750D02*
X-126950D01*
G01X-112750Y530000D02*
Y545000D01*
X-108375D01*
X-106975Y544250D01*
X-106100Y543250D01*
X-105750Y541250D01*
X-106100Y539250D01*
X-107150Y538000D01*
X-108375Y537250D01*
X-112750D01*
G01X-108375D02*
X-105750Y530000D01*
G01X-99600D02*
Y545000D01*
X-95050Y532500D01*
X-90500Y545000D01*
Y530000D01*
G01X-85225D02*
X-80850Y545000D01*
X-76475Y530000D01*
G01X-78050Y535250D02*
X-83650D01*
G01X-70325Y532000D02*
X-68925Y530750D01*
X-67350Y530000D01*
X-65950D01*
X-64550Y530750D01*
X-63500Y532000D01*
X-62975Y533750D01*
X-63325Y535500D01*
X-64200Y537000D01*
X-65775Y538000D01*
X-67875Y538500D01*
X-69100Y539500D01*
X-69625Y541250D01*
X-69275Y543000D01*
X-68400Y544250D01*
X-67175Y545000D01*
X-65950D01*
X-64725Y544500D01*
X-63675Y543250D01*
G01X-56300Y530000D02*
Y545000D01*
G01X-49650D02*
X-56300Y535750D01*
G01X-48600Y530000D02*
X-53325Y540000D01*
G01X-20200Y543750D02*
X-21250Y544500D01*
X-22475Y545000D01*
X-23875D01*
X-25450Y544250D01*
X-26675Y543000D01*
X-27550Y541500D01*
X-28250Y539000D01*
X-28425Y536750D01*
X-28075Y534500D01*
X-27550Y533000D01*
X-26500Y531500D01*
X-25275Y530500D01*
X-24050Y530000D01*
X-22825D01*
X-21600Y530500D01*
X-20550Y531250D01*
X-19675Y532250D01*
G01X-13350Y545000D02*
Y530000D01*
X-6350D01*
G01X7850D02*
X850D01*
Y545000D01*
X7850D01*
G01X5050Y537750D02*
X850D01*
G01X14175Y530000D02*
X18550Y545000D01*
X22925Y530000D01*
G01X21350Y535250D02*
X15750D01*
G01X28725Y530000D02*
Y545000D01*
X36775Y530000D01*
Y545000D01*
G01X44850D02*
X49050D01*
G01X46950D02*
Y530000D01*
G01X44850D02*
X49050D01*
G01X57125D02*
Y545000D01*
X65175Y530000D01*
Y545000D01*
G01X76400Y537500D02*
X79900D01*
Y533000D01*
X78850Y531500D01*
X77625Y530500D01*
X75875Y530000D01*
X74125Y530500D01*
X72900Y531500D01*
X71850Y533000D01*
X71150Y534750D01*
X70800Y536750D01*
Y538500D01*
X71150Y540000D01*
X71850Y541750D01*
X72900Y543250D01*
X73950Y544250D01*
X75350Y545000D01*
X76575D01*
X77975Y544500D01*
X79025Y543500D01*
G01X100250Y530000D02*
Y545000D01*
X104450D01*
X105850Y544250D01*
X106900Y542500D01*
X107250Y540500D01*
X106900Y538500D01*
X106025Y537000D01*
X104450Y536250D01*
X100250D01*
G01X114450Y530000D02*
Y545000D01*
X118825D01*
X120225Y544250D01*
X121100Y543250D01*
X121450Y541250D01*
X121100Y539250D01*
X120050Y538000D01*
X118825Y537250D01*
X114450D01*
G01X118825D02*
X121450Y530000D01*
G01X132150D02*
X130750Y530250D01*
X129525Y531250D01*
X128475Y532750D01*
X127775Y534500D01*
X127425Y536500D01*
Y538500D01*
X127775Y540500D01*
X128475Y542250D01*
X129525Y543750D01*
X130750Y544750D01*
X132150Y545000D01*
X133550Y544750D01*
X134775Y543750D01*
X135825Y542250D01*
X136525Y540500D01*
X136875Y538500D01*
Y536500D01*
X136525Y534500D01*
X135825Y532750D01*
X134775Y531250D01*
X133550Y530250D01*
X132150Y530000D01*
G01X150200Y543750D02*
X149150Y544500D01*
X147925Y545000D01*
X146525D01*
X144950Y544250D01*
X143725Y543000D01*
X142850Y541500D01*
X142150Y539000D01*
X141975Y536750D01*
X142325Y534500D01*
X142850Y533000D01*
X143900Y531500D01*
X145125Y530500D01*
X146350Y530000D01*
X147575D01*
X148800Y530500D01*
X149850Y531250D01*
X150725Y532250D01*
G01X164050Y530000D02*
X157050D01*
Y545000D01*
X164050D01*
G01X161250Y537750D02*
X157050D01*
G01X171075Y532000D02*
X172475Y530750D01*
X174050Y530000D01*
X175450D01*
X176850Y530750D01*
X177900Y532000D01*
X178425Y533750D01*
X178075Y535500D01*
X177200Y537000D01*
X175625Y538000D01*
X173525Y538500D01*
X172300Y539500D01*
X171775Y541250D01*
X172125Y543000D01*
X173000Y544250D01*
X174225Y545000D01*
X175450D01*
X176675Y544500D01*
X177725Y543250D01*
G01X185275Y532000D02*
X186675Y530750D01*
X188250Y530000D01*
X189650D01*
X191050Y530750D01*
X192100Y532000D01*
X192625Y533750D01*
X192275Y535500D01*
X191400Y537000D01*
X189825Y538000D01*
X187725Y538500D01*
X186500Y539500D01*
X185975Y541250D01*
X186325Y543000D01*
X187200Y544250D01*
X188425Y545000D01*
X189650D01*
X190875Y544500D01*
X191925Y543250D01*
G01X203150Y529500D02*
X202800Y529750D01*
Y530250D01*
X203150Y530500D01*
X203500Y530250D01*
Y529750D01*
X203150Y529500D01*
G01X-276500Y575000D02*
Y560000D01*
G01Y562250D02*
X-277200Y561000D01*
X-278250Y560250D01*
X-279475Y560000D01*
X-280875Y560500D01*
X-281925Y561750D01*
X-282625Y563250D01*
X-282800Y565000D01*
X-282625Y566750D01*
X-281925Y568250D01*
X-280875Y569500D01*
X-279475Y570000D01*
X-278250Y569750D01*
X-277375Y569250D01*
X-276500Y568250D01*
G01X-265450Y559500D02*
X-265800Y559750D01*
Y560250D01*
X-265450Y560500D01*
X-265100Y560250D01*
Y559750D01*
X-265450Y559500D01*
G01X-241600Y560000D02*
Y575000D01*
X-237050Y562500D01*
X-232500Y575000D01*
Y560000D01*
G01X-227225D02*
X-222850Y575000D01*
X-218475Y560000D01*
G01X-220050Y565250D02*
X-225650D01*
G01X-212500Y560000D02*
Y575000D01*
G01X-205850D02*
X-212500Y565750D01*
G01X-204800Y560000D02*
X-209525Y570000D01*
G01X-190950Y560000D02*
X-197950D01*
Y575000D01*
X-190950D01*
G01X-193750Y567750D02*
X-197950D01*
G01X-169725Y562000D02*
X-168325Y560750D01*
X-166750Y560000D01*
X-165350D01*
X-163950Y560750D01*
X-162900Y562000D01*
X-162375Y563750D01*
X-162725Y565500D01*
X-163600Y567000D01*
X-165175Y568000D01*
X-167275Y568500D01*
X-168500Y569500D01*
X-169025Y571250D01*
X-168675Y573000D01*
X-167800Y574250D01*
X-166575Y575000D01*
X-165350D01*
X-164125Y574500D01*
X-163075Y573250D01*
G01X-155700Y575000D02*
Y564250D01*
X-155000Y562000D01*
X-153600Y560500D01*
X-151850Y560000D01*
X-150100Y560500D01*
X-148700Y562000D01*
X-148000Y564250D01*
Y575000D01*
G01X-141150Y560000D02*
Y575000D01*
X-136775D01*
X-135375Y574250D01*
X-134500Y573250D01*
X-134150Y571250D01*
X-134500Y569250D01*
X-135550Y568000D01*
X-136775Y567250D01*
X-141150D01*
G01X-136775D02*
X-134150Y560000D01*
G01X-119950D02*
X-126950D01*
Y575000D01*
X-119950D01*
G01X-122750Y567750D02*
X-126950D01*
G01X-95050Y575000D02*
Y560000D01*
G01X-99075Y575000D02*
X-91025D01*
G01X-84525Y560000D02*
Y575000D01*
G01X-77175D02*
Y560000D01*
G01Y567500D02*
X-84525D01*
G01X-63150Y560000D02*
X-70150D01*
Y575000D01*
X-63150D01*
G01X-65950Y567750D02*
X-70150D01*
G01X-41925Y562000D02*
X-40525Y560750D01*
X-38950Y560000D01*
X-37550D01*
X-36150Y560750D01*
X-35100Y562000D01*
X-34575Y563750D01*
X-34925Y565500D01*
X-35800Y567000D01*
X-37375Y568000D01*
X-39475Y568500D01*
X-40700Y569500D01*
X-41225Y571250D01*
X-40875Y573000D01*
X-40000Y574250D01*
X-38775Y575000D01*
X-37550D01*
X-36325Y574500D01*
X-35275Y573250D01*
G01X-24050Y560000D02*
X-25450Y560250D01*
X-26675Y561250D01*
X-27725Y562750D01*
X-28425Y564500D01*
X-28775Y566500D01*
Y568500D01*
X-28425Y570500D01*
X-27725Y572250D01*
X-26675Y573750D01*
X-25450Y574750D01*
X-24050Y575000D01*
X-22650Y574750D01*
X-21425Y573750D01*
X-20375Y572250D01*
X-19675Y570500D01*
X-19325Y568500D01*
Y566500D01*
X-19675Y564500D01*
X-20375Y562750D01*
X-21425Y561250D01*
X-22650Y560250D01*
X-24050Y560000D01*
G01X-13350Y575000D02*
Y560000D01*
X-6350D01*
G01X500D02*
Y575000D01*
X4000D01*
X5400Y574250D01*
X6450Y573250D01*
X7325Y571750D01*
X8025Y570000D01*
X8200Y567500D01*
X8025Y565000D01*
X7325Y563250D01*
X6450Y561750D01*
X5400Y560750D01*
X4000Y560000D01*
X500D01*
G01X22050D02*
X15050D01*
Y575000D01*
X22050D01*
G01X19250Y567750D02*
X15050D01*
G01X29250Y560000D02*
Y575000D01*
X33625D01*
X35025Y574250D01*
X35900Y573250D01*
X36250Y571250D01*
X35900Y569250D01*
X34850Y568000D01*
X33625Y567250D01*
X29250D01*
G01X33625D02*
X36250Y560000D01*
G01X42400D02*
Y575000D01*
X46950Y562500D01*
X51500Y575000D01*
Y560000D01*
G01X56775D02*
X61150Y575000D01*
X65525Y560000D01*
G01X63950Y565250D02*
X58350D01*
G01X71675Y562000D02*
X73075Y560750D01*
X74650Y560000D01*
X76050D01*
X77450Y560750D01*
X78500Y562000D01*
X79025Y563750D01*
X78675Y565500D01*
X77800Y567000D01*
X76225Y568000D01*
X74125Y568500D01*
X72900Y569500D01*
X72375Y571250D01*
X72725Y573000D01*
X73600Y574250D01*
X74825Y575000D01*
X76050D01*
X77275Y574500D01*
X78325Y573250D01*
G01X85700Y560000D02*
Y575000D01*
G01X92350D02*
X85700Y565750D01*
G01X93400Y560000D02*
X88675Y570000D01*
G01X115850Y575000D02*
X120050D01*
G01X117950D02*
Y560000D01*
G01X115850D02*
X120050D01*
G01X128475Y562000D02*
X129875Y560750D01*
X131450Y560000D01*
X132850D01*
X134250Y560750D01*
X135300Y562000D01*
X135825Y563750D01*
X135475Y565500D01*
X134600Y567000D01*
X133025Y568000D01*
X130925Y568500D01*
X129700Y569500D01*
X129175Y571250D01*
X129525Y573000D01*
X130400Y574250D01*
X131625Y575000D01*
X132850D01*
X134075Y574500D01*
X135125Y573250D01*
G01X160550Y575000D02*
Y560000D01*
G01X156525Y575000D02*
X164575D01*
G01X174750Y560000D02*
X173350Y560250D01*
X172125Y561250D01*
X171075Y562750D01*
X170375Y564500D01*
X170025Y566500D01*
Y568500D01*
X170375Y570500D01*
X171075Y572250D01*
X172125Y573750D01*
X173350Y574750D01*
X174750Y575000D01*
X176150Y574750D01*
X177375Y573750D01*
X178425Y572250D01*
X179125Y570500D01*
X179475Y568500D01*
Y566500D01*
X179125Y564500D01*
X178425Y562750D01*
X177375Y561250D01*
X176150Y560250D01*
X174750Y560000D01*
G01X188950Y575000D02*
Y560000D01*
G01X184925Y575000D02*
X192975D01*
G01X198775Y560000D02*
X203150Y575000D01*
X207525Y560000D01*
G01X205950Y565250D02*
X200350D01*
G01X213850Y575000D02*
Y560000D01*
X220850D01*
G01X228050Y575000D02*
Y560000D01*
X235050D01*
G01X245750D02*
Y566750D01*
X242250Y575000D01*
G01X249250D02*
X245750Y566750D01*
G01X278000Y573750D02*
X276950Y574500D01*
X275725Y575000D01*
X274325D01*
X272750Y574250D01*
X271525Y573000D01*
X270650Y571500D01*
X269950Y569000D01*
X269775Y566750D01*
X270125Y564500D01*
X270650Y563000D01*
X271700Y561500D01*
X272925Y560500D01*
X274150Y560000D01*
X275375D01*
X276600Y560500D01*
X277650Y561250D01*
X278525Y562250D01*
G01X284850Y575000D02*
Y560000D01*
X291850D01*
G01X306050D02*
X299050D01*
Y575000D01*
X306050D01*
G01X303250Y567750D02*
X299050D01*
G01X312375Y560000D02*
X316750Y575000D01*
X321125Y560000D01*
G01X319550Y565250D02*
X313950D01*
G01X326925Y560000D02*
Y575000D01*
X334975Y560000D01*
Y575000D01*
G01X348650Y560000D02*
X341650D01*
Y575000D01*
X348650D01*
G01X345850Y567750D02*
X341650D01*
G01X355500Y560000D02*
Y575000D01*
X359000D01*
X360400Y574250D01*
X361450Y573250D01*
X362325Y571750D01*
X363025Y570000D01*
X363200Y567500D01*
X363025Y565000D01*
X362325Y563250D01*
X361450Y561750D01*
X360400Y560750D01*
X359000Y560000D01*
X355500D01*
G01X384425D02*
Y575000D01*
X391075D01*
G01X388625Y567750D02*
X384425D01*
G01X398450Y560000D02*
Y575000D01*
X402825D01*
X404225Y574250D01*
X405100Y573250D01*
X405450Y571250D01*
X405100Y569250D01*
X404050Y568000D01*
X402825Y567250D01*
X398450D01*
G01X402825D02*
X405450Y560000D01*
G01X416150D02*
X414750Y560250D01*
X413525Y561250D01*
X412475Y562750D01*
X411775Y564500D01*
X411425Y566500D01*
Y568500D01*
X411775Y570500D01*
X412475Y572250D01*
X413525Y573750D01*
X414750Y574750D01*
X416150Y575000D01*
X417550Y574750D01*
X418775Y573750D01*
X419825Y572250D01*
X420525Y570500D01*
X420875Y568500D01*
Y566500D01*
X420525Y564500D01*
X419825Y562750D01*
X418775Y561250D01*
X417550Y560250D01*
X416150Y560000D01*
G01X425800D02*
Y575000D01*
X430350Y562500D01*
X434900Y575000D01*
Y560000D01*
G01X454375D02*
X458750Y575000D01*
X463125Y560000D01*
G01X461550Y565250D02*
X455950D01*
G01X469450Y575000D02*
Y560000D01*
X476450D01*
G01X483650Y575000D02*
Y560000D01*
X490650D01*
G01X515550Y575000D02*
Y560000D01*
G01X511525Y575000D02*
X519575D01*
G01X533250Y560000D02*
X526250D01*
Y575000D01*
X533250D01*
G01X530450Y567750D02*
X526250D01*
G01X540275Y562000D02*
X541675Y560750D01*
X543250Y560000D01*
X544650D01*
X546050Y560750D01*
X547100Y562000D01*
X547625Y563750D01*
X547275Y565500D01*
X546400Y567000D01*
X544825Y568000D01*
X542725Y568500D01*
X541500Y569500D01*
X540975Y571250D01*
X541325Y573000D01*
X542200Y574250D01*
X543425Y575000D01*
X544650D01*
X545875Y574500D01*
X546925Y573250D01*
G01X558150Y575000D02*
Y560000D01*
G01X554125Y575000D02*
X562175D01*
G01X583050Y560000D02*
Y575000D01*
X587250D01*
X588650Y574250D01*
X589700Y572500D01*
X590050Y570500D01*
X589700Y568500D01*
X588825Y567000D01*
X587250Y566250D01*
X583050D01*
G01X596375Y560000D02*
X600750Y575000D01*
X605125Y560000D01*
G01X603550Y565250D02*
X597950D01*
G01X611100Y560000D02*
Y575000D01*
X614600D01*
X616000Y574250D01*
X617050Y573250D01*
X617925Y571750D01*
X618625Y570000D01*
X618800Y567500D01*
X618625Y565000D01*
X617925Y563250D01*
X617050Y561750D01*
X616000Y560750D01*
X614600Y560000D01*
X611100D01*
G01X625475Y562000D02*
X626875Y560750D01*
X628450Y560000D01*
X629850D01*
X631250Y560750D01*
X632300Y562000D01*
X632825Y563750D01*
X632475Y565500D01*
X631600Y567000D01*
X630025Y568000D01*
X627925Y568500D01*
X626700Y569500D01*
X626175Y571250D01*
X626525Y573000D01*
X627400Y574250D01*
X628625Y575000D01*
X629850D01*
X631075Y574500D01*
X632125Y573250D01*
G01X653700Y560000D02*
Y575000D01*
X657200D01*
X658600Y574250D01*
X659650Y573250D01*
X660525Y571750D01*
X661225Y570000D01*
X661400Y567500D01*
X661225Y565000D01*
X660525Y563250D01*
X659650Y561750D01*
X658600Y560750D01*
X657200Y560000D01*
X653700D01*
G01X667900Y575000D02*
Y564250D01*
X668600Y562000D01*
X670000Y560500D01*
X671750Y560000D01*
X673500Y560500D01*
X674900Y562000D01*
X675600Y564250D01*
Y575000D01*
G01X682450Y560000D02*
Y575000D01*
X686825D01*
X688225Y574250D01*
X689100Y573250D01*
X689450Y571250D01*
X689100Y569250D01*
X688050Y568000D01*
X686825Y567250D01*
X682450D01*
G01X686825D02*
X689450Y560000D01*
G01X698050Y575000D02*
X702250D01*
G01X700150D02*
Y560000D01*
G01X698050D02*
X702250D01*
G01X710325D02*
Y575000D01*
X718375Y560000D01*
Y575000D01*
G01X729600Y567500D02*
X733100D01*
Y563000D01*
X732050Y561500D01*
X730825Y560500D01*
X729075Y560000D01*
X727325Y560500D01*
X726100Y561500D01*
X725050Y563000D01*
X724350Y564750D01*
X724000Y566750D01*
Y568500D01*
X724350Y570000D01*
X725050Y571750D01*
X726100Y573250D01*
X727150Y574250D01*
X728550Y575000D01*
X729775D01*
X731175Y574500D01*
X732225Y573500D01*
G01X-276850Y598750D02*
X-278075Y599750D01*
X-279125Y600000D01*
X-280525Y599500D01*
X-281575Y598500D01*
X-282275Y596750D01*
X-282450Y595000D01*
X-282275Y593250D01*
X-281575Y591750D01*
X-280525Y590500D01*
X-279125Y590000D01*
X-277900Y590500D01*
X-276850Y591500D01*
G01X-265450Y589500D02*
X-265800Y589750D01*
Y590250D01*
X-265450Y590500D01*
X-265100Y590250D01*
Y589750D01*
X-265450Y589500D01*
G01X-240725Y592000D02*
X-239325Y590750D01*
X-237750Y590000D01*
X-236350D01*
X-234950Y590750D01*
X-233900Y592000D01*
X-233375Y593750D01*
X-233725Y595500D01*
X-234600Y597000D01*
X-236175Y598000D01*
X-238275Y598500D01*
X-239500Y599500D01*
X-240025Y601250D01*
X-239675Y603000D01*
X-238800Y604250D01*
X-237575Y605000D01*
X-236350D01*
X-235125Y604500D01*
X-234075Y603250D01*
G01X-219350Y590000D02*
X-226350D01*
Y605000D01*
X-219350D01*
G01X-222150Y597750D02*
X-226350D01*
G01X-213025Y590000D02*
X-208650Y605000D01*
X-204275Y590000D01*
G01X-205850Y595250D02*
X-211450D01*
G01X-197950Y605000D02*
Y590000D01*
X-190950D01*
G01X-166050Y605000D02*
Y590000D01*
G01X-170075Y605000D02*
X-162025D01*
G01X-155525Y590000D02*
Y605000D01*
G01X-148175D02*
Y590000D01*
G01Y597500D02*
X-155525D01*
G01X-134150Y590000D02*
X-141150D01*
Y605000D01*
X-134150D01*
G01X-136950Y597750D02*
X-141150D01*
G01X-113625Y605000D02*
X-109250Y590000D01*
X-104875Y605000D01*
G01X-97150D02*
X-92950D01*
G01X-95050D02*
Y590000D01*
G01X-97150D02*
X-92950D01*
G01X-85225D02*
X-80850Y605000D01*
X-76475Y590000D01*
G01X-78050Y595250D02*
X-83650D01*
G01X-70325Y592000D02*
X-68925Y590750D01*
X-67350Y590000D01*
X-65950D01*
X-64550Y590750D01*
X-63500Y592000D01*
X-62975Y593750D01*
X-63325Y595500D01*
X-64200Y597000D01*
X-65775Y598000D01*
X-67875Y598500D01*
X-69100Y599500D01*
X-69625Y601250D01*
X-69275Y603000D01*
X-68400Y604250D01*
X-67175Y605000D01*
X-65950D01*
X-64725Y604500D01*
X-63675Y603250D01*
G01X-42100Y605000D02*
Y594250D01*
X-41400Y592000D01*
X-40000Y590500D01*
X-38250Y590000D01*
X-36500Y590500D01*
X-35100Y592000D01*
X-34400Y594250D01*
Y605000D01*
G01X-27725Y592000D02*
X-26325Y590750D01*
X-24750Y590000D01*
X-23350D01*
X-21950Y590750D01*
X-20900Y592000D01*
X-20375Y593750D01*
X-20725Y595500D01*
X-21600Y597000D01*
X-23175Y598000D01*
X-25275Y598500D01*
X-26500Y599500D01*
X-27025Y601250D01*
X-26675Y603000D01*
X-25800Y604250D01*
X-24575Y605000D01*
X-23350D01*
X-22125Y604500D01*
X-21075Y603250D01*
G01X-11950Y605000D02*
X-7750D01*
G01X-9850D02*
Y590000D01*
G01X-11950D02*
X-7750D01*
G01X325D02*
Y605000D01*
X8375Y590000D01*
Y605000D01*
G01X19600Y597500D02*
X23100D01*
Y593000D01*
X22050Y591500D01*
X20825Y590500D01*
X19075Y590000D01*
X17325Y590500D01*
X16100Y591500D01*
X15050Y593000D01*
X14350Y594750D01*
X14000Y596750D01*
Y598500D01*
X14350Y600000D01*
X15050Y601750D01*
X16100Y603250D01*
X17150Y604250D01*
X18550Y605000D01*
X19775D01*
X21175Y604500D01*
X22225Y603500D01*
G01X43275Y592000D02*
X44675Y590750D01*
X46250Y590000D01*
X47650D01*
X49050Y590750D01*
X50100Y592000D01*
X50625Y593750D01*
X50275Y595500D01*
X49400Y597000D01*
X47825Y598000D01*
X45725Y598500D01*
X44500Y599500D01*
X43975Y601250D01*
X44325Y603000D01*
X45200Y604250D01*
X46425Y605000D01*
X47650D01*
X48875Y604500D01*
X49925Y603250D01*
G01X61150Y590000D02*
X59750Y590250D01*
X58525Y591250D01*
X57475Y592750D01*
X56775Y594500D01*
X56425Y596500D01*
Y598500D01*
X56775Y600500D01*
X57475Y602250D01*
X58525Y603750D01*
X59750Y604750D01*
X61150Y605000D01*
X62550Y604750D01*
X63775Y603750D01*
X64825Y602250D01*
X65525Y600500D01*
X65875Y598500D01*
Y596500D01*
X65525Y594500D01*
X64825Y592750D01*
X63775Y591250D01*
X62550Y590250D01*
X61150Y590000D01*
G01X71850Y605000D02*
Y590000D01*
X78850D01*
G01X85700D02*
Y605000D01*
X89200D01*
X90600Y604250D01*
X91650Y603250D01*
X92525Y601750D01*
X93225Y600000D01*
X93400Y597500D01*
X93225Y595000D01*
X92525Y593250D01*
X91650Y591750D01*
X90600Y590750D01*
X89200Y590000D01*
X85700D01*
G01X107250D02*
X100250D01*
Y605000D01*
X107250D01*
G01X104450Y597750D02*
X100250D01*
G01X114450Y590000D02*
Y605000D01*
X118825D01*
X120225Y604250D01*
X121100Y603250D01*
X121450Y601250D01*
X121100Y599250D01*
X120050Y598000D01*
X118825Y597250D01*
X114450D01*
G01X118825D02*
X121450Y590000D01*
G01X127600D02*
Y605000D01*
X132150Y592500D01*
X136700Y605000D01*
Y590000D01*
G01X141975D02*
X146350Y605000D01*
X150725Y590000D01*
G01X149150Y595250D02*
X143550D01*
G01X156875Y592000D02*
X158275Y590750D01*
X159850Y590000D01*
X161250D01*
X162650Y590750D01*
X163700Y592000D01*
X164225Y593750D01*
X163875Y595500D01*
X163000Y597000D01*
X161425Y598000D01*
X159325Y598500D01*
X158100Y599500D01*
X157575Y601250D01*
X157925Y603000D01*
X158800Y604250D01*
X160025Y605000D01*
X161250D01*
X162475Y604500D01*
X163525Y603250D01*
G01X170900Y590000D02*
Y605000D01*
G01X177550D02*
X170900Y595750D01*
G01X178600Y590000D02*
X173875Y600000D01*
G01X203150Y590000D02*
X201750Y590250D01*
X200525Y591250D01*
X199475Y592750D01*
X198775Y594500D01*
X198425Y596500D01*
Y598500D01*
X198775Y600500D01*
X199475Y602250D01*
X200525Y603750D01*
X201750Y604750D01*
X203150Y605000D01*
X204550Y604750D01*
X205775Y603750D01*
X206825Y602250D01*
X207525Y600500D01*
X207875Y598500D01*
Y596500D01*
X207525Y594500D01*
X206825Y592750D01*
X205775Y591250D01*
X204550Y590250D01*
X203150Y590000D01*
G01X213325D02*
Y605000D01*
X221375Y590000D01*
Y605000D01*
G01X245750D02*
Y590000D01*
G01X241725Y605000D02*
X249775D01*
G01X256275Y590000D02*
Y605000D01*
G01X263625D02*
Y590000D01*
G01Y597500D02*
X256275D01*
G01X277650Y590000D02*
X270650D01*
Y605000D01*
X277650D01*
G01X274850Y597750D02*
X270650D01*
G01X302550Y605000D02*
Y590000D01*
G01X298525Y605000D02*
X306575D01*
G01X320250Y590000D02*
X313250D01*
Y605000D01*
X320250D01*
G01X317450Y597750D02*
X313250D01*
G01X327275Y592000D02*
X328675Y590750D01*
X330250Y590000D01*
X331650D01*
X333050Y590750D01*
X334100Y592000D01*
X334625Y593750D01*
X334275Y595500D01*
X333400Y597000D01*
X331825Y598000D01*
X329725Y598500D01*
X328500Y599500D01*
X327975Y601250D01*
X328325Y603000D01*
X329200Y604250D01*
X330425Y605000D01*
X331650D01*
X332875Y604500D01*
X333925Y603250D01*
G01X345150Y605000D02*
Y590000D01*
G01X341125Y605000D02*
X349175D01*
G01X370050Y590000D02*
Y605000D01*
X374250D01*
X375650Y604250D01*
X376700Y602500D01*
X377050Y600500D01*
X376700Y598500D01*
X375825Y597000D01*
X374250Y596250D01*
X370050D01*
G01X383375Y590000D02*
X387750Y605000D01*
X392125Y590000D01*
G01X390550Y595250D02*
X384950D01*
G01X398100Y590000D02*
Y605000D01*
X401600D01*
X403000Y604250D01*
X404050Y603250D01*
X404925Y601750D01*
X405625Y600000D01*
X405800Y597500D01*
X405625Y595000D01*
X404925Y593250D01*
X404050Y591750D01*
X403000Y590750D01*
X401600Y590000D01*
X398100D01*
G01X426675Y592000D02*
X428075Y590750D01*
X429650Y590000D01*
X431050D01*
X432450Y590750D01*
X433500Y592000D01*
X434025Y593750D01*
X433675Y595500D01*
X432800Y597000D01*
X431225Y598000D01*
X429125Y598500D01*
X427900Y599500D01*
X427375Y601250D01*
X427725Y603000D01*
X428600Y604250D01*
X429825Y605000D01*
X431050D01*
X432275Y604500D01*
X433325Y603250D01*
G01X442450Y605000D02*
X446650D01*
G01X444550D02*
Y590000D01*
G01X442450D02*
X446650D01*
G01X454900D02*
Y605000D01*
X458400D01*
X459800Y604250D01*
X460850Y603250D01*
X461725Y601750D01*
X462425Y600000D01*
X462600Y597500D01*
X462425Y595000D01*
X461725Y593250D01*
X460850Y591750D01*
X459800Y590750D01*
X458400Y590000D01*
X454900D01*
G01X476450D02*
X469450D01*
Y605000D01*
X476450D01*
G01X473650Y597750D02*
X469450D01*
G01X487150Y589500D02*
X486800Y589750D01*
Y590250D01*
X487150Y590500D01*
X487500Y590250D01*
Y589750D01*
X487150Y589500D01*
G01X-282800Y620000D02*
Y635000D01*
G01Y627500D02*
X-281925Y629000D01*
X-280875Y629750D01*
X-279825Y630000D01*
X-278250Y629500D01*
X-277200Y628500D01*
X-276500Y626750D01*
Y624750D01*
X-276850Y622750D01*
X-277550Y621250D01*
X-278775Y620250D01*
X-279825Y620000D01*
X-280875Y620250D01*
X-281925Y621000D01*
X-282800Y622250D01*
G01X-265450Y619500D02*
X-265800Y619750D01*
Y620250D01*
X-265450Y620500D01*
X-265100Y620250D01*
Y619750D01*
X-265450Y619500D01*
G01X-240725Y622000D02*
X-239325Y620750D01*
X-237750Y620000D01*
X-236350D01*
X-234950Y620750D01*
X-233900Y622000D01*
X-233375Y623750D01*
X-233725Y625500D01*
X-234600Y627000D01*
X-236175Y628000D01*
X-238275Y628500D01*
X-239500Y629500D01*
X-240025Y631250D01*
X-239675Y633000D01*
X-238800Y634250D01*
X-237575Y635000D01*
X-236350D01*
X-235125Y634500D01*
X-234075Y633250D01*
G01X-219350Y620000D02*
X-226350D01*
Y635000D01*
X-219350D01*
G01X-222150Y627750D02*
X-226350D01*
G01X-213025Y620000D02*
X-208650Y635000D01*
X-204275Y620000D01*
G01X-205850Y625250D02*
X-211450D01*
G01X-197950Y635000D02*
Y620000D01*
X-190950D01*
G01X-166050Y635000D02*
Y620000D01*
G01X-170075Y635000D02*
X-162025D01*
G01X-155525Y620000D02*
Y635000D01*
G01X-148175D02*
Y620000D01*
G01Y627500D02*
X-155525D01*
G01X-134150Y620000D02*
X-141150D01*
Y635000D01*
X-134150D01*
G01X-136950Y627750D02*
X-141150D01*
G01X-113625Y635000D02*
X-109250Y620000D01*
X-104875Y635000D01*
G01X-97150D02*
X-92950D01*
G01X-95050D02*
Y620000D01*
G01X-97150D02*
X-92950D01*
G01X-85225D02*
X-80850Y635000D01*
X-76475Y620000D01*
G01X-78050Y625250D02*
X-83650D01*
G01X-70325Y622000D02*
X-68925Y620750D01*
X-67350Y620000D01*
X-65950D01*
X-64550Y620750D01*
X-63500Y622000D01*
X-62975Y623750D01*
X-63325Y625500D01*
X-64200Y627000D01*
X-65775Y628000D01*
X-67875Y628500D01*
X-69100Y629500D01*
X-69625Y631250D01*
X-69275Y633000D01*
X-68400Y634250D01*
X-67175Y635000D01*
X-65950D01*
X-64725Y634500D01*
X-63675Y633250D01*
G01X-42100Y635000D02*
Y624250D01*
X-41400Y622000D01*
X-40000Y620500D01*
X-38250Y620000D01*
X-36500Y620500D01*
X-35100Y622000D01*
X-34400Y624250D01*
Y635000D01*
G01X-27725Y622000D02*
X-26325Y620750D01*
X-24750Y620000D01*
X-23350D01*
X-21950Y620750D01*
X-20900Y622000D01*
X-20375Y623750D01*
X-20725Y625500D01*
X-21600Y627000D01*
X-23175Y628000D01*
X-25275Y628500D01*
X-26500Y629500D01*
X-27025Y631250D01*
X-26675Y633000D01*
X-25800Y634250D01*
X-24575Y635000D01*
X-23350D01*
X-22125Y634500D01*
X-21075Y633250D01*
G01X-11950Y635000D02*
X-7750D01*
G01X-9850D02*
Y620000D01*
G01X-11950D02*
X-7750D01*
G01X325D02*
Y635000D01*
X8375Y620000D01*
Y635000D01*
G01X19600Y627500D02*
X23100D01*
Y623000D01*
X22050Y621500D01*
X20825Y620500D01*
X19075Y620000D01*
X17325Y620500D01*
X16100Y621500D01*
X15050Y623000D01*
X14350Y624750D01*
X14000Y626750D01*
Y628500D01*
X14350Y630000D01*
X15050Y631750D01*
X16100Y633250D01*
X17150Y634250D01*
X18550Y635000D01*
X19775D01*
X21175Y634500D01*
X22225Y633500D01*
G01X43275Y622000D02*
X44675Y620750D01*
X46250Y620000D01*
X47650D01*
X49050Y620750D01*
X50100Y622000D01*
X50625Y623750D01*
X50275Y625500D01*
X49400Y627000D01*
X47825Y628000D01*
X45725Y628500D01*
X44500Y629500D01*
X43975Y631250D01*
X44325Y633000D01*
X45200Y634250D01*
X46425Y635000D01*
X47650D01*
X48875Y634500D01*
X49925Y633250D01*
G01X61150Y620000D02*
X59750Y620250D01*
X58525Y621250D01*
X57475Y622750D01*
X56775Y624500D01*
X56425Y626500D01*
Y628500D01*
X56775Y630500D01*
X57475Y632250D01*
X58525Y633750D01*
X59750Y634750D01*
X61150Y635000D01*
X62550Y634750D01*
X63775Y633750D01*
X64825Y632250D01*
X65525Y630500D01*
X65875Y628500D01*
Y626500D01*
X65525Y624500D01*
X64825Y622750D01*
X63775Y621250D01*
X62550Y620250D01*
X61150Y620000D01*
G01X71850Y635000D02*
Y620000D01*
X78850D01*
G01X85700D02*
Y635000D01*
X89200D01*
X90600Y634250D01*
X91650Y633250D01*
X92525Y631750D01*
X93225Y630000D01*
X93400Y627500D01*
X93225Y625000D01*
X92525Y623250D01*
X91650Y621750D01*
X90600Y620750D01*
X89200Y620000D01*
X85700D01*
G01X107250D02*
X100250D01*
Y635000D01*
X107250D01*
G01X104450Y627750D02*
X100250D01*
G01X114450Y620000D02*
Y635000D01*
X118825D01*
X120225Y634250D01*
X121100Y633250D01*
X121450Y631250D01*
X121100Y629250D01*
X120050Y628000D01*
X118825Y627250D01*
X114450D01*
G01X118825D02*
X121450Y620000D01*
G01X127600D02*
Y635000D01*
X132150Y622500D01*
X136700Y635000D01*
Y620000D01*
G01X141975D02*
X146350Y635000D01*
X150725Y620000D01*
G01X149150Y625250D02*
X143550D01*
G01X156875Y622000D02*
X158275Y620750D01*
X159850Y620000D01*
X161250D01*
X162650Y620750D01*
X163700Y622000D01*
X164225Y623750D01*
X163875Y625500D01*
X163000Y627000D01*
X161425Y628000D01*
X159325Y628500D01*
X158100Y629500D01*
X157575Y631250D01*
X157925Y633000D01*
X158800Y634250D01*
X160025Y635000D01*
X161250D01*
X162475Y634500D01*
X163525Y633250D01*
G01X170900Y620000D02*
Y635000D01*
G01X177550D02*
X170900Y625750D01*
G01X178600Y620000D02*
X173875Y630000D01*
G01X203150Y620000D02*
X201750Y620250D01*
X200525Y621250D01*
X199475Y622750D01*
X198775Y624500D01*
X198425Y626500D01*
Y628500D01*
X198775Y630500D01*
X199475Y632250D01*
X200525Y633750D01*
X201750Y634750D01*
X203150Y635000D01*
X204550Y634750D01*
X205775Y633750D01*
X206825Y632250D01*
X207525Y630500D01*
X207875Y628500D01*
Y626500D01*
X207525Y624500D01*
X206825Y622750D01*
X205775Y621250D01*
X204550Y620250D01*
X203150Y620000D01*
G01X213325D02*
Y635000D01*
X221375Y620000D01*
Y635000D01*
G01X245750D02*
Y620000D01*
G01X241725Y635000D02*
X249775D01*
G01X256275Y620000D02*
Y635000D01*
G01X263625D02*
Y620000D01*
G01Y627500D02*
X256275D01*
G01X277650Y620000D02*
X270650D01*
Y635000D01*
X277650D01*
G01X274850Y627750D02*
X270650D01*
G01X298875Y622000D02*
X300275Y620750D01*
X301850Y620000D01*
X303250D01*
X304650Y620750D01*
X305700Y622000D01*
X306225Y623750D01*
X305875Y625500D01*
X305000Y627000D01*
X303425Y628000D01*
X301325Y628500D01*
X300100Y629500D01*
X299575Y631250D01*
X299925Y633000D01*
X300800Y634250D01*
X302025Y635000D01*
X303250D01*
X304475Y634500D01*
X305525Y633250D01*
G01X314650Y635000D02*
X318850D01*
G01X316750D02*
Y620000D01*
G01X314650D02*
X318850D01*
G01X327100D02*
Y635000D01*
X330600D01*
X332000Y634250D01*
X333050Y633250D01*
X333925Y631750D01*
X334625Y630000D01*
X334800Y627500D01*
X334625Y625000D01*
X333925Y623250D01*
X333050Y621750D01*
X332000Y620750D01*
X330600Y620000D01*
X327100D01*
G01X348650D02*
X341650D01*
Y635000D01*
X348650D01*
G01X345850Y627750D02*
X341650D01*
G01X373550Y620000D02*
X372150Y620250D01*
X370925Y621250D01*
X369875Y622750D01*
X369175Y624500D01*
X368825Y626500D01*
Y628500D01*
X369175Y630500D01*
X369875Y632250D01*
X370925Y633750D01*
X372150Y634750D01*
X373550Y635000D01*
X374950Y634750D01*
X376175Y633750D01*
X377225Y632250D01*
X377925Y630500D01*
X378275Y628500D01*
Y626500D01*
X377925Y624500D01*
X377225Y622750D01*
X376175Y621250D01*
X374950Y620250D01*
X373550Y620000D01*
G01X384250D02*
Y635000D01*
X388450D01*
X389850Y634250D01*
X390900Y632500D01*
X391250Y630500D01*
X390900Y628500D01*
X390025Y627000D01*
X388450Y626250D01*
X384250D01*
G01X398450Y620000D02*
Y635000D01*
X402650D01*
X404050Y634250D01*
X405100Y632500D01*
X405450Y630500D01*
X405100Y628500D01*
X404225Y627000D01*
X402650Y626250D01*
X398450D01*
G01X416150Y620000D02*
X414750Y620250D01*
X413525Y621250D01*
X412475Y622750D01*
X411775Y624500D01*
X411425Y626500D01*
Y628500D01*
X411775Y630500D01*
X412475Y632250D01*
X413525Y633750D01*
X414750Y634750D01*
X416150Y635000D01*
X417550Y634750D01*
X418775Y633750D01*
X419825Y632250D01*
X420525Y630500D01*
X420875Y628500D01*
Y626500D01*
X420525Y624500D01*
X419825Y622750D01*
X418775Y621250D01*
X417550Y620250D01*
X416150Y620000D01*
G01X426675Y622000D02*
X428075Y620750D01*
X429650Y620000D01*
X431050D01*
X432450Y620750D01*
X433500Y622000D01*
X434025Y623750D01*
X433675Y625500D01*
X432800Y627000D01*
X431225Y628000D01*
X429125Y628500D01*
X427900Y629500D01*
X427375Y631250D01*
X427725Y633000D01*
X428600Y634250D01*
X429825Y635000D01*
X431050D01*
X432275Y634500D01*
X433325Y633250D01*
G01X442450Y635000D02*
X446650D01*
G01X444550D02*
Y620000D01*
G01X442450D02*
X446650D01*
G01X458750Y635000D02*
Y620000D01*
G01X454725Y635000D02*
X462775D01*
G01X476450Y620000D02*
X469450D01*
Y635000D01*
X476450D01*
G01X473650Y627750D02*
X469450D01*
G01X501350Y620000D02*
X499950Y620250D01*
X498725Y621250D01*
X497675Y622750D01*
X496975Y624500D01*
X496625Y626500D01*
Y628500D01*
X496975Y630500D01*
X497675Y632250D01*
X498725Y633750D01*
X499950Y634750D01*
X501350Y635000D01*
X502750Y634750D01*
X503975Y633750D01*
X505025Y632250D01*
X505725Y630500D01*
X506075Y628500D01*
Y626500D01*
X505725Y624500D01*
X505025Y622750D01*
X503975Y621250D01*
X502750Y620250D01*
X501350Y620000D01*
G01X512225D02*
Y635000D01*
X518875D01*
G01X516425Y627750D02*
X512225D01*
G01X543950Y635000D02*
Y620000D01*
G01X539925Y635000D02*
X547975D01*
G01X554475Y620000D02*
Y635000D01*
G01X561825D02*
Y620000D01*
G01Y627500D02*
X554475D01*
G01X575850Y620000D02*
X568850D01*
Y635000D01*
X575850D01*
G01X573050Y627750D02*
X568850D01*
G01X600750Y635000D02*
Y620000D01*
G01X596725Y635000D02*
X604775D01*
G01X618450Y620000D02*
X611450D01*
Y635000D01*
X618450D01*
G01X615650Y627750D02*
X611450D01*
G01X625475Y622000D02*
X626875Y620750D01*
X628450Y620000D01*
X629850D01*
X631250Y620750D01*
X632300Y622000D01*
X632825Y623750D01*
X632475Y625500D01*
X631600Y627000D01*
X630025Y628000D01*
X627925Y628500D01*
X626700Y629500D01*
X626175Y631250D01*
X626525Y633000D01*
X627400Y634250D01*
X628625Y635000D01*
X629850D01*
X631075Y634500D01*
X632125Y633250D01*
G01X643350Y635000D02*
Y620000D01*
G01X639325Y635000D02*
X647375D01*
G01X668250Y620000D02*
Y635000D01*
X672450D01*
X673850Y634250D01*
X674900Y632500D01*
X675250Y630500D01*
X674900Y628500D01*
X674025Y627000D01*
X672450Y626250D01*
X668250D01*
G01X681575Y620000D02*
X685950Y635000D01*
X690325Y620000D01*
G01X688750Y625250D02*
X683150D01*
G01X696300Y620000D02*
Y635000D01*
X699800D01*
X701200Y634250D01*
X702250Y633250D01*
X703125Y631750D01*
X703825Y630000D01*
X704000Y627500D01*
X703825Y625000D01*
X703125Y623250D01*
X702250Y621750D01*
X701200Y620750D01*
X699800Y620000D01*
X696300D01*
G01X710675Y622000D02*
X712075Y620750D01*
X713650Y620000D01*
X715050D01*
X716450Y620750D01*
X717500Y622000D01*
X718025Y623750D01*
X717675Y625500D01*
X716800Y627000D01*
X715225Y628000D01*
X713125Y628500D01*
X711900Y629500D01*
X711375Y631250D01*
X711725Y633000D01*
X712600Y634250D01*
X713825Y635000D01*
X715050D01*
X716275Y634500D01*
X717325Y633250D01*
G01X728550Y619500D02*
X728200Y619750D01*
Y620250D01*
X728550Y620500D01*
X728900Y620250D01*
Y619750D01*
X728550Y619500D01*
G01X-276500Y650000D02*
Y660000D01*
G01Y658250D02*
X-277200Y659250D01*
X-278250Y659750D01*
X-279475Y660000D01*
X-280700Y659500D01*
X-281750Y658500D01*
X-282450Y657000D01*
X-282800Y655000D01*
X-282450Y653000D01*
X-281750Y651500D01*
X-280700Y650500D01*
X-279475Y650000D01*
X-278250Y650250D01*
X-277200Y651000D01*
X-276500Y652000D01*
G01X-265450Y649500D02*
X-265800Y649750D01*
Y650250D01*
X-265450Y650500D01*
X-265100Y650250D01*
Y649750D01*
X-265450Y649500D01*
G01X-240725Y652000D02*
X-239325Y650750D01*
X-237750Y650000D01*
X-236350D01*
X-234950Y650750D01*
X-233900Y652000D01*
X-233375Y653750D01*
X-233725Y655500D01*
X-234600Y657000D01*
X-236175Y658000D01*
X-238275Y658500D01*
X-239500Y659500D01*
X-240025Y661250D01*
X-239675Y663000D01*
X-238800Y664250D01*
X-237575Y665000D01*
X-236350D01*
X-235125Y664500D01*
X-234075Y663250D01*
G01X-222850Y665000D02*
Y650000D01*
G01X-226875Y665000D02*
X-218825D01*
G01X-212500D02*
Y654250D01*
X-211800Y652000D01*
X-210400Y650500D01*
X-208650Y650000D01*
X-206900Y650500D01*
X-205500Y652000D01*
X-204800Y654250D01*
Y665000D01*
G01X-197775Y650000D02*
Y665000D01*
X-191125D01*
G01X-193575Y657750D02*
X-197775D01*
G01X-183575Y650000D02*
Y665000D01*
X-176925D01*
G01X-179375Y657750D02*
X-183575D01*
G01X-155525Y652000D02*
X-154125Y650750D01*
X-152550Y650000D01*
X-151150D01*
X-149750Y650750D01*
X-148700Y652000D01*
X-148175Y653750D01*
X-148525Y655500D01*
X-149400Y657000D01*
X-150975Y658000D01*
X-153075Y658500D01*
X-154300Y659500D01*
X-154825Y661250D01*
X-154475Y663000D01*
X-153600Y664250D01*
X-152375Y665000D01*
X-151150D01*
X-149925Y664500D01*
X-148875Y663250D01*
G01X-137650Y650000D02*
X-139050Y650250D01*
X-140275Y651250D01*
X-141325Y652750D01*
X-142025Y654500D01*
X-142375Y656500D01*
Y658500D01*
X-142025Y660500D01*
X-141325Y662250D01*
X-140275Y663750D01*
X-139050Y664750D01*
X-137650Y665000D01*
X-136250Y664750D01*
X-135025Y663750D01*
X-133975Y662250D01*
X-133275Y660500D01*
X-132925Y658500D01*
Y656500D01*
X-133275Y654500D01*
X-133975Y652750D01*
X-135025Y651250D01*
X-136250Y650250D01*
X-137650Y650000D01*
G01X-126950Y665000D02*
Y650000D01*
X-119950D01*
G01X-113100D02*
Y665000D01*
X-109600D01*
X-108200Y664250D01*
X-107150Y663250D01*
X-106275Y661750D01*
X-105575Y660000D01*
X-105400Y657500D01*
X-105575Y655000D01*
X-106275Y653250D01*
X-107150Y651750D01*
X-108200Y650750D01*
X-109600Y650000D01*
X-113100D01*
G01X-91550D02*
X-98550D01*
Y665000D01*
X-91550D01*
G01X-94350Y657750D02*
X-98550D01*
G01X-84350Y650000D02*
Y665000D01*
X-79975D01*
X-78575Y664250D01*
X-77700Y663250D01*
X-77350Y661250D01*
X-77700Y659250D01*
X-78750Y658000D01*
X-79975Y657250D01*
X-84350D01*
G01X-79975D02*
X-77350Y650000D01*
G01X-71200D02*
Y665000D01*
X-66650Y652500D01*
X-62100Y665000D01*
Y650000D01*
G01X-56825D02*
X-52450Y665000D01*
X-48075Y650000D01*
G01X-49650Y655250D02*
X-55250D01*
G01X-41925Y652000D02*
X-40525Y650750D01*
X-38950Y650000D01*
X-37550D01*
X-36150Y650750D01*
X-35100Y652000D01*
X-34575Y653750D01*
X-34925Y655500D01*
X-35800Y657000D01*
X-37375Y658000D01*
X-39475Y658500D01*
X-40700Y659500D01*
X-41225Y661250D01*
X-40875Y663000D01*
X-40000Y664250D01*
X-38775Y665000D01*
X-37550D01*
X-36325Y664500D01*
X-35275Y663250D01*
G01X-27900Y650000D02*
Y665000D01*
G01X-21250D02*
X-27900Y655750D01*
G01X-20200Y650000D02*
X-24925Y660000D01*
G01X2250Y665000D02*
X6450D01*
G01X4350D02*
Y650000D01*
G01X2250D02*
X6450D01*
G01X14525D02*
Y665000D01*
X22575Y650000D01*
Y665000D01*
G01X32750D02*
Y650000D01*
G01X28725Y665000D02*
X36775D01*
G01X46950Y650000D02*
X45550Y650250D01*
X44325Y651250D01*
X43275Y652750D01*
X42575Y654500D01*
X42225Y656500D01*
Y658500D01*
X42575Y660500D01*
X43275Y662250D01*
X44325Y663750D01*
X45550Y664750D01*
X46950Y665000D01*
X48350Y664750D01*
X49575Y663750D01*
X50625Y662250D01*
X51325Y660500D01*
X51675Y658500D01*
Y656500D01*
X51325Y654500D01*
X50625Y652750D01*
X49575Y651250D01*
X48350Y650250D01*
X46950Y650000D01*
G01X75350Y665000D02*
Y650000D01*
G01X71325Y665000D02*
X79375D01*
G01X85875Y650000D02*
Y665000D01*
G01X93225D02*
Y650000D01*
G01Y657500D02*
X85875D01*
G01X107250Y650000D02*
X100250D01*
Y665000D01*
X107250D01*
G01X104450Y657750D02*
X100250D01*
G01X127775Y665000D02*
X132150Y650000D01*
X136525Y665000D01*
G01X144250D02*
X148450D01*
G01X146350D02*
Y650000D01*
G01X144250D02*
X148450D01*
G01X156175D02*
X160550Y665000D01*
X164925Y650000D01*
G01X163350Y655250D02*
X157750D01*
G01X171075Y652000D02*
X172475Y650750D01*
X174050Y650000D01*
X175450D01*
X176850Y650750D01*
X177900Y652000D01*
X178425Y653750D01*
X178075Y655500D01*
X177200Y657000D01*
X175625Y658000D01*
X173525Y658500D01*
X172300Y659500D01*
X171775Y661250D01*
X172125Y663000D01*
X173000Y664250D01*
X174225Y665000D01*
X175450D01*
X176675Y664500D01*
X177725Y663250D01*
G01X199825Y650000D02*
Y665000D01*
X206475D01*
G01X204025Y657750D02*
X199825D01*
G01X213850Y650000D02*
Y665000D01*
X218225D01*
X219625Y664250D01*
X220500Y663250D01*
X220850Y661250D01*
X220500Y659250D01*
X219450Y658000D01*
X218225Y657250D01*
X213850D01*
G01X218225D02*
X220850Y650000D01*
G01X231550D02*
X230150Y650250D01*
X228925Y651250D01*
X227875Y652750D01*
X227175Y654500D01*
X226825Y656500D01*
Y658500D01*
X227175Y660500D01*
X227875Y662250D01*
X228925Y663750D01*
X230150Y664750D01*
X231550Y665000D01*
X232950Y664750D01*
X234175Y663750D01*
X235225Y662250D01*
X235925Y660500D01*
X236275Y658500D01*
Y656500D01*
X235925Y654500D01*
X235225Y652750D01*
X234175Y651250D01*
X232950Y650250D01*
X231550Y650000D01*
G01X241200D02*
Y665000D01*
X245750Y652500D01*
X250300Y665000D01*
Y650000D01*
G01X274150Y665000D02*
Y650000D01*
G01X270125Y665000D02*
X278175D01*
G01X284675Y650000D02*
Y665000D01*
G01X292025D02*
Y650000D01*
G01Y657500D02*
X284675D01*
G01X306050Y650000D02*
X299050D01*
Y665000D01*
X306050D01*
G01X303250Y657750D02*
X299050D01*
G01X327275Y652000D02*
X328675Y650750D01*
X330250Y650000D01*
X331650D01*
X333050Y650750D01*
X334100Y652000D01*
X334625Y653750D01*
X334275Y655500D01*
X333400Y657000D01*
X331825Y658000D01*
X329725Y658500D01*
X328500Y659500D01*
X327975Y661250D01*
X328325Y663000D01*
X329200Y664250D01*
X330425Y665000D01*
X331650D01*
X332875Y664500D01*
X333925Y663250D01*
G01X343050Y665000D02*
X347250D01*
G01X345150D02*
Y650000D01*
G01X343050D02*
X347250D01*
G01X355500D02*
Y665000D01*
X359000D01*
X360400Y664250D01*
X361450Y663250D01*
X362325Y661750D01*
X363025Y660000D01*
X363200Y657500D01*
X363025Y655000D01*
X362325Y653250D01*
X361450Y651750D01*
X360400Y650750D01*
X359000Y650000D01*
X355500D01*
G01X377050D02*
X370050D01*
Y665000D01*
X377050D01*
G01X374250Y657750D02*
X370050D01*
G01X401950Y650000D02*
X400550Y650250D01*
X399325Y651250D01*
X398275Y652750D01*
X397575Y654500D01*
X397225Y656500D01*
Y658500D01*
X397575Y660500D01*
X398275Y662250D01*
X399325Y663750D01*
X400550Y664750D01*
X401950Y665000D01*
X403350Y664750D01*
X404575Y663750D01*
X405625Y662250D01*
X406325Y660500D01*
X406675Y658500D01*
Y656500D01*
X406325Y654500D01*
X405625Y652750D01*
X404575Y651250D01*
X403350Y650250D01*
X401950Y650000D01*
G01X412650D02*
Y665000D01*
X416850D01*
X418250Y664250D01*
X419300Y662500D01*
X419650Y660500D01*
X419300Y658500D01*
X418425Y657000D01*
X416850Y656250D01*
X412650D01*
G01X426850Y650000D02*
Y665000D01*
X431050D01*
X432450Y664250D01*
X433500Y662500D01*
X433850Y660500D01*
X433500Y658500D01*
X432625Y657000D01*
X431050Y656250D01*
X426850D01*
G01X444550Y650000D02*
X443150Y650250D01*
X441925Y651250D01*
X440875Y652750D01*
X440175Y654500D01*
X439825Y656500D01*
Y658500D01*
X440175Y660500D01*
X440875Y662250D01*
X441925Y663750D01*
X443150Y664750D01*
X444550Y665000D01*
X445950Y664750D01*
X447175Y663750D01*
X448225Y662250D01*
X448925Y660500D01*
X449275Y658500D01*
Y656500D01*
X448925Y654500D01*
X448225Y652750D01*
X447175Y651250D01*
X445950Y650250D01*
X444550Y650000D01*
G01X455075Y652000D02*
X456475Y650750D01*
X458050Y650000D01*
X459450D01*
X460850Y650750D01*
X461900Y652000D01*
X462425Y653750D01*
X462075Y655500D01*
X461200Y657000D01*
X459625Y658000D01*
X457525Y658500D01*
X456300Y659500D01*
X455775Y661250D01*
X456125Y663000D01*
X457000Y664250D01*
X458225Y665000D01*
X459450D01*
X460675Y664500D01*
X461725Y663250D01*
G01X470850Y665000D02*
X475050D01*
G01X472950D02*
Y650000D01*
G01X470850D02*
X475050D01*
G01X487150Y665000D02*
Y650000D01*
G01X483125Y665000D02*
X491175D01*
G01X504850Y650000D02*
X497850D01*
Y665000D01*
X504850D01*
G01X502050Y657750D02*
X497850D01*
G01X529750Y665000D02*
Y650000D01*
G01X525725Y665000D02*
X533775D01*
G01X540275Y650000D02*
Y665000D01*
G01X547625D02*
Y650000D01*
G01Y657500D02*
X540275D01*
G01X561650Y650000D02*
X554650D01*
Y665000D01*
X561650D01*
G01X558850Y657750D02*
X554650D01*
G01X586550Y665000D02*
Y650000D01*
G01X582525Y665000D02*
X590575D01*
G01X604250Y650000D02*
X597250D01*
Y665000D01*
X604250D01*
G01X601450Y657750D02*
X597250D01*
G01X611275Y652000D02*
X612675Y650750D01*
X614250Y650000D01*
X615650D01*
X617050Y650750D01*
X618100Y652000D01*
X618625Y653750D01*
X618275Y655500D01*
X617400Y657000D01*
X615825Y658000D01*
X613725Y658500D01*
X612500Y659500D01*
X611975Y661250D01*
X612325Y663000D01*
X613200Y664250D01*
X614425Y665000D01*
X615650D01*
X616875Y664500D01*
X617925Y663250D01*
G01X629150Y665000D02*
Y650000D01*
G01X625125Y665000D02*
X633175D01*
G01X654050Y650000D02*
Y665000D01*
X658250D01*
X659650Y664250D01*
X660700Y662500D01*
X661050Y660500D01*
X660700Y658500D01*
X659825Y657000D01*
X658250Y656250D01*
X654050D01*
G01X667375Y650000D02*
X671750Y665000D01*
X676125Y650000D01*
G01X674550Y655250D02*
X668950D01*
G01X682100Y650000D02*
Y665000D01*
X685600D01*
X687000Y664250D01*
X688050Y663250D01*
X688925Y661750D01*
X689625Y660000D01*
X689800Y657500D01*
X689625Y655000D01*
X688925Y653250D01*
X688050Y651750D01*
X687000Y650750D01*
X685600Y650000D01*
X682100D01*
G01X696475Y652000D02*
X697875Y650750D01*
X699450Y650000D01*
X700850D01*
X702250Y650750D01*
X703300Y652000D01*
X703825Y653750D01*
X703475Y655500D01*
X702600Y657000D01*
X701025Y658000D01*
X698925Y658500D01*
X697700Y659500D01*
X697175Y661250D01*
X697525Y663000D01*
X698400Y664250D01*
X699625Y665000D01*
X700850D01*
X702075Y664500D01*
X703125Y663250D01*
G01X714350Y649500D02*
X714000Y649750D01*
Y650250D01*
X714350Y650500D01*
X714700Y650250D01*
Y649750D01*
X714350Y649500D01*
G01X-336450Y680000D02*
X-337850Y680250D01*
X-339075Y681250D01*
X-340125Y682750D01*
X-340825Y684500D01*
X-341175Y686500D01*
Y688500D01*
X-340825Y690500D01*
X-340125Y692250D01*
X-339075Y693750D01*
X-337850Y694750D01*
X-336450Y695000D01*
X-335050Y694750D01*
X-333825Y693750D01*
X-332775Y692250D01*
X-332075Y690500D01*
X-331725Y688500D01*
Y686500D01*
X-332075Y684500D01*
X-332775Y682750D01*
X-333825Y681250D01*
X-335050Y680250D01*
X-336450Y680000D01*
G01X-325575D02*
Y695000D01*
X-318925D01*
G01X-321375Y687750D02*
X-325575D01*
G01X-293850Y695000D02*
Y680000D01*
G01X-297875Y695000D02*
X-289825D01*
G01X-283325Y680000D02*
Y695000D01*
G01X-275975D02*
Y680000D01*
G01Y687500D02*
X-283325D01*
G01X-261950Y680000D02*
X-268950D01*
Y695000D01*
X-261950D01*
G01X-264750Y687750D02*
X-268950D01*
G01X-241425Y695000D02*
X-237050Y680000D01*
X-232675Y695000D01*
G01X-224950D02*
X-220750D01*
G01X-222850D02*
Y680000D01*
G01X-224950D02*
X-220750D01*
G01X-213025D02*
X-208650Y695000D01*
X-204275Y680000D01*
G01X-205850Y685250D02*
X-211450D01*
G01X-194450Y679500D02*
X-194800Y679750D01*
Y680250D01*
X-194450Y680500D01*
X-194100Y680250D01*
Y679750D01*
X-194450Y679500D01*
G01X-151850Y695000D02*
Y680000D01*
G01X-155875Y695000D02*
X-147825D01*
G01X-141325Y680000D02*
Y695000D01*
G01X-133975D02*
Y680000D01*
G01Y687500D02*
X-141325D01*
G01X-119950Y680000D02*
X-126950D01*
Y695000D01*
X-119950D01*
G01X-122750Y687750D02*
X-126950D01*
G01X-109250Y680000D02*
Y686750D01*
X-112750Y695000D01*
G01X-105750D02*
X-109250Y686750D01*
G01X-85225Y680000D02*
X-80850Y695000D01*
X-76475Y680000D01*
G01X-78050Y685250D02*
X-83650D01*
G01X-70150Y680000D02*
Y695000D01*
X-65775D01*
X-64375Y694250D01*
X-63500Y693250D01*
X-63150Y691250D01*
X-63500Y689250D01*
X-64550Y688000D01*
X-65775Y687250D01*
X-70150D01*
G01X-65775D02*
X-63150Y680000D01*
G01X-48950D02*
X-55950D01*
Y695000D01*
X-48950D01*
G01X-51750Y687750D02*
X-55950D01*
G01X-27550Y680000D02*
Y695000D01*
X-23175D01*
X-21775Y694250D01*
X-20900Y693250D01*
X-20550Y691250D01*
X-20900Y689250D01*
X-21950Y688000D01*
X-23175Y687250D01*
X-27550D01*
G01X-23175D02*
X-20550Y680000D01*
G01X-6350D02*
X-13350D01*
Y695000D01*
X-6350D01*
G01X-9150Y687750D02*
X-13350D01*
G01X4350Y680000D02*
X2950Y680250D01*
X1725Y681250D01*
X675Y682750D01*
X-25Y684500D01*
X-375Y686500D01*
Y688500D01*
X-25Y690500D01*
X675Y692250D01*
X1725Y693750D01*
X2950Y694750D01*
X4350Y695000D01*
X5750Y694750D01*
X6975Y693750D01*
X8025Y692250D01*
X8725Y690500D01*
X9075Y688500D01*
Y686500D01*
X8725Y684500D01*
X8025Y682750D01*
X6975Y681250D01*
X5750Y680250D01*
X4350Y680000D01*
G01X5750Y684000D02*
X7850Y680000D01*
G01X14700Y695000D02*
Y684250D01*
X15400Y682000D01*
X16800Y680500D01*
X18550Y680000D01*
X20300Y680500D01*
X21700Y682000D01*
X22400Y684250D01*
Y695000D01*
G01X30650D02*
X34850D01*
G01X32750D02*
Y680000D01*
G01X30650D02*
X34850D01*
G01X43450D02*
Y695000D01*
X47825D01*
X49225Y694250D01*
X50100Y693250D01*
X50450Y691250D01*
X50100Y689250D01*
X49050Y688000D01*
X47825Y687250D01*
X43450D01*
G01X47825D02*
X50450Y680000D01*
G01X64650D02*
X57650D01*
Y695000D01*
X64650D01*
G01X61850Y687750D02*
X57650D01*
G01X71500Y680000D02*
Y695000D01*
X75000D01*
X76400Y694250D01*
X77450Y693250D01*
X78325Y691750D01*
X79025Y690000D01*
X79200Y687500D01*
X79025Y685000D01*
X78325Y683250D01*
X77450Y681750D01*
X76400Y680750D01*
X75000Y680000D01*
X71500D01*
G01X103750Y695000D02*
Y680000D01*
G01X99725Y695000D02*
X107775D01*
G01X117950Y680000D02*
X116550Y680250D01*
X115325Y681250D01*
X114275Y682750D01*
X113575Y684500D01*
X113225Y686500D01*
Y688500D01*
X113575Y690500D01*
X114275Y692250D01*
X115325Y693750D01*
X116550Y694750D01*
X117950Y695000D01*
X119350Y694750D01*
X120575Y693750D01*
X121625Y692250D01*
X122325Y690500D01*
X122675Y688500D01*
Y686500D01*
X122325Y684500D01*
X121625Y682750D01*
X120575Y681250D01*
X119350Y680250D01*
X117950Y680000D01*
G01X147750Y688000D02*
X148450Y688750D01*
X148975Y690000D01*
X149325Y691750D01*
X148975Y693250D01*
X148275Y694250D01*
X147050Y695000D01*
X142325D01*
Y680000D01*
X148100D01*
X149325Y681000D01*
X150025Y682500D01*
X150375Y684250D01*
X150025Y686000D01*
X148975Y687500D01*
X147750Y688000D01*
X142325D01*
G01X164050Y680000D02*
X157050D01*
Y695000D01*
X164050D01*
G01X161250Y687750D02*
X157050D01*
G01X185275Y682000D02*
X186675Y680750D01*
X188250Y680000D01*
X189650D01*
X191050Y680750D01*
X192100Y682000D01*
X192625Y683750D01*
X192275Y685500D01*
X191400Y687000D01*
X189825Y688000D01*
X187725Y688500D01*
X186500Y689500D01*
X185975Y691250D01*
X186325Y693000D01*
X187200Y694250D01*
X188425Y695000D01*
X189650D01*
X190875Y694500D01*
X191925Y693250D01*
G01X203150Y695000D02*
Y680000D01*
G01X199125Y695000D02*
X207175D01*
G01X213500D02*
Y684250D01*
X214200Y682000D01*
X215600Y680500D01*
X217350Y680000D01*
X219100Y680500D01*
X220500Y682000D01*
X221200Y684250D01*
Y695000D01*
G01X228225Y680000D02*
Y695000D01*
X234875D01*
G01X232425Y687750D02*
X228225D01*
G01X242425Y680000D02*
Y695000D01*
X249075D01*
G01X246625Y687750D02*
X242425D01*
G01X263450Y680000D02*
X256450D01*
Y695000D01*
X263450D01*
G01X260650Y687750D02*
X256450D01*
G01X270300Y680000D02*
Y695000D01*
X273800D01*
X275200Y694250D01*
X276250Y693250D01*
X277125Y691750D01*
X277825Y690000D01*
X278000Y687500D01*
X277825Y685000D01*
X277125Y683250D01*
X276250Y681750D01*
X275200Y680750D01*
X273800Y680000D01*
X270300D01*
G01X298700Y683000D02*
X299750Y681250D01*
X301150Y680250D01*
X302725Y680000D01*
X304125Y680250D01*
X305525Y681500D01*
X306400Y683000D01*
X306575Y684500D01*
X306225Y686250D01*
X305000Y687500D01*
X303775Y688000D01*
X302200D01*
G01X303775D02*
X304825Y688750D01*
X305700Y690000D01*
X306050Y691500D01*
X305700Y693000D01*
X304825Y694250D01*
X303250Y695000D01*
X301675Y694750D01*
X300100Y693750D01*
G01X330950Y695000D02*
Y680000D01*
G01X326925Y695000D02*
X334975D01*
G01X343050D02*
X347250D01*
G01X345150D02*
Y680000D01*
G01X343050D02*
X347250D01*
G01X354800D02*
Y695000D01*
X359350Y682500D01*
X363900Y695000D01*
Y680000D01*
G01X377050D02*
X370050D01*
Y695000D01*
X377050D01*
G01X374250Y687750D02*
X370050D01*
G01X384075Y682000D02*
X385475Y680750D01*
X387050Y680000D01*
X388450D01*
X389850Y680750D01*
X390900Y682000D01*
X391425Y683750D01*
X391075Y685500D01*
X390200Y687000D01*
X388625Y688000D01*
X386525Y688500D01*
X385300Y689500D01*
X384775Y691250D01*
X385125Y693000D01*
X386000Y694250D01*
X387225Y695000D01*
X388450D01*
X389675Y694500D01*
X390725Y693250D01*
G01X411775Y680000D02*
X416150Y695000D01*
X420525Y680000D01*
G01X418950Y685250D02*
X413350D01*
G01X426675Y682000D02*
X428075Y680750D01*
X429650Y680000D01*
X431050D01*
X432450Y680750D01*
X433500Y682000D01*
X434025Y683750D01*
X433675Y685500D01*
X432800Y687000D01*
X431225Y688000D01*
X429125Y688500D01*
X427900Y689500D01*
X427375Y691250D01*
X427725Y693000D01*
X428600Y694250D01*
X429825Y695000D01*
X431050D01*
X432275Y694500D01*
X433325Y693250D01*
G01X455425Y680000D02*
Y695000D01*
X462075D01*
G01X459625Y687750D02*
X455425D01*
G01X472950Y680000D02*
X471550Y680250D01*
X470325Y681250D01*
X469275Y682750D01*
X468575Y684500D01*
X468225Y686500D01*
Y688500D01*
X468575Y690500D01*
X469275Y692250D01*
X470325Y693750D01*
X471550Y694750D01*
X472950Y695000D01*
X474350Y694750D01*
X475575Y693750D01*
X476625Y692250D01*
X477325Y690500D01*
X477675Y688500D01*
Y686500D01*
X477325Y684500D01*
X476625Y682750D01*
X475575Y681250D01*
X474350Y680250D01*
X472950Y680000D01*
G01X483650Y695000D02*
Y680000D01*
X490650D01*
G01X497850Y695000D02*
Y680000D01*
X504850D01*
G01X515550D02*
X514150Y680250D01*
X512925Y681250D01*
X511875Y682750D01*
X511175Y684500D01*
X510825Y686500D01*
Y688500D01*
X511175Y690500D01*
X511875Y692250D01*
X512925Y693750D01*
X514150Y694750D01*
X515550Y695000D01*
X516950Y694750D01*
X518175Y693750D01*
X519225Y692250D01*
X519925Y690500D01*
X520275Y688500D01*
Y686500D01*
X519925Y684500D01*
X519225Y682750D01*
X518175Y681250D01*
X516950Y680250D01*
X515550Y680000D01*
G01X524500Y695000D02*
X526950Y680000D01*
X529750Y695000D01*
X532550Y680000D01*
X535000Y695000D01*
G01X540275Y682000D02*
X541675Y680750D01*
X543250Y680000D01*
X544650D01*
X546050Y680750D01*
X547100Y682000D01*
X547625Y683750D01*
X547275Y685500D01*
X546400Y687000D01*
X544825Y688000D01*
X542725Y688500D01*
X541500Y689500D01*
X540975Y691250D01*
X541325Y693000D01*
X542200Y694250D01*
X543425Y695000D01*
X544650D01*
X545875Y694500D01*
X546925Y693250D01*
G01X558150Y679500D02*
X557800Y679750D01*
Y680250D01*
X558150Y680500D01*
X558500Y680250D01*
Y679750D01*
X558150Y679500D01*
G01Y686250D02*
X557800Y686500D01*
Y687000D01*
X558150Y687250D01*
X558500Y687000D01*
Y686500D01*
X558150Y686250D01*
G01X-340825Y725000D02*
X-336450Y710000D01*
X-332075Y725000D01*
G01X-324350D02*
X-320150D01*
G01X-322250D02*
Y710000D01*
G01X-324350D02*
X-320150D01*
G01X-312425D02*
X-308050Y725000D01*
X-303675Y710000D01*
G01X-305250Y715250D02*
X-310850D01*
G01X-279650Y725000D02*
Y710000D01*
G01X-283675Y725000D02*
X-275625D01*
G01X-265450Y710000D02*
X-266850Y710250D01*
X-268075Y711250D01*
X-269125Y712750D01*
X-269825Y714500D01*
X-270175Y716500D01*
Y718500D01*
X-269825Y720500D01*
X-269125Y722250D01*
X-268075Y723750D01*
X-266850Y724750D01*
X-265450Y725000D01*
X-264050Y724750D01*
X-262825Y723750D01*
X-261775Y722250D01*
X-261075Y720500D01*
X-260725Y718500D01*
Y716500D01*
X-261075Y714500D01*
X-261775Y712750D01*
X-262825Y711250D01*
X-264050Y710250D01*
X-265450Y710000D01*
G01X-237050Y725000D02*
Y710000D01*
G01X-241075Y725000D02*
X-233025D01*
G01X-226525Y710000D02*
Y725000D01*
G01X-219175D02*
Y710000D01*
G01Y717500D02*
X-226525D01*
G01X-205150Y710000D02*
X-212150D01*
Y725000D01*
X-205150D01*
G01X-207950Y717750D02*
X-212150D01*
G01X-180250Y710000D02*
X-181650Y710250D01*
X-182875Y711250D01*
X-183925Y712750D01*
X-184625Y714500D01*
X-184975Y716500D01*
Y718500D01*
X-184625Y720500D01*
X-183925Y722250D01*
X-182875Y723750D01*
X-181650Y724750D01*
X-180250Y725000D01*
X-178850Y724750D01*
X-177625Y723750D01*
X-176575Y722250D01*
X-175875Y720500D01*
X-175525Y718500D01*
Y716500D01*
X-175875Y714500D01*
X-176575Y712750D01*
X-177625Y711250D01*
X-178850Y710250D01*
X-180250Y710000D01*
G01X-166050Y725000D02*
Y710000D01*
G01X-170075Y725000D02*
X-162025D01*
G01X-155525Y710000D02*
Y725000D01*
G01X-148175D02*
Y710000D01*
G01Y717500D02*
X-155525D01*
G01X-134150Y710000D02*
X-141150D01*
Y725000D01*
X-134150D01*
G01X-136950Y717750D02*
X-141150D01*
G01X-126950Y710000D02*
Y725000D01*
X-122575D01*
X-121175Y724250D01*
X-120300Y723250D01*
X-119950Y721250D01*
X-120300Y719250D01*
X-121350Y718000D01*
X-122575Y717250D01*
X-126950D01*
G01X-122575D02*
X-119950Y710000D01*
G01X-109250Y709500D02*
X-109600Y709750D01*
Y710250D01*
X-109250Y710500D01*
X-108900Y710250D01*
Y709750D01*
X-109250Y709500D01*
G01X-66650Y725000D02*
Y710000D01*
G01X-70675Y725000D02*
X-62625D01*
G01X-56125Y710000D02*
Y725000D01*
G01X-48775D02*
Y710000D01*
G01Y717500D02*
X-56125D01*
G01X-34750Y710000D02*
X-41750D01*
Y725000D01*
X-34750D01*
G01X-37550Y717750D02*
X-41750D01*
G01X-27550Y710000D02*
Y725000D01*
X-23175D01*
X-21775Y724250D01*
X-20900Y723250D01*
X-20550Y721250D01*
X-20900Y719250D01*
X-21950Y718000D01*
X-23175Y717250D01*
X-27550D01*
G01X-23175D02*
X-20550Y710000D01*
G01X-6350D02*
X-13350D01*
Y725000D01*
X-6350D01*
G01X-9150Y717750D02*
X-13350D01*
G01X16450Y725000D02*
X20650D01*
G01X18550D02*
Y710000D01*
G01X16450D02*
X20650D01*
G01X29075Y712000D02*
X30475Y710750D01*
X32050Y710000D01*
X33450D01*
X34850Y710750D01*
X35900Y712000D01*
X36425Y713750D01*
X36075Y715500D01*
X35200Y717000D01*
X33625Y718000D01*
X31525Y718500D01*
X30300Y719500D01*
X29775Y721250D01*
X30125Y723000D01*
X31000Y724250D01*
X32225Y725000D01*
X33450D01*
X34675Y724500D01*
X35725Y723250D01*
G01X57125Y710000D02*
Y725000D01*
X65175Y710000D01*
Y725000D01*
G01X75350Y710000D02*
X73950Y710250D01*
X72725Y711250D01*
X71675Y712750D01*
X70975Y714500D01*
X70625Y716500D01*
Y718500D01*
X70975Y720500D01*
X71675Y722250D01*
X72725Y723750D01*
X73950Y724750D01*
X75350Y725000D01*
X76750Y724750D01*
X77975Y723750D01*
X79025Y722250D01*
X79725Y720500D01*
X80075Y718500D01*
Y716500D01*
X79725Y714500D01*
X79025Y712750D01*
X77975Y711250D01*
X76750Y710250D01*
X75350Y710000D01*
G01X107600Y723750D02*
X106550Y724500D01*
X105325Y725000D01*
X103925D01*
X102350Y724250D01*
X101125Y723000D01*
X100250Y721500D01*
X99550Y719000D01*
X99375Y716750D01*
X99725Y714500D01*
X100250Y713000D01*
X101300Y711500D01*
X102525Y710500D01*
X103750Y710000D01*
X104975D01*
X106200Y710500D01*
X107250Y711250D01*
X108125Y712250D01*
G01X117950Y710000D02*
X116550Y710250D01*
X115325Y711250D01*
X114275Y712750D01*
X113575Y714500D01*
X113225Y716500D01*
Y718500D01*
X113575Y720500D01*
X114275Y722250D01*
X115325Y723750D01*
X116550Y724750D01*
X117950Y725000D01*
X119350Y724750D01*
X120575Y723750D01*
X121625Y722250D01*
X122325Y720500D01*
X122675Y718500D01*
Y716500D01*
X122325Y714500D01*
X121625Y712750D01*
X120575Y711250D01*
X119350Y710250D01*
X117950Y710000D01*
G01X128125D02*
Y725000D01*
X136175Y710000D01*
Y725000D01*
G01X146350D02*
Y710000D01*
G01X142325Y725000D02*
X150375D01*
G01X158450D02*
X162650D01*
G01X160550D02*
Y710000D01*
G01X158450D02*
X162650D01*
G01X170725D02*
Y725000D01*
X178775Y710000D01*
Y725000D01*
G01X185100D02*
Y714250D01*
X185800Y712000D01*
X187200Y710500D01*
X188950Y710000D01*
X190700Y710500D01*
X192100Y712000D01*
X192800Y714250D01*
Y725000D01*
G01X203150Y710000D02*
X201750Y710250D01*
X200525Y711250D01*
X199475Y712750D01*
X198775Y714500D01*
X198425Y716500D01*
Y718500D01*
X198775Y720500D01*
X199475Y722250D01*
X200525Y723750D01*
X201750Y724750D01*
X203150Y725000D01*
X204550Y724750D01*
X205775Y723750D01*
X206825Y722250D01*
X207525Y720500D01*
X207875Y718500D01*
Y716500D01*
X207525Y714500D01*
X206825Y712750D01*
X205775Y711250D01*
X204550Y710250D01*
X203150Y710000D01*
G01X213500Y725000D02*
Y714250D01*
X214200Y712000D01*
X215600Y710500D01*
X217350Y710000D01*
X219100Y710500D01*
X220500Y712000D01*
X221200Y714250D01*
Y725000D01*
G01X227875Y712000D02*
X229275Y710750D01*
X230850Y710000D01*
X232250D01*
X233650Y710750D01*
X234700Y712000D01*
X235225Y713750D01*
X234875Y715500D01*
X234000Y717000D01*
X232425Y718000D01*
X230325Y718500D01*
X229100Y719500D01*
X228575Y721250D01*
X228925Y723000D01*
X229800Y724250D01*
X231025Y725000D01*
X232250D01*
X233475Y724500D01*
X234525Y723250D01*
G01X255575Y710000D02*
X259950Y725000D01*
X264325Y710000D01*
G01X262750Y715250D02*
X257150D01*
G01X272050Y725000D02*
X276250D01*
G01X274150D02*
Y710000D01*
G01X272050D02*
X276250D01*
G01X284850D02*
Y725000D01*
X289225D01*
X290625Y724250D01*
X291500Y723250D01*
X291850Y721250D01*
X291500Y719250D01*
X290450Y718000D01*
X289225Y717250D01*
X284850D01*
G01X289225D02*
X291850Y710000D01*
G01X317800Y717500D02*
X321300D01*
Y713000D01*
X320250Y711500D01*
X319025Y710500D01*
X317275Y710000D01*
X315525Y710500D01*
X314300Y711500D01*
X313250Y713000D01*
X312550Y714750D01*
X312200Y716750D01*
Y718500D01*
X312550Y720000D01*
X313250Y721750D01*
X314300Y723250D01*
X315350Y724250D01*
X316750Y725000D01*
X317975D01*
X319375Y724500D01*
X320425Y723500D01*
G01X326575Y710000D02*
X330950Y725000D01*
X335325Y710000D01*
G01X333750Y715250D02*
X328150D01*
G01X341650Y710000D02*
Y725000D01*
X345850D01*
X347250Y724250D01*
X348300Y722500D01*
X348650Y720500D01*
X348300Y718500D01*
X347425Y717000D01*
X345850Y716250D01*
X341650D01*
G01X370225Y710000D02*
Y725000D01*
X376875D01*
G01X374425Y717750D02*
X370225D01*
G01X384250Y710000D02*
Y725000D01*
X388625D01*
X390025Y724250D01*
X390900Y723250D01*
X391250Y721250D01*
X390900Y719250D01*
X389850Y718000D01*
X388625Y717250D01*
X384250D01*
G01X388625D02*
X391250Y710000D01*
G01X401950D02*
X400550Y710250D01*
X399325Y711250D01*
X398275Y712750D01*
X397575Y714500D01*
X397225Y716500D01*
Y718500D01*
X397575Y720500D01*
X398275Y722250D01*
X399325Y723750D01*
X400550Y724750D01*
X401950Y725000D01*
X403350Y724750D01*
X404575Y723750D01*
X405625Y722250D01*
X406325Y720500D01*
X406675Y718500D01*
Y716500D01*
X406325Y714500D01*
X405625Y712750D01*
X404575Y711250D01*
X403350Y710250D01*
X401950Y710000D01*
G01X411600D02*
Y725000D01*
X416150Y712500D01*
X420700Y725000D01*
Y710000D01*
G01X444550D02*
X443150Y710250D01*
X441925Y711250D01*
X440875Y712750D01*
X440175Y714500D01*
X439825Y716500D01*
Y718500D01*
X440175Y720500D01*
X440875Y722250D01*
X441925Y723750D01*
X443150Y724750D01*
X444550Y725000D01*
X445950Y724750D01*
X447175Y723750D01*
X448225Y722250D01*
X448925Y720500D01*
X449275Y718500D01*
Y716500D01*
X448925Y714500D01*
X448225Y712750D01*
X447175Y711250D01*
X445950Y710250D01*
X444550Y710000D01*
G01X454725D02*
Y725000D01*
X462775Y710000D01*
Y725000D01*
G01X476450Y710000D02*
X469450D01*
Y725000D01*
X476450D01*
G01X473650Y717750D02*
X469450D01*
G01X504850Y710000D02*
X497850D01*
Y725000D01*
X504850D01*
G01X502050Y717750D02*
X497850D01*
G01X511525Y710000D02*
Y725000D01*
X519575Y710000D01*
Y725000D01*
G01X525900Y710000D02*
Y725000D01*
X529400D01*
X530800Y724250D01*
X531850Y723250D01*
X532725Y721750D01*
X533425Y720000D01*
X533600Y717500D01*
X533425Y715000D01*
X532725Y713250D01*
X531850Y711750D01*
X530800Y710750D01*
X529400Y710000D01*
X525900D01*
G01X558150Y725000D02*
Y710000D01*
G01X554125Y725000D02*
X562175D01*
G01X572350Y710000D02*
X570950Y710250D01*
X569725Y711250D01*
X568675Y712750D01*
X567975Y714500D01*
X567625Y716500D01*
Y718500D01*
X567975Y720500D01*
X568675Y722250D01*
X569725Y723750D01*
X570950Y724750D01*
X572350Y725000D01*
X573750Y724750D01*
X574975Y723750D01*
X576025Y722250D01*
X576725Y720500D01*
X577075Y718500D01*
Y716500D01*
X576725Y714500D01*
X576025Y712750D01*
X574975Y711250D01*
X573750Y710250D01*
X572350Y710000D01*
G01X600750Y725000D02*
Y710000D01*
G01X596725Y725000D02*
X604775D01*
G01X611275Y710000D02*
Y725000D01*
G01X618625D02*
Y710000D01*
G01Y717500D02*
X611275D01*
G01X632650Y710000D02*
X625650D01*
Y725000D01*
X632650D01*
G01X629850Y717750D02*
X625650D01*
G01X657550Y710000D02*
X656150Y710250D01*
X654925Y711250D01*
X653875Y712750D01*
X653175Y714500D01*
X652825Y716500D01*
Y718500D01*
X653175Y720500D01*
X653875Y722250D01*
X654925Y723750D01*
X656150Y724750D01*
X657550Y725000D01*
X658950Y724750D01*
X660175Y723750D01*
X661225Y722250D01*
X661925Y720500D01*
X662275Y718500D01*
Y716500D01*
X661925Y714500D01*
X661225Y712750D01*
X660175Y711250D01*
X658950Y710250D01*
X657550Y710000D01*
G01X671750Y725000D02*
Y710000D01*
G01X667725Y725000D02*
X675775D01*
G01X682275Y710000D02*
Y725000D01*
G01X689625D02*
Y710000D01*
G01Y717500D02*
X682275D01*
G01X703650Y710000D02*
X696650D01*
Y725000D01*
X703650D01*
G01X700850Y717750D02*
X696650D01*
G01X710850Y710000D02*
Y725000D01*
X715225D01*
X716625Y724250D01*
X717500Y723250D01*
X717850Y721250D01*
X717500Y719250D01*
X716450Y718000D01*
X715225Y717250D01*
X710850D01*
G01X715225D02*
X717850Y710000D01*
G01X746250D02*
X739250D01*
Y725000D01*
X746250D01*
G01X743450Y717750D02*
X739250D01*
G01X752925Y710000D02*
Y725000D01*
X760975Y710000D01*
Y725000D01*
G01X767300Y710000D02*
Y725000D01*
X770800D01*
X772200Y724250D01*
X773250Y723250D01*
X774125Y721750D01*
X774825Y720000D01*
X775000Y717500D01*
X774825Y715000D01*
X774125Y713250D01*
X773250Y711750D01*
X772200Y710750D01*
X770800Y710000D01*
X767300D01*
G01X-339950Y740000D02*
Y755000D01*
X-335750D01*
X-334350Y754250D01*
X-333300Y752500D01*
X-332950Y750500D01*
X-333300Y748500D01*
X-334175Y747000D01*
X-335750Y746250D01*
X-339950D01*
G01X-326625Y740000D02*
X-322250Y755000D01*
X-317875Y740000D01*
G01X-319450Y745250D02*
X-325050D01*
G01X-311900Y740000D02*
Y755000D01*
X-308400D01*
X-307000Y754250D01*
X-305950Y753250D01*
X-305075Y751750D01*
X-304375Y750000D01*
X-304200Y747500D01*
X-304375Y745000D01*
X-305075Y743250D01*
X-305950Y741750D01*
X-307000Y740750D01*
X-308400Y740000D01*
X-311900D01*
G01X-297525Y742000D02*
X-296125Y740750D01*
X-294550Y740000D01*
X-293150D01*
X-291750Y740750D01*
X-290700Y742000D01*
X-290175Y743750D01*
X-290525Y745500D01*
X-291400Y747000D01*
X-292975Y748000D01*
X-295075Y748500D01*
X-296300Y749500D01*
X-296825Y751250D01*
X-296475Y753000D01*
X-295600Y754250D01*
X-294375Y755000D01*
X-293150D01*
X-291925Y754500D01*
X-290875Y753250D01*
G01X-279650Y739500D02*
X-280000Y739750D01*
Y740250D01*
X-279650Y740500D01*
X-279300Y740250D01*
Y739750D01*
X-279650Y739500D01*
G01X-239150Y755000D02*
X-234950D01*
G01X-237050D02*
Y740000D01*
G01X-239150D02*
X-234950D01*
G01X-222850Y755000D02*
Y740000D01*
G01X-226875Y755000D02*
X-218825D01*
G01X-196550D02*
X-192350D01*
G01X-194450D02*
Y740000D01*
G01X-196550D02*
X-192350D01*
G01X-183925Y742000D02*
X-182525Y740750D01*
X-180950Y740000D01*
X-179550D01*
X-178150Y740750D01*
X-177100Y742000D01*
X-176575Y743750D01*
X-176925Y745500D01*
X-177800Y747000D01*
X-179375Y748000D01*
X-181475Y748500D01*
X-182700Y749500D01*
X-183225Y751250D01*
X-182875Y753000D01*
X-182000Y754250D01*
X-180775Y755000D01*
X-179550D01*
X-178325Y754500D01*
X-177275Y753250D01*
G01X-155350Y740000D02*
Y755000D01*
X-150975D01*
X-149575Y754250D01*
X-148700Y753250D01*
X-148350Y751250D01*
X-148700Y749250D01*
X-149750Y748000D01*
X-150975Y747250D01*
X-155350D01*
G01X-150975D02*
X-148350Y740000D01*
G01X-134150D02*
X-141150D01*
Y755000D01*
X-134150D01*
G01X-136950Y747750D02*
X-141150D01*
G01X-123450Y740000D02*
X-124850Y740250D01*
X-126075Y741250D01*
X-127125Y742750D01*
X-127825Y744500D01*
X-128175Y746500D01*
Y748500D01*
X-127825Y750500D01*
X-127125Y752250D01*
X-126075Y753750D01*
X-124850Y754750D01*
X-123450Y755000D01*
X-122050Y754750D01*
X-120825Y753750D01*
X-119775Y752250D01*
X-119075Y750500D01*
X-118725Y748500D01*
Y746500D01*
X-119075Y744500D01*
X-119775Y742750D01*
X-120825Y741250D01*
X-122050Y740250D01*
X-123450Y740000D01*
G01X-122050Y744000D02*
X-119950Y740000D01*
G01X-113100Y755000D02*
Y744250D01*
X-112400Y742000D01*
X-111000Y740500D01*
X-109250Y740000D01*
X-107500Y740500D01*
X-106100Y742000D01*
X-105400Y744250D01*
Y755000D01*
G01X-97150D02*
X-92950D01*
G01X-95050D02*
Y740000D01*
G01X-97150D02*
X-92950D01*
G01X-84350D02*
Y755000D01*
X-79975D01*
X-78575Y754250D01*
X-77700Y753250D01*
X-77350Y751250D01*
X-77700Y749250D01*
X-78750Y748000D01*
X-79975Y747250D01*
X-84350D01*
G01X-79975D02*
X-77350Y740000D01*
G01X-63150D02*
X-70150D01*
Y755000D01*
X-63150D01*
G01X-65950Y747750D02*
X-70150D01*
G01X-56300Y740000D02*
Y755000D01*
X-52800D01*
X-51400Y754250D01*
X-50350Y753250D01*
X-49475Y751750D01*
X-48775Y750000D01*
X-48600Y747500D01*
X-48775Y745000D01*
X-49475Y743250D01*
X-50350Y741750D01*
X-51400Y740750D01*
X-52800Y740000D01*
X-56300D01*
G01X-24050Y755000D02*
Y740000D01*
G01X-28075Y755000D02*
X-20025D01*
G01X-13525Y740000D02*
Y755000D01*
G01X-6175D02*
Y740000D01*
G01Y747500D02*
X-13525D01*
G01X-25Y740000D02*
X4350Y755000D01*
X8725Y740000D01*
G01X7150Y745250D02*
X1550D01*
G01X18550Y755000D02*
Y740000D01*
G01X14525Y755000D02*
X22575D01*
G01X42575Y740000D02*
X46950Y755000D01*
X51325Y740000D01*
G01X49750Y745250D02*
X44150D01*
G01X59050Y755000D02*
X63250D01*
G01X61150D02*
Y740000D01*
G01X59050D02*
X63250D01*
G01X71850D02*
Y755000D01*
X76225D01*
X77625Y754250D01*
X78500Y753250D01*
X78850Y751250D01*
X78500Y749250D01*
X77450Y748000D01*
X76225Y747250D01*
X71850D01*
G01X76225D02*
X78850Y740000D01*
G01X100075Y742000D02*
X101475Y740750D01*
X103050Y740000D01*
X104450D01*
X105850Y740750D01*
X106900Y742000D01*
X107425Y743750D01*
X107075Y745500D01*
X106200Y747000D01*
X104625Y748000D01*
X102525Y748500D01*
X101300Y749500D01*
X100775Y751250D01*
X101125Y753000D01*
X102000Y754250D01*
X103225Y755000D01*
X104450D01*
X105675Y754500D01*
X106725Y753250D01*
G01X114275Y740000D02*
Y755000D01*
G01X121625D02*
Y740000D01*
G01Y747500D02*
X114275D01*
G01X127775Y740000D02*
X132150Y755000D01*
X136525Y740000D01*
G01X134950Y745250D02*
X129350D01*
G01X142850Y755000D02*
Y740000D01*
X149850D01*
G01X157050Y755000D02*
Y740000D01*
X164050D01*
G01X184925D02*
Y755000D01*
X192975Y740000D01*
Y755000D01*
G01X203150Y740000D02*
X201750Y740250D01*
X200525Y741250D01*
X199475Y742750D01*
X198775Y744500D01*
X198425Y746500D01*
Y748500D01*
X198775Y750500D01*
X199475Y752250D01*
X200525Y753750D01*
X201750Y754750D01*
X203150Y755000D01*
X204550Y754750D01*
X205775Y753750D01*
X206825Y752250D01*
X207525Y750500D01*
X207875Y748500D01*
Y746500D01*
X207525Y744500D01*
X206825Y742750D01*
X205775Y741250D01*
X204550Y740250D01*
X203150Y740000D01*
G01X217350Y755000D02*
Y740000D01*
G01X213325Y755000D02*
X221375D01*
G01X242425Y740000D02*
Y755000D01*
X249075D01*
G01X246625Y747750D02*
X242425D01*
G01X256450Y755000D02*
Y740000D01*
X263450D01*
G01X274150D02*
X272750Y740250D01*
X271525Y741250D01*
X270475Y742750D01*
X269775Y744500D01*
X269425Y746500D01*
Y748500D01*
X269775Y750500D01*
X270475Y752250D01*
X271525Y753750D01*
X272750Y754750D01*
X274150Y755000D01*
X275550Y754750D01*
X276775Y753750D01*
X277825Y752250D01*
X278525Y750500D01*
X278875Y748500D01*
Y746500D01*
X278525Y744500D01*
X277825Y742750D01*
X276775Y741250D01*
X275550Y740250D01*
X274150Y740000D01*
G01X283100Y755000D02*
X285550Y740000D01*
X288350Y755000D01*
X291150Y740000D01*
X293600Y755000D01*
G01X316750D02*
Y740000D01*
G01X312725Y755000D02*
X320775D01*
G01X327275Y740000D02*
Y755000D01*
G01X334625D02*
Y740000D01*
G01Y747500D02*
X327275D01*
G01X341650Y740000D02*
Y755000D01*
X346025D01*
X347425Y754250D01*
X348300Y753250D01*
X348650Y751250D01*
X348300Y749250D01*
X347250Y748000D01*
X346025Y747250D01*
X341650D01*
G01X346025D02*
X348650Y740000D01*
G01X359350D02*
X357950Y740250D01*
X356725Y741250D01*
X355675Y742750D01*
X354975Y744500D01*
X354625Y746500D01*
Y748500D01*
X354975Y750500D01*
X355675Y752250D01*
X356725Y753750D01*
X357950Y754750D01*
X359350Y755000D01*
X360750Y754750D01*
X361975Y753750D01*
X363025Y752250D01*
X363725Y750500D01*
X364075Y748500D01*
Y746500D01*
X363725Y744500D01*
X363025Y742750D01*
X361975Y741250D01*
X360750Y740250D01*
X359350Y740000D01*
G01X369700Y755000D02*
Y744250D01*
X370400Y742000D01*
X371800Y740500D01*
X373550Y740000D01*
X375300Y740500D01*
X376700Y742000D01*
X377400Y744250D01*
Y755000D01*
G01X388800Y747500D02*
X392300D01*
Y743000D01*
X391250Y741500D01*
X390025Y740500D01*
X388275Y740000D01*
X386525Y740500D01*
X385300Y741500D01*
X384250Y743000D01*
X383550Y744750D01*
X383200Y746750D01*
Y748500D01*
X383550Y750000D01*
X384250Y751750D01*
X385300Y753250D01*
X386350Y754250D01*
X387750Y755000D01*
X388975D01*
X390375Y754500D01*
X391425Y753500D01*
G01X398275Y740000D02*
Y755000D01*
G01X405625D02*
Y740000D01*
G01Y747500D02*
X398275D01*
G01X427025Y740000D02*
Y755000D01*
X433675D01*
G01X431225Y747750D02*
X427025D01*
G01X441050Y740000D02*
Y755000D01*
X445425D01*
X446825Y754250D01*
X447700Y753250D01*
X448050Y751250D01*
X447700Y749250D01*
X446650Y748000D01*
X445425Y747250D01*
X441050D01*
G01X445425D02*
X448050Y740000D01*
G01X458750D02*
X457350Y740250D01*
X456125Y741250D01*
X455075Y742750D01*
X454375Y744500D01*
X454025Y746500D01*
Y748500D01*
X454375Y750500D01*
X455075Y752250D01*
X456125Y753750D01*
X457350Y754750D01*
X458750Y755000D01*
X460150Y754750D01*
X461375Y753750D01*
X462425Y752250D01*
X463125Y750500D01*
X463475Y748500D01*
Y746500D01*
X463125Y744500D01*
X462425Y742750D01*
X461375Y741250D01*
X460150Y740250D01*
X458750Y740000D01*
G01X468400D02*
Y755000D01*
X472950Y742500D01*
X477500Y755000D01*
Y740000D01*
G01X501350D02*
X499950Y740250D01*
X498725Y741250D01*
X497675Y742750D01*
X496975Y744500D01*
X496625Y746500D01*
Y748500D01*
X496975Y750500D01*
X497675Y752250D01*
X498725Y753750D01*
X499950Y754750D01*
X501350Y755000D01*
X502750Y754750D01*
X503975Y753750D01*
X505025Y752250D01*
X505725Y750500D01*
X506075Y748500D01*
Y746500D01*
X505725Y744500D01*
X505025Y742750D01*
X503975Y741250D01*
X502750Y740250D01*
X501350Y740000D01*
G01X511525D02*
Y755000D01*
X519575Y740000D01*
Y755000D01*
G01X533250Y740000D02*
X526250D01*
Y755000D01*
X533250D01*
G01X530450Y747750D02*
X526250D01*
G01X561650Y740000D02*
X554650D01*
Y755000D01*
X561650D01*
G01X558850Y747750D02*
X554650D01*
G01X568325Y740000D02*
Y755000D01*
X576375Y740000D01*
Y755000D01*
G01X582700Y740000D02*
Y755000D01*
X586200D01*
X587600Y754250D01*
X588650Y753250D01*
X589525Y751750D01*
X590225Y750000D01*
X590400Y747500D01*
X590225Y745000D01*
X589525Y743250D01*
X588650Y741750D01*
X587600Y740750D01*
X586200Y740000D01*
X582700D01*
G01X614950D02*
X613550Y740250D01*
X612325Y741250D01*
X611275Y742750D01*
X610575Y744500D01*
X610225Y746500D01*
Y748500D01*
X610575Y750500D01*
X611275Y752250D01*
X612325Y753750D01*
X613550Y754750D01*
X614950Y755000D01*
X616350Y754750D01*
X617575Y753750D01*
X618625Y752250D01*
X619325Y750500D01*
X619675Y748500D01*
Y746500D01*
X619325Y744500D01*
X618625Y742750D01*
X617575Y741250D01*
X616350Y740250D01*
X614950Y740000D01*
G01X625825D02*
Y755000D01*
X632475D01*
G01X630025Y747750D02*
X625825D01*
G01X657550Y755000D02*
Y740000D01*
G01X653525Y755000D02*
X661575D01*
G01X668075Y740000D02*
Y755000D01*
G01X675425D02*
Y740000D01*
G01Y747500D02*
X668075D01*
G01X689450Y740000D02*
X682450D01*
Y755000D01*
X689450D01*
G01X686650Y747750D02*
X682450D01*
G01X714350Y755000D02*
Y740000D01*
G01X710325Y755000D02*
X718375D01*
G01X732050Y740000D02*
X725050D01*
Y755000D01*
X732050D01*
G01X729250Y747750D02*
X725050D01*
G01X739075Y742000D02*
X740475Y740750D01*
X742050Y740000D01*
X743450D01*
X744850Y740750D01*
X745900Y742000D01*
X746425Y743750D01*
X746075Y745500D01*
X745200Y747000D01*
X743625Y748000D01*
X741525Y748500D01*
X740300Y749500D01*
X739775Y751250D01*
X740125Y753000D01*
X741000Y754250D01*
X742225Y755000D01*
X743450D01*
X744675Y754500D01*
X745725Y753250D01*
G01X756950Y755000D02*
Y740000D01*
G01X752925Y755000D02*
X760975D01*
G01X781850Y740000D02*
Y755000D01*
X786050D01*
X787450Y754250D01*
X788500Y752500D01*
X788850Y750500D01*
X788500Y748500D01*
X787625Y747000D01*
X786050Y746250D01*
X781850D01*
G01X795175Y740000D02*
X799550Y755000D01*
X803925Y740000D01*
G01X802350Y745250D02*
X796750D01*
G01X809900Y740000D02*
Y755000D01*
X813400D01*
X814800Y754250D01*
X815850Y753250D01*
X816725Y751750D01*
X817425Y750000D01*
X817600Y747500D01*
X817425Y745000D01*
X816725Y743250D01*
X815850Y741750D01*
X814800Y740750D01*
X813400Y740000D01*
X809900D01*
G01X-340825Y770000D02*
X-336450Y785000D01*
X-332075Y770000D01*
G01X-333650Y775250D02*
X-339250D01*
G01X-326275Y770000D02*
Y785000D01*
X-318225Y770000D01*
Y785000D01*
G01X-311900Y770000D02*
Y785000D01*
X-308400D01*
X-307000Y784250D01*
X-305950Y783250D01*
X-305075Y781750D01*
X-304375Y780000D01*
X-304200Y777500D01*
X-304375Y775000D01*
X-305075Y773250D01*
X-305950Y771750D01*
X-307000Y770750D01*
X-308400Y770000D01*
X-311900D01*
G01X-283675D02*
Y785000D01*
X-275625Y770000D01*
Y785000D01*
G01X-265450Y770000D02*
X-266850Y770250D01*
X-268075Y771250D01*
X-269125Y772750D01*
X-269825Y774500D01*
X-270175Y776500D01*
Y778500D01*
X-269825Y780500D01*
X-269125Y782250D01*
X-268075Y783750D01*
X-266850Y784750D01*
X-265450Y785000D01*
X-264050Y784750D01*
X-262825Y783750D01*
X-261775Y782250D01*
X-261075Y780500D01*
X-260725Y778500D01*
Y776500D01*
X-261075Y774500D01*
X-261775Y772750D01*
X-262825Y771250D01*
X-264050Y770250D01*
X-265450Y770000D01*
G01X-241600D02*
Y785000D01*
X-237050Y772500D01*
X-232500Y785000D01*
Y770000D01*
G01X-222850D02*
X-224250Y770250D01*
X-225475Y771250D01*
X-226525Y772750D01*
X-227225Y774500D01*
X-227575Y776500D01*
Y778500D01*
X-227225Y780500D01*
X-226525Y782250D01*
X-225475Y783750D01*
X-224250Y784750D01*
X-222850Y785000D01*
X-221450Y784750D01*
X-220225Y783750D01*
X-219175Y782250D01*
X-218475Y780500D01*
X-218125Y778500D01*
Y776500D01*
X-218475Y774500D01*
X-219175Y772750D01*
X-220225Y771250D01*
X-221450Y770250D01*
X-222850Y770000D01*
G01X-212150D02*
Y785000D01*
X-207775D01*
X-206375Y784250D01*
X-205500Y783250D01*
X-205150Y781250D01*
X-205500Y779250D01*
X-206550Y778000D01*
X-207775Y777250D01*
X-212150D01*
G01X-207775D02*
X-205150Y770000D01*
G01X-190950D02*
X-197950D01*
Y785000D01*
X-190950D01*
G01X-193750Y777750D02*
X-197950D01*
G01X-166050Y785000D02*
Y770000D01*
G01X-170075Y785000D02*
X-162025D01*
G01X-155525Y770000D02*
Y785000D01*
G01X-148175D02*
Y770000D01*
G01Y777500D02*
X-155525D01*
G01X-142025Y770000D02*
X-137650Y785000D01*
X-133275Y770000D01*
G01X-134850Y775250D02*
X-140450D01*
G01X-127475Y770000D02*
Y785000D01*
X-119425Y770000D01*
Y785000D01*
G01X-98025Y771750D02*
X-96800Y770500D01*
X-95400Y770000D01*
X-94000Y770500D01*
X-92775Y772000D01*
X-91900Y774250D01*
X-91550Y776500D01*
Y779250D01*
X-91900Y781500D01*
X-92775Y783500D01*
X-93825Y784500D01*
X-95050Y785000D01*
X-96450Y784500D01*
X-97500Y783500D01*
X-98200Y782000D01*
X-98550Y780000D01*
X-98200Y778250D01*
X-97325Y776500D01*
X-96275Y775500D01*
X-95050Y775250D01*
X-93650Y775750D01*
X-92600Y777000D01*
X-91550Y779250D01*
G01X-80850Y785000D02*
X-82250Y784500D01*
X-83300Y783250D01*
X-84000Y781750D01*
X-84525Y779750D01*
X-84700Y777500D01*
X-84525Y775250D01*
X-84000Y773250D01*
X-83300Y771750D01*
X-82250Y770500D01*
X-80850Y770000D01*
X-79450Y770500D01*
X-78400Y771750D01*
X-77700Y773250D01*
X-77175Y775250D01*
X-77000Y777500D01*
X-77175Y779750D01*
X-77700Y781750D01*
X-78400Y783250D01*
X-79450Y784500D01*
X-80850Y785000D01*
G01X-69800Y769500D02*
X-63500Y785000D01*
G01X-69800D02*
X-70850Y784500D01*
X-71375Y783750D01*
X-71725Y782250D01*
X-71375Y780750D01*
X-70850Y780000D01*
X-69800Y779500D01*
X-68750Y780000D01*
X-68225Y780750D01*
X-67875Y782250D01*
X-68225Y783750D01*
X-68750Y784500D01*
X-69800Y785000D01*
G01X-63500Y775000D02*
X-64550Y774500D01*
X-65075Y773750D01*
X-65425Y772250D01*
X-65075Y770750D01*
X-64550Y770000D01*
X-63500Y769500D01*
X-62450Y770000D01*
X-61925Y770750D01*
X-61575Y772250D01*
X-61925Y773750D01*
X-62450Y774500D01*
X-63500Y775000D01*
G01X-38250Y770000D02*
X-39650Y770250D01*
X-40875Y771250D01*
X-41925Y772750D01*
X-42625Y774500D01*
X-42975Y776500D01*
Y778500D01*
X-42625Y780500D01*
X-41925Y782250D01*
X-40875Y783750D01*
X-39650Y784750D01*
X-38250Y785000D01*
X-36850Y784750D01*
X-35625Y783750D01*
X-34575Y782250D01*
X-33875Y780500D01*
X-33525Y778500D01*
Y776500D01*
X-33875Y774500D01*
X-34575Y772750D01*
X-35625Y771250D01*
X-36850Y770250D01*
X-38250Y770000D01*
G01X-27375D02*
Y785000D01*
X-20725D01*
G01X-23175Y777750D02*
X-27375D01*
G01X4350Y785000D02*
Y770000D01*
G01X325Y785000D02*
X8375D01*
G01X14875Y770000D02*
Y785000D01*
G01X22225D02*
Y770000D01*
G01Y777500D02*
X14875D01*
G01X36250Y770000D02*
X29250D01*
Y785000D01*
X36250D01*
G01X33450Y777750D02*
X29250D01*
G01X56775Y785000D02*
X61150Y770000D01*
X65525Y785000D01*
G01X73250D02*
X77450D01*
G01X75350D02*
Y770000D01*
G01X73250D02*
X77450D01*
G01X85175D02*
X89550Y785000D01*
X93925Y770000D01*
G01X92350Y775250D02*
X86750D01*
G01X114275Y770000D02*
Y785000D01*
G01X121625D02*
Y770000D01*
G01Y777500D02*
X114275D01*
G01X135650Y770000D02*
X128650D01*
Y785000D01*
X135650D01*
G01X132850Y777750D02*
X128650D01*
G01X144250Y785000D02*
X148450D01*
G01X146350D02*
Y770000D01*
G01X144250D02*
X148450D01*
G01X161600Y777500D02*
X165100D01*
Y773000D01*
X164050Y771500D01*
X162825Y770500D01*
X161075Y770000D01*
X159325Y770500D01*
X158100Y771500D01*
X157050Y773000D01*
X156350Y774750D01*
X156000Y776750D01*
Y778500D01*
X156350Y780000D01*
X157050Y781750D01*
X158100Y783250D01*
X159150Y784250D01*
X160550Y785000D01*
X161775D01*
X163175Y784500D01*
X164225Y783500D01*
G01X171075Y770000D02*
Y785000D01*
G01X178425D02*
Y770000D01*
G01Y777500D02*
X171075D01*
G01X188950Y785000D02*
Y770000D01*
G01X184925Y785000D02*
X192975D01*
G01X212800Y770000D02*
Y785000D01*
X217350Y772500D01*
X221900Y785000D01*
Y770000D01*
G01X235050D02*
X228050D01*
Y785000D01*
X235050D01*
G01X232250Y777750D02*
X228050D01*
G01X241375Y770000D02*
X245750Y785000D01*
X250125Y770000D01*
G01X248550Y775250D02*
X242950D01*
G01X256275Y772000D02*
X257675Y770750D01*
X259250Y770000D01*
X260650D01*
X262050Y770750D01*
X263100Y772000D01*
X263625Y773750D01*
X263275Y775500D01*
X262400Y777000D01*
X260825Y778000D01*
X258725Y778500D01*
X257500Y779500D01*
X256975Y781250D01*
X257325Y783000D01*
X258200Y784250D01*
X259425Y785000D01*
X260650D01*
X261875Y784500D01*
X262925Y783250D01*
G01X270300Y785000D02*
Y774250D01*
X271000Y772000D01*
X272400Y770500D01*
X274150Y770000D01*
X275900Y770500D01*
X277300Y772000D01*
X278000Y774250D01*
Y785000D01*
G01X284850Y770000D02*
Y785000D01*
X289225D01*
X290625Y784250D01*
X291500Y783250D01*
X291850Y781250D01*
X291500Y779250D01*
X290450Y778000D01*
X289225Y777250D01*
X284850D01*
G01X289225D02*
X291850Y770000D01*
G01X306050D02*
X299050D01*
Y785000D01*
X306050D01*
G01X303250Y777750D02*
X299050D01*
G01X312900Y770000D02*
Y785000D01*
X316400D01*
X317800Y784250D01*
X318850Y783250D01*
X319725Y781750D01*
X320425Y780000D01*
X320600Y777500D01*
X320425Y775000D01*
X319725Y773250D01*
X318850Y771750D01*
X317800Y770750D01*
X316400Y770000D01*
X312900D01*
G01X341825D02*
Y785000D01*
X348475D01*
G01X346025Y777750D02*
X341825D01*
G01X355850Y770000D02*
Y785000D01*
X360225D01*
X361625Y784250D01*
X362500Y783250D01*
X362850Y781250D01*
X362500Y779250D01*
X361450Y778000D01*
X360225Y777250D01*
X355850D01*
G01X360225D02*
X362850Y770000D01*
G01X373550D02*
X372150Y770250D01*
X370925Y771250D01*
X369875Y772750D01*
X369175Y774500D01*
X368825Y776500D01*
Y778500D01*
X369175Y780500D01*
X369875Y782250D01*
X370925Y783750D01*
X372150Y784750D01*
X373550Y785000D01*
X374950Y784750D01*
X376175Y783750D01*
X377225Y782250D01*
X377925Y780500D01*
X378275Y778500D01*
Y776500D01*
X377925Y774500D01*
X377225Y772750D01*
X376175Y771250D01*
X374950Y770250D01*
X373550Y770000D01*
G01X383200D02*
Y785000D01*
X387750Y772500D01*
X392300Y785000D01*
Y770000D01*
G01X416150Y785000D02*
Y770000D01*
G01X412125Y785000D02*
X420175D01*
G01X426675Y770000D02*
Y785000D01*
G01X434025D02*
Y770000D01*
G01Y777500D02*
X426675D01*
G01X448050Y770000D02*
X441050D01*
Y785000D01*
X448050D01*
G01X445250Y777750D02*
X441050D01*
G01X469275Y772000D02*
X470675Y770750D01*
X472250Y770000D01*
X473650D01*
X475050Y770750D01*
X476100Y772000D01*
X476625Y773750D01*
X476275Y775500D01*
X475400Y777000D01*
X473825Y778000D01*
X471725Y778500D01*
X470500Y779500D01*
X469975Y781250D01*
X470325Y783000D01*
X471200Y784250D01*
X472425Y785000D01*
X473650D01*
X474875Y784500D01*
X475925Y783250D01*
G01X485050Y785000D02*
X489250D01*
G01X487150D02*
Y770000D01*
G01X485050D02*
X489250D01*
G01X497500D02*
Y785000D01*
X501000D01*
X502400Y784250D01*
X503450Y783250D01*
X504325Y781750D01*
X505025Y780000D01*
X505200Y777500D01*
X505025Y775000D01*
X504325Y773250D01*
X503450Y771750D01*
X502400Y770750D01*
X501000Y770000D01*
X497500D01*
G01X519050D02*
X512050D01*
Y785000D01*
X519050D01*
G01X516250Y777750D02*
X512050D01*
G01X543950Y770000D02*
X542550Y770250D01*
X541325Y771250D01*
X540275Y772750D01*
X539575Y774500D01*
X539225Y776500D01*
Y778500D01*
X539575Y780500D01*
X540275Y782250D01*
X541325Y783750D01*
X542550Y784750D01*
X543950Y785000D01*
X545350Y784750D01*
X546575Y783750D01*
X547625Y782250D01*
X548325Y780500D01*
X548675Y778500D01*
Y776500D01*
X548325Y774500D01*
X547625Y772750D01*
X546575Y771250D01*
X545350Y770250D01*
X543950Y770000D01*
G01X554650D02*
Y785000D01*
X558850D01*
X560250Y784250D01*
X561300Y782500D01*
X561650Y780500D01*
X561300Y778500D01*
X560425Y777000D01*
X558850Y776250D01*
X554650D01*
G01X568850Y770000D02*
Y785000D01*
X573050D01*
X574450Y784250D01*
X575500Y782500D01*
X575850Y780500D01*
X575500Y778500D01*
X574625Y777000D01*
X573050Y776250D01*
X568850D01*
G01X586550Y770000D02*
X585150Y770250D01*
X583925Y771250D01*
X582875Y772750D01*
X582175Y774500D01*
X581825Y776500D01*
Y778500D01*
X582175Y780500D01*
X582875Y782250D01*
X583925Y783750D01*
X585150Y784750D01*
X586550Y785000D01*
X587950Y784750D01*
X589175Y783750D01*
X590225Y782250D01*
X590925Y780500D01*
X591275Y778500D01*
Y776500D01*
X590925Y774500D01*
X590225Y772750D01*
X589175Y771250D01*
X587950Y770250D01*
X586550Y770000D01*
G01X597075Y772000D02*
X598475Y770750D01*
X600050Y770000D01*
X601450D01*
X602850Y770750D01*
X603900Y772000D01*
X604425Y773750D01*
X604075Y775500D01*
X603200Y777000D01*
X601625Y778000D01*
X599525Y778500D01*
X598300Y779500D01*
X597775Y781250D01*
X598125Y783000D01*
X599000Y784250D01*
X600225Y785000D01*
X601450D01*
X602675Y784500D01*
X603725Y783250D01*
G01X612850Y785000D02*
X617050D01*
G01X614950D02*
Y770000D01*
G01X612850D02*
X617050D01*
G01X629150Y785000D02*
Y770000D01*
G01X625125Y785000D02*
X633175D01*
G01X646850Y770000D02*
X639850D01*
Y785000D01*
X646850D01*
G01X644050Y777750D02*
X639850D01*
G01X671750Y785000D02*
Y770000D01*
G01X667725Y785000D02*
X675775D01*
G01X685950Y770000D02*
X684550Y770250D01*
X683325Y771250D01*
X682275Y772750D01*
X681575Y774500D01*
X681225Y776500D01*
Y778500D01*
X681575Y780500D01*
X682275Y782250D01*
X683325Y783750D01*
X684550Y784750D01*
X685950Y785000D01*
X687350Y784750D01*
X688575Y783750D01*
X689625Y782250D01*
X690325Y780500D01*
X690675Y778500D01*
Y776500D01*
X690325Y774500D01*
X689625Y772750D01*
X688575Y771250D01*
X687350Y770250D01*
X685950Y770000D01*
G01X714350Y785000D02*
Y770000D01*
G01X710325Y785000D02*
X718375D01*
G01X724875Y770000D02*
Y785000D01*
G01X732225D02*
Y770000D01*
G01Y777500D02*
X724875D01*
G01X746250Y770000D02*
X739250D01*
Y785000D01*
X746250D01*
G01X743450Y777750D02*
X739250D01*
G01X771150Y785000D02*
Y770000D01*
G01X767125Y785000D02*
X775175D01*
G01X788850Y770000D02*
X781850D01*
Y785000D01*
X788850D01*
G01X786050Y777750D02*
X781850D01*
G01X795875Y772000D02*
X797275Y770750D01*
X798850Y770000D01*
X800250D01*
X801650Y770750D01*
X802700Y772000D01*
X803225Y773750D01*
X802875Y775500D01*
X802000Y777000D01*
X800425Y778000D01*
X798325Y778500D01*
X797100Y779500D01*
X796575Y781250D01*
X796925Y783000D01*
X797800Y784250D01*
X799025Y785000D01*
X800250D01*
X801475Y784500D01*
X802525Y783250D01*
G01X813750Y785000D02*
Y770000D01*
G01X809725Y785000D02*
X817775D01*
G01X-338550Y815000D02*
X-334350D01*
G01X-336450D02*
Y800000D01*
G01X-338550D02*
X-334350D01*
G01X-325925Y802000D02*
X-324525Y800750D01*
X-322950Y800000D01*
X-321550D01*
X-320150Y800750D01*
X-319100Y802000D01*
X-318575Y803750D01*
X-318925Y805500D01*
X-319800Y807000D01*
X-321375Y808000D01*
X-323475Y808500D01*
X-324700Y809500D01*
X-325225Y811250D01*
X-324875Y813000D01*
X-324000Y814250D01*
X-322775Y815000D01*
X-321550D01*
X-320325Y814500D01*
X-319275Y813250D01*
G01X-293850Y800000D02*
X-295250Y800250D01*
X-296475Y801250D01*
X-297525Y802750D01*
X-298225Y804500D01*
X-298575Y806500D01*
Y808500D01*
X-298225Y810500D01*
X-297525Y812250D01*
X-296475Y813750D01*
X-295250Y814750D01*
X-293850Y815000D01*
X-292450Y814750D01*
X-291225Y813750D01*
X-290175Y812250D01*
X-289475Y810500D01*
X-289125Y808500D01*
Y806500D01*
X-289475Y804500D01*
X-290175Y802750D01*
X-291225Y801250D01*
X-292450Y800250D01*
X-293850Y800000D01*
G01X-283150D02*
Y815000D01*
X-278950D01*
X-277550Y814250D01*
X-276500Y812500D01*
X-276150Y810500D01*
X-276500Y808500D01*
X-277375Y807000D01*
X-278950Y806250D01*
X-283150D01*
G01X-268950Y800000D02*
Y815000D01*
X-264750D01*
X-263350Y814250D01*
X-262300Y812500D01*
X-261950Y810500D01*
X-262300Y808500D01*
X-263175Y807000D01*
X-264750Y806250D01*
X-268950D01*
G01X-251250Y800000D02*
X-252650Y800250D01*
X-253875Y801250D01*
X-254925Y802750D01*
X-255625Y804500D01*
X-255975Y806500D01*
Y808500D01*
X-255625Y810500D01*
X-254925Y812250D01*
X-253875Y813750D01*
X-252650Y814750D01*
X-251250Y815000D01*
X-249850Y814750D01*
X-248625Y813750D01*
X-247575Y812250D01*
X-246875Y810500D01*
X-246525Y808500D01*
Y806500D01*
X-246875Y804500D01*
X-247575Y802750D01*
X-248625Y801250D01*
X-249850Y800250D01*
X-251250Y800000D01*
G01X-240725Y802000D02*
X-239325Y800750D01*
X-237750Y800000D01*
X-236350D01*
X-234950Y800750D01*
X-233900Y802000D01*
X-233375Y803750D01*
X-233725Y805500D01*
X-234600Y807000D01*
X-236175Y808000D01*
X-238275Y808500D01*
X-239500Y809500D01*
X-240025Y811250D01*
X-239675Y813000D01*
X-238800Y814250D01*
X-237575Y815000D01*
X-236350D01*
X-235125Y814500D01*
X-234075Y813250D01*
G01X-224950Y815000D02*
X-220750D01*
G01X-222850D02*
Y800000D01*
G01X-224950D02*
X-220750D01*
G01X-208650Y815000D02*
Y800000D01*
G01X-212675Y815000D02*
X-204625D01*
G01X-190950Y800000D02*
X-197950D01*
Y815000D01*
X-190950D01*
G01X-193750Y807750D02*
X-197950D01*
G01X-166050Y815000D02*
Y800000D01*
G01X-170075Y815000D02*
X-162025D01*
G01X-151850Y800000D02*
X-153250Y800250D01*
X-154475Y801250D01*
X-155525Y802750D01*
X-156225Y804500D01*
X-156575Y806500D01*
Y808500D01*
X-156225Y810500D01*
X-155525Y812250D01*
X-154475Y813750D01*
X-153250Y814750D01*
X-151850Y815000D01*
X-150450Y814750D01*
X-149225Y813750D01*
X-148175Y812250D01*
X-147475Y810500D01*
X-147125Y808500D01*
Y806500D01*
X-147475Y804500D01*
X-148175Y802750D01*
X-149225Y801250D01*
X-150450Y800250D01*
X-151850Y800000D01*
G01X-123450Y815000D02*
Y800000D01*
G01X-127475Y815000D02*
X-119425D01*
G01X-112925Y800000D02*
Y815000D01*
G01X-105575D02*
Y800000D01*
G01Y807500D02*
X-112925D01*
G01X-91550Y800000D02*
X-98550D01*
Y815000D01*
X-91550D01*
G01X-94350Y807750D02*
X-98550D01*
G01X-66650Y815000D02*
Y800000D01*
G01X-70675Y815000D02*
X-62625D01*
G01X-48950Y800000D02*
X-55950D01*
Y815000D01*
X-48950D01*
G01X-51750Y807750D02*
X-55950D01*
G01X-41925Y802000D02*
X-40525Y800750D01*
X-38950Y800000D01*
X-37550D01*
X-36150Y800750D01*
X-35100Y802000D01*
X-34575Y803750D01*
X-34925Y805500D01*
X-35800Y807000D01*
X-37375Y808000D01*
X-39475Y808500D01*
X-40700Y809500D01*
X-41225Y811250D01*
X-40875Y813000D01*
X-40000Y814250D01*
X-38775Y815000D01*
X-37550D01*
X-36325Y814500D01*
X-35275Y813250D01*
G01X-24050Y815000D02*
Y800000D01*
G01X-28075Y815000D02*
X-20025D01*
G01X850Y800000D02*
Y815000D01*
X5050D01*
X6450Y814250D01*
X7500Y812500D01*
X7850Y810500D01*
X7500Y808500D01*
X6625Y807000D01*
X5050Y806250D01*
X850D01*
G01X14175Y800000D02*
X18550Y815000D01*
X22925Y800000D01*
G01X21350Y805250D02*
X15750D01*
G01X28900Y800000D02*
Y815000D01*
X32400D01*
X33800Y814250D01*
X34850Y813250D01*
X35725Y811750D01*
X36425Y810000D01*
X36600Y807500D01*
X36425Y805000D01*
X35725Y803250D01*
X34850Y801750D01*
X33800Y800750D01*
X32400Y800000D01*
X28900D01*
G01X43275Y802000D02*
X44675Y800750D01*
X46250Y800000D01*
X47650D01*
X49050Y800750D01*
X50100Y802000D01*
X50625Y803750D01*
X50275Y805500D01*
X49400Y807000D01*
X47825Y808000D01*
X45725Y808500D01*
X44500Y809500D01*
X43975Y811250D01*
X44325Y813000D01*
X45200Y814250D01*
X46425Y815000D01*
X47650D01*
X48875Y814500D01*
X49925Y813250D01*
G01X61150Y799500D02*
X60800Y799750D01*
Y800250D01*
X61150Y800500D01*
X61500Y800250D01*
Y799750D01*
X61150Y799500D01*
G01X89550Y815000D02*
Y800000D01*
G01X85525Y815000D02*
X93575D01*
G01X100075Y800000D02*
Y815000D01*
G01X107425D02*
Y800000D01*
G01Y807500D02*
X100075D01*
G01X121450Y800000D02*
X114450D01*
Y815000D01*
X121450D01*
G01X118650Y807750D02*
X114450D01*
G01X142850Y800000D02*
Y815000D01*
X147050D01*
X148450Y814250D01*
X149500Y812500D01*
X149850Y810500D01*
X149500Y808500D01*
X148625Y807000D01*
X147050Y806250D01*
X142850D01*
G01X157050Y815000D02*
Y800000D01*
X164050D01*
G01X170900Y815000D02*
Y804250D01*
X171600Y802000D01*
X173000Y800500D01*
X174750Y800000D01*
X176500Y800500D01*
X177900Y802000D01*
X178600Y804250D01*
Y815000D01*
G01X190000Y807500D02*
X193500D01*
Y803000D01*
X192450Y801500D01*
X191225Y800500D01*
X189475Y800000D01*
X187725Y800500D01*
X186500Y801500D01*
X185450Y803000D01*
X184750Y804750D01*
X184400Y806750D01*
Y808500D01*
X184750Y810000D01*
X185450Y811750D01*
X186500Y813250D01*
X187550Y814250D01*
X188950Y815000D01*
X190175D01*
X191575Y814500D01*
X192625Y813500D01*
G01X204200Y807500D02*
X207700D01*
Y803000D01*
X206650Y801500D01*
X205425Y800500D01*
X203675Y800000D01*
X201925Y800500D01*
X200700Y801500D01*
X199650Y803000D01*
X198950Y804750D01*
X198600Y806750D01*
Y808500D01*
X198950Y810000D01*
X199650Y811750D01*
X200700Y813250D01*
X201750Y814250D01*
X203150Y815000D01*
X204375D01*
X205775Y814500D01*
X206825Y813500D01*
G01X220850Y800000D02*
X213850D01*
Y815000D01*
X220850D01*
G01X218050Y807750D02*
X213850D01*
G01X227700Y800000D02*
Y815000D01*
X231200D01*
X232600Y814250D01*
X233650Y813250D01*
X234525Y811750D01*
X235225Y810000D01*
X235400Y807500D01*
X235225Y805000D01*
X234525Y803250D01*
X233650Y801750D01*
X232600Y800750D01*
X231200Y800000D01*
X227700D01*
G01X255400D02*
Y815000D01*
X259950Y802500D01*
X264500Y815000D01*
Y800000D01*
G01X269775D02*
X274150Y815000D01*
X278525Y800000D01*
G01X276950Y805250D02*
X271350D01*
G01X288350Y815000D02*
Y800000D01*
G01X284325Y815000D02*
X292375D01*
G01X306050Y800000D02*
X299050D01*
Y815000D01*
X306050D01*
G01X303250Y807750D02*
X299050D01*
G01X313250Y800000D02*
Y815000D01*
X317625D01*
X319025Y814250D01*
X319900Y813250D01*
X320250Y811250D01*
X319900Y809250D01*
X318850Y808000D01*
X317625Y807250D01*
X313250D01*
G01X317625D02*
X320250Y800000D01*
G01X328850Y815000D02*
X333050D01*
G01X330950D02*
Y800000D01*
G01X328850D02*
X333050D01*
G01X340775D02*
X345150Y815000D01*
X349525Y800000D01*
G01X347950Y805250D02*
X342350D01*
G01X355850Y815000D02*
Y800000D01*
X362850D01*
G01X384075D02*
Y815000D01*
G01X391425D02*
Y800000D01*
G01Y807500D02*
X384075D01*
G01X397575Y800000D02*
X401950Y815000D01*
X406325Y800000D01*
G01X404750Y805250D02*
X399150D01*
G01X412475Y802000D02*
X413875Y800750D01*
X415450Y800000D01*
X416850D01*
X418250Y800750D01*
X419300Y802000D01*
X419825Y803750D01*
X419475Y805500D01*
X418600Y807000D01*
X417025Y808000D01*
X414925Y808500D01*
X413700Y809500D01*
X413175Y811250D01*
X413525Y813000D01*
X414400Y814250D01*
X415625Y815000D01*
X416850D01*
X418075Y814500D01*
X419125Y813250D01*
G01X444550Y815000D02*
Y800000D01*
G01X440525Y815000D02*
X448575D01*
G01X458750Y800000D02*
X457350Y800250D01*
X456125Y801250D01*
X455075Y802750D01*
X454375Y804500D01*
X454025Y806500D01*
Y808500D01*
X454375Y810500D01*
X455075Y812250D01*
X456125Y813750D01*
X457350Y814750D01*
X458750Y815000D01*
X460150Y814750D01*
X461375Y813750D01*
X462425Y812250D01*
X463125Y810500D01*
X463475Y808500D01*
Y806500D01*
X463125Y804500D01*
X462425Y802750D01*
X461375Y801250D01*
X460150Y800250D01*
X458750Y800000D01*
G01X488550Y808000D02*
X489250Y808750D01*
X489775Y810000D01*
X490125Y811750D01*
X489775Y813250D01*
X489075Y814250D01*
X487850Y815000D01*
X483125D01*
Y800000D01*
X488900D01*
X490125Y801000D01*
X490825Y802500D01*
X491175Y804250D01*
X490825Y806000D01*
X489775Y807500D01*
X488550Y808000D01*
X483125D01*
G01X504850Y800000D02*
X497850D01*
Y815000D01*
X504850D01*
G01X502050Y807750D02*
X497850D01*
G01X526425Y800000D02*
Y815000D01*
X533075D01*
G01X530625Y807750D02*
X526425D01*
G01X541850Y815000D02*
X546050D01*
G01X543950D02*
Y800000D01*
G01X541850D02*
X546050D01*
G01X554650Y815000D02*
Y800000D01*
X561650D01*
G01X568850Y815000D02*
Y800000D01*
X575850D01*
G01X590050D02*
X583050D01*
Y815000D01*
X590050D01*
G01X587250Y807750D02*
X583050D01*
G01X596900Y800000D02*
Y815000D01*
X600400D01*
X601800Y814250D01*
X602850Y813250D01*
X603725Y811750D01*
X604425Y810000D01*
X604600Y807500D01*
X604425Y805000D01*
X603725Y803250D01*
X602850Y801750D01*
X601800Y800750D01*
X600400Y800000D01*
X596900D01*
G01X624775D02*
X629150Y815000D01*
X633525Y800000D01*
G01X631950Y805250D02*
X626350D01*
G01X643350Y815000D02*
Y800000D01*
G01X639325Y815000D02*
X647375D01*
G01X668250D02*
Y800000D01*
X675250D01*
G01X689450D02*
X682450D01*
Y815000D01*
X689450D01*
G01X686650Y807750D02*
X682450D01*
G01X695775Y800000D02*
X700150Y815000D01*
X704525Y800000D01*
G01X702950Y805250D02*
X697350D01*
G01X710675Y802000D02*
X712075Y800750D01*
X713650Y800000D01*
X715050D01*
X716450Y800750D01*
X717500Y802000D01*
X718025Y803750D01*
X717675Y805500D01*
X716800Y807000D01*
X715225Y808000D01*
X713125Y808500D01*
X711900Y809500D01*
X711375Y811250D01*
X711725Y813000D01*
X712600Y814250D01*
X713825Y815000D01*
X715050D01*
X716275Y814500D01*
X717325Y813250D01*
G01X728550Y815000D02*
Y800000D01*
G01X724525Y815000D02*
X732575D01*
G01X759050Y800000D02*
Y815000D01*
X752575Y804250D01*
X761325D01*
G01X771150Y815000D02*
X769750Y814500D01*
X768700Y813250D01*
X768000Y811750D01*
X767475Y809750D01*
X767300Y807500D01*
X767475Y805250D01*
X768000Y803250D01*
X768700Y801750D01*
X769750Y800500D01*
X771150Y800000D01*
X772550Y800500D01*
X773600Y801750D01*
X774300Y803250D01*
X774825Y805250D01*
X775000Y807500D01*
X774825Y809750D01*
X774300Y811750D01*
X773600Y813250D01*
X772550Y814500D01*
X771150Y815000D01*
G01X782200Y799500D02*
X788500Y815000D01*
G01X782200D02*
X781150Y814500D01*
X780625Y813750D01*
X780275Y812250D01*
X780625Y810750D01*
X781150Y810000D01*
X782200Y809500D01*
X783250Y810000D01*
X783775Y810750D01*
X784125Y812250D01*
X783775Y813750D01*
X783250Y814500D01*
X782200Y815000D01*
G01X788500Y805000D02*
X787450Y804500D01*
X786925Y803750D01*
X786575Y802250D01*
X786925Y800750D01*
X787450Y800000D01*
X788500Y799500D01*
X789550Y800000D01*
X790075Y800750D01*
X790425Y802250D01*
X790075Y803750D01*
X789550Y804500D01*
X788500Y805000D01*
G01X-336450Y845000D02*
Y830000D01*
G01X-340475Y845000D02*
X-332425D01*
G01X-325925Y830000D02*
Y845000D01*
G01X-318575D02*
Y830000D01*
G01Y837500D02*
X-325925D01*
G01X-304550Y830000D02*
X-311550D01*
Y845000D01*
X-304550D01*
G01X-307350Y837750D02*
X-311550D01*
G01X-284025Y845000D02*
X-279650Y830000D01*
X-275275Y845000D01*
G01X-267550D02*
X-263350D01*
G01X-265450D02*
Y830000D01*
G01X-267550D02*
X-263350D01*
G01X-255625D02*
X-251250Y845000D01*
X-246875Y830000D01*
G01X-248450Y835250D02*
X-254050D01*
G01X-240725Y832000D02*
X-239325Y830750D01*
X-237750Y830000D01*
X-236350D01*
X-234950Y830750D01*
X-233900Y832000D01*
X-233375Y833750D01*
X-233725Y835500D01*
X-234600Y837000D01*
X-236175Y838000D01*
X-238275Y838500D01*
X-239500Y839500D01*
X-240025Y841250D01*
X-239675Y843000D01*
X-238800Y844250D01*
X-237575Y845000D01*
X-236350D01*
X-235125Y844500D01*
X-234075Y843250D01*
G01X-208650Y845000D02*
Y830000D01*
G01X-212675Y845000D02*
X-204625D01*
G01X-198125Y830000D02*
Y845000D01*
G01X-190775D02*
Y830000D01*
G01Y837500D02*
X-198125D01*
G01X-184625Y830000D02*
X-180250Y845000D01*
X-175875Y830000D01*
G01X-177450Y835250D02*
X-183050D01*
G01X-166050Y845000D02*
Y830000D01*
G01X-170075Y845000D02*
X-162025D01*
G01X-142025Y830000D02*
X-137650Y845000D01*
X-133275Y830000D01*
G01X-134850Y835250D02*
X-140450D01*
G01X-126950Y830000D02*
Y845000D01*
X-122575D01*
X-121175Y844250D01*
X-120300Y843250D01*
X-119950Y841250D01*
X-120300Y839250D01*
X-121350Y838000D01*
X-122575Y837250D01*
X-126950D01*
G01X-122575D02*
X-119950Y830000D01*
G01X-105750D02*
X-112750D01*
Y845000D01*
X-105750D01*
G01X-108550Y837750D02*
X-112750D01*
G01X-84700Y845000D02*
Y834250D01*
X-84000Y832000D01*
X-82600Y830500D01*
X-80850Y830000D01*
X-79100Y830500D01*
X-77700Y832000D01*
X-77000Y834250D01*
Y845000D01*
G01X-70325Y832000D02*
X-68925Y830750D01*
X-67350Y830000D01*
X-65950D01*
X-64550Y830750D01*
X-63500Y832000D01*
X-62975Y833750D01*
X-63325Y835500D01*
X-64200Y837000D01*
X-65775Y838000D01*
X-67875Y838500D01*
X-69100Y839500D01*
X-69625Y841250D01*
X-69275Y843000D01*
X-68400Y844250D01*
X-67175Y845000D01*
X-65950D01*
X-64725Y844500D01*
X-63675Y843250D01*
G01X-48950Y830000D02*
X-55950D01*
Y845000D01*
X-48950D01*
G01X-51750Y837750D02*
X-55950D01*
G01X-42100Y830000D02*
Y845000D01*
X-38600D01*
X-37200Y844250D01*
X-36150Y843250D01*
X-35275Y841750D01*
X-34575Y840000D01*
X-34400Y837500D01*
X-34575Y835000D01*
X-35275Y833250D01*
X-36150Y831750D01*
X-37200Y830750D01*
X-38600Y830000D01*
X-42100D01*
G01X-14225D02*
X-9850Y845000D01*
X-5475Y830000D01*
G01X-7050Y835250D02*
X-12650D01*
G01X675Y832000D02*
X2075Y830750D01*
X3650Y830000D01*
X5050D01*
X6450Y830750D01*
X7500Y832000D01*
X8025Y833750D01*
X7675Y835500D01*
X6800Y837000D01*
X5225Y838000D01*
X3125Y838500D01*
X1900Y839500D01*
X1375Y841250D01*
X1725Y843000D01*
X2600Y844250D01*
X3825Y845000D01*
X5050D01*
X6275Y844500D01*
X7325Y843250D01*
G01X32750Y845000D02*
Y830000D01*
G01X28725Y845000D02*
X36775D01*
G01X50450Y830000D02*
X43450D01*
Y845000D01*
X50450D01*
G01X47650Y837750D02*
X43450D01*
G01X57475Y832000D02*
X58875Y830750D01*
X60450Y830000D01*
X61850D01*
X63250Y830750D01*
X64300Y832000D01*
X64825Y833750D01*
X64475Y835500D01*
X63600Y837000D01*
X62025Y838000D01*
X59925Y838500D01*
X58700Y839500D01*
X58175Y841250D01*
X58525Y843000D01*
X59400Y844250D01*
X60625Y845000D01*
X61850D01*
X63075Y844500D01*
X64125Y843250D01*
G01X75350Y845000D02*
Y830000D01*
G01X71325Y845000D02*
X79375D01*
G01X100250Y830000D02*
Y845000D01*
X104450D01*
X105850Y844250D01*
X106900Y842500D01*
X107250Y840500D01*
X106900Y838500D01*
X106025Y837000D01*
X104450Y836250D01*
X100250D01*
G01X113575Y830000D02*
X117950Y845000D01*
X122325Y830000D01*
G01X120750Y835250D02*
X115150D01*
G01X128300Y830000D02*
Y845000D01*
X131800D01*
X133200Y844250D01*
X134250Y843250D01*
X135125Y841750D01*
X135825Y840000D01*
X136000Y837500D01*
X135825Y835000D01*
X135125Y833250D01*
X134250Y831750D01*
X133200Y830750D01*
X131800Y830000D01*
X128300D01*
G01X142675Y832000D02*
X144075Y830750D01*
X145650Y830000D01*
X147050D01*
X148450Y830750D01*
X149500Y832000D01*
X150025Y833750D01*
X149675Y835500D01*
X148800Y837000D01*
X147225Y838000D01*
X145125Y838500D01*
X143900Y839500D01*
X143375Y841250D01*
X143725Y843000D01*
X144600Y844250D01*
X145825Y845000D01*
X147050D01*
X148275Y844500D01*
X149325Y843250D01*
G01X170375Y830000D02*
X174750Y845000D01*
X179125Y830000D01*
G01X177550Y835250D02*
X171950D01*
G01X185450Y830000D02*
Y845000D01*
X189825D01*
X191225Y844250D01*
X192100Y843250D01*
X192450Y841250D01*
X192100Y839250D01*
X191050Y838000D01*
X189825Y837250D01*
X185450D01*
G01X189825D02*
X192450Y830000D01*
G01X206650D02*
X199650D01*
Y845000D01*
X206650D01*
G01X203850Y837750D02*
X199650D01*
G01X228050Y830000D02*
Y845000D01*
X232425D01*
X233825Y844250D01*
X234700Y843250D01*
X235050Y841250D01*
X234700Y839250D01*
X233650Y838000D01*
X232425Y837250D01*
X228050D01*
G01X232425D02*
X235050Y830000D01*
G01X249250D02*
X242250D01*
Y845000D01*
X249250D01*
G01X246450Y837750D02*
X242250D01*
G01X259950Y830000D02*
X258550Y830250D01*
X257325Y831250D01*
X256275Y832750D01*
X255575Y834500D01*
X255225Y836500D01*
Y838500D01*
X255575Y840500D01*
X256275Y842250D01*
X257325Y843750D01*
X258550Y844750D01*
X259950Y845000D01*
X261350Y844750D01*
X262575Y843750D01*
X263625Y842250D01*
X264325Y840500D01*
X264675Y838500D01*
Y836500D01*
X264325Y834500D01*
X263625Y832750D01*
X262575Y831250D01*
X261350Y830250D01*
X259950Y830000D01*
G01X261350Y834000D02*
X263450Y830000D01*
G01X270300Y845000D02*
Y834250D01*
X271000Y832000D01*
X272400Y830500D01*
X274150Y830000D01*
X275900Y830500D01*
X277300Y832000D01*
X278000Y834250D01*
Y845000D01*
G01X286250D02*
X290450D01*
G01X288350D02*
Y830000D01*
G01X286250D02*
X290450D01*
G01X299050D02*
Y845000D01*
X303425D01*
X304825Y844250D01*
X305700Y843250D01*
X306050Y841250D01*
X305700Y839250D01*
X304650Y838000D01*
X303425Y837250D01*
X299050D01*
G01X303425D02*
X306050Y830000D01*
G01X320250D02*
X313250D01*
Y845000D01*
X320250D01*
G01X317450Y837750D02*
X313250D01*
G01X327100Y830000D02*
Y845000D01*
X330600D01*
X332000Y844250D01*
X333050Y843250D01*
X333925Y841750D01*
X334625Y840000D01*
X334800Y837500D01*
X334625Y835000D01*
X333925Y833250D01*
X333050Y831750D01*
X332000Y830750D01*
X330600Y830000D01*
X327100D01*
G01X359350Y845000D02*
Y830000D01*
G01X355325Y845000D02*
X363375D01*
G01X373550Y830000D02*
X372150Y830250D01*
X370925Y831250D01*
X369875Y832750D01*
X369175Y834500D01*
X368825Y836500D01*
Y838500D01*
X369175Y840500D01*
X369875Y842250D01*
X370925Y843750D01*
X372150Y844750D01*
X373550Y845000D01*
X374950Y844750D01*
X376175Y843750D01*
X377225Y842250D01*
X377925Y840500D01*
X378275Y838500D01*
Y836500D01*
X377925Y834500D01*
X377225Y832750D01*
X376175Y831250D01*
X374950Y830250D01*
X373550Y830000D01*
G01X403350Y838000D02*
X404050Y838750D01*
X404575Y840000D01*
X404925Y841750D01*
X404575Y843250D01*
X403875Y844250D01*
X402650Y845000D01*
X397925D01*
Y830000D01*
X403700D01*
X404925Y831000D01*
X405625Y832500D01*
X405975Y834250D01*
X405625Y836000D01*
X404575Y837500D01*
X403350Y838000D01*
X397925D01*
G01X419650Y830000D02*
X412650D01*
Y845000D01*
X419650D01*
G01X416850Y837750D02*
X412650D01*
G01X441050Y830000D02*
Y845000D01*
X445250D01*
X446650Y844250D01*
X447700Y842500D01*
X448050Y840500D01*
X447700Y838500D01*
X446825Y837000D01*
X445250Y836250D01*
X441050D01*
G01X455250Y845000D02*
Y830000D01*
X462250D01*
G01X469100Y845000D02*
Y834250D01*
X469800Y832000D01*
X471200Y830500D01*
X472950Y830000D01*
X474700Y830500D01*
X476100Y832000D01*
X476800Y834250D01*
Y845000D01*
G01X488200Y837500D02*
X491700D01*
Y833000D01*
X490650Y831500D01*
X489425Y830500D01*
X487675Y830000D01*
X485925Y830500D01*
X484700Y831500D01*
X483650Y833000D01*
X482950Y834750D01*
X482600Y836750D01*
Y838500D01*
X482950Y840000D01*
X483650Y841750D01*
X484700Y843250D01*
X485750Y844250D01*
X487150Y845000D01*
X488375D01*
X489775Y844500D01*
X490825Y843500D01*
G01X502400Y837500D02*
X505900D01*
Y833000D01*
X504850Y831500D01*
X503625Y830500D01*
X501875Y830000D01*
X500125Y830500D01*
X498900Y831500D01*
X497850Y833000D01*
X497150Y834750D01*
X496800Y836750D01*
Y838500D01*
X497150Y840000D01*
X497850Y841750D01*
X498900Y843250D01*
X499950Y844250D01*
X501350Y845000D01*
X502575D01*
X503975Y844500D01*
X505025Y843500D01*
G01X519050Y830000D02*
X512050D01*
Y845000D01*
X519050D01*
G01X516250Y837750D02*
X512050D01*
G01X525900Y830000D02*
Y845000D01*
X529400D01*
X530800Y844250D01*
X531850Y843250D01*
X532725Y841750D01*
X533425Y840000D01*
X533600Y837500D01*
X533425Y835000D01*
X532725Y833250D01*
X531850Y831750D01*
X530800Y830750D01*
X529400Y830000D01*
X525900D01*
G01X558150D02*
X556750Y830250D01*
X555525Y831250D01*
X554475Y832750D01*
X553775Y834500D01*
X553425Y836500D01*
Y838500D01*
X553775Y840500D01*
X554475Y842250D01*
X555525Y843750D01*
X556750Y844750D01*
X558150Y845000D01*
X559550Y844750D01*
X560775Y843750D01*
X561825Y842250D01*
X562525Y840500D01*
X562875Y838500D01*
Y836500D01*
X562525Y834500D01*
X561825Y832750D01*
X560775Y831250D01*
X559550Y830250D01*
X558150Y830000D01*
G01X568325D02*
Y845000D01*
X576375Y830000D01*
Y845000D01*
G01X600750D02*
Y830000D01*
G01X596725Y845000D02*
X604775D01*
G01X611275Y830000D02*
Y845000D01*
G01X618625D02*
Y830000D01*
G01Y837500D02*
X611275D01*
G01X632650Y830000D02*
X625650D01*
Y845000D01*
X632650D01*
G01X629850Y837750D02*
X625650D01*
G01X653875Y832000D02*
X655275Y830750D01*
X656850Y830000D01*
X658250D01*
X659650Y830750D01*
X660700Y832000D01*
X661225Y833750D01*
X660875Y835500D01*
X660000Y837000D01*
X658425Y838000D01*
X656325Y838500D01*
X655100Y839500D01*
X654575Y841250D01*
X654925Y843000D01*
X655800Y844250D01*
X657025Y845000D01*
X658250D01*
X659475Y844500D01*
X660525Y843250D01*
G01X669650Y845000D02*
X673850D01*
G01X671750D02*
Y830000D01*
G01X669650D02*
X673850D01*
G01X682100D02*
Y845000D01*
X685600D01*
X687000Y844250D01*
X688050Y843250D01*
X688925Y841750D01*
X689625Y840000D01*
X689800Y837500D01*
X689625Y835000D01*
X688925Y833250D01*
X688050Y831750D01*
X687000Y830750D01*
X685600Y830000D01*
X682100D01*
G01X703650D02*
X696650D01*
Y845000D01*
X703650D01*
G01X700850Y837750D02*
X696650D01*
G01X728550Y845000D02*
Y830000D01*
G01X724525Y845000D02*
X732575D01*
G01X739075Y830000D02*
Y845000D01*
G01X746425D02*
Y830000D01*
G01Y837500D02*
X739075D01*
G01X752575Y830000D02*
X756950Y845000D01*
X761325Y830000D01*
G01X759750Y835250D02*
X754150D01*
G01X771150Y845000D02*
Y830000D01*
G01X767125Y845000D02*
X775175D01*
G01X-396575Y872500D02*
X-395525Y874000D01*
X-394300Y874750D01*
X-392900Y875000D01*
X-391150Y874500D01*
X-389925Y873250D01*
X-389575Y871750D01*
X-389750Y870250D01*
X-390450Y869000D01*
X-393950Y866500D01*
X-395525Y864750D01*
X-396575Y862250D01*
X-396925Y860000D01*
X-389575D01*
G01X-376950D02*
Y875000D01*
X-383425Y864250D01*
X-374675D01*
G01X-364850Y859500D02*
X-365200Y859750D01*
Y860250D01*
X-364850Y860500D01*
X-364500Y860250D01*
Y859750D01*
X-364850Y859500D01*
G01X-340825Y875000D02*
X-336450Y860000D01*
X-332075Y875000D01*
G01X-324350D02*
X-320150D01*
G01X-322250D02*
Y860000D01*
G01X-324350D02*
X-320150D01*
G01X-312425D02*
X-308050Y875000D01*
X-303675Y860000D01*
G01X-305250Y865250D02*
X-310850D01*
G01X-283150Y860000D02*
Y875000D01*
X-278950D01*
X-277550Y874250D01*
X-276500Y872500D01*
X-276150Y870500D01*
X-276500Y868500D01*
X-277375Y867000D01*
X-278950Y866250D01*
X-283150D01*
G01X-268950Y875000D02*
Y860000D01*
X-261950D01*
G01X-255100Y875000D02*
Y864250D01*
X-254400Y862000D01*
X-253000Y860500D01*
X-251250Y860000D01*
X-249500Y860500D01*
X-248100Y862000D01*
X-247400Y864250D01*
Y875000D01*
G01X-236000Y867500D02*
X-232500D01*
Y863000D01*
X-233550Y861500D01*
X-234775Y860500D01*
X-236525Y860000D01*
X-238275Y860500D01*
X-239500Y861500D01*
X-240550Y863000D01*
X-241250Y864750D01*
X-241600Y866750D01*
Y868500D01*
X-241250Y870000D01*
X-240550Y871750D01*
X-239500Y873250D01*
X-238450Y874250D01*
X-237050Y875000D01*
X-235825D01*
X-234425Y874500D01*
X-233375Y873500D01*
G01X-221800Y867500D02*
X-218300D01*
Y863000D01*
X-219350Y861500D01*
X-220575Y860500D01*
X-222325Y860000D01*
X-224075Y860500D01*
X-225300Y861500D01*
X-226350Y863000D01*
X-227050Y864750D01*
X-227400Y866750D01*
Y868500D01*
X-227050Y870000D01*
X-226350Y871750D01*
X-225300Y873250D01*
X-224250Y874250D01*
X-222850Y875000D01*
X-221625D01*
X-220225Y874500D01*
X-219175Y873500D01*
G01X-210750Y875000D02*
X-206550D01*
G01X-208650D02*
Y860000D01*
G01X-210750D02*
X-206550D01*
G01X-198475D02*
Y875000D01*
X-190425Y860000D01*
Y875000D01*
G01X-179200Y867500D02*
X-175700D01*
Y863000D01*
X-176750Y861500D01*
X-177975Y860500D01*
X-179725Y860000D01*
X-181475Y860500D01*
X-182700Y861500D01*
X-183750Y863000D01*
X-184450Y864750D01*
X-184800Y866750D01*
Y868500D01*
X-184450Y870000D01*
X-183750Y871750D01*
X-182700Y873250D01*
X-181650Y874250D01*
X-180250Y875000D01*
X-179025D01*
X-177625Y874500D01*
X-176575Y873500D01*
G01X-155350Y860000D02*
Y875000D01*
X-150975D01*
X-149575Y874250D01*
X-148700Y873250D01*
X-148350Y871250D01*
X-148700Y869250D01*
X-149750Y868000D01*
X-150975Y867250D01*
X-155350D01*
G01X-150975D02*
X-148350Y860000D01*
G01X-134150D02*
X-141150D01*
Y875000D01*
X-134150D01*
G01X-136950Y867750D02*
X-141150D01*
G01X-123450Y860000D02*
X-124850Y860250D01*
X-126075Y861250D01*
X-127125Y862750D01*
X-127825Y864500D01*
X-128175Y866500D01*
Y868500D01*
X-127825Y870500D01*
X-127125Y872250D01*
X-126075Y873750D01*
X-124850Y874750D01*
X-123450Y875000D01*
X-122050Y874750D01*
X-120825Y873750D01*
X-119775Y872250D01*
X-119075Y870500D01*
X-118725Y868500D01*
Y866500D01*
X-119075Y864500D01*
X-119775Y862750D01*
X-120825Y861250D01*
X-122050Y860250D01*
X-123450Y860000D01*
G01X-122050Y864000D02*
X-119950Y860000D01*
G01X-113100Y875000D02*
Y864250D01*
X-112400Y862000D01*
X-111000Y860500D01*
X-109250Y860000D01*
X-107500Y860500D01*
X-106100Y862000D01*
X-105400Y864250D01*
Y875000D01*
G01X-97150D02*
X-92950D01*
G01X-95050D02*
Y860000D01*
G01X-97150D02*
X-92950D01*
G01X-84350D02*
Y875000D01*
X-79975D01*
X-78575Y874250D01*
X-77700Y873250D01*
X-77350Y871250D01*
X-77700Y869250D01*
X-78750Y868000D01*
X-79975Y867250D01*
X-84350D01*
G01X-79975D02*
X-77350Y860000D01*
G01X-63150D02*
X-70150D01*
Y875000D01*
X-63150D01*
G01X-65950Y867750D02*
X-70150D01*
G01X-57000Y860000D02*
Y875000D01*
X-52450Y862500D01*
X-47900Y875000D01*
Y860000D01*
G01X-34750D02*
X-41750D01*
Y875000D01*
X-34750D01*
G01X-37550Y867750D02*
X-41750D01*
G01X-28075Y860000D02*
Y875000D01*
X-20025Y860000D01*
Y875000D01*
G01X-9850D02*
Y860000D01*
G01X-13875Y875000D02*
X-5825D01*
G01X675Y862000D02*
X2075Y860750D01*
X3650Y860000D01*
X5050D01*
X6450Y860750D01*
X7500Y862000D01*
X8025Y863750D01*
X7675Y865500D01*
X6800Y867000D01*
X5225Y868000D01*
X3125Y868500D01*
X1900Y869500D01*
X1375Y871250D01*
X1725Y873000D01*
X2600Y874250D01*
X3825Y875000D01*
X5050D01*
X6275Y874500D01*
X7325Y873250D01*
G01X29425Y860000D02*
Y875000D01*
X36075D01*
G01X33625Y867750D02*
X29425D01*
G01X46950Y860000D02*
X45550Y860250D01*
X44325Y861250D01*
X43275Y862750D01*
X42575Y864500D01*
X42225Y866500D01*
Y868500D01*
X42575Y870500D01*
X43275Y872250D01*
X44325Y873750D01*
X45550Y874750D01*
X46950Y875000D01*
X48350Y874750D01*
X49575Y873750D01*
X50625Y872250D01*
X51325Y870500D01*
X51675Y868500D01*
Y866500D01*
X51325Y864500D01*
X50625Y862750D01*
X49575Y861250D01*
X48350Y860250D01*
X46950Y860000D01*
G01X57650D02*
Y875000D01*
X62025D01*
X63425Y874250D01*
X64300Y873250D01*
X64650Y871250D01*
X64300Y869250D01*
X63250Y868000D01*
X62025Y867250D01*
X57650D01*
G01X62025D02*
X64650Y860000D01*
G01X89550Y875000D02*
Y860000D01*
G01X85525Y875000D02*
X93575D01*
G01X107250Y860000D02*
X100250D01*
Y875000D01*
X107250D01*
G01X104450Y867750D02*
X100250D01*
G01X114275Y862000D02*
X115675Y860750D01*
X117250Y860000D01*
X118650D01*
X120050Y860750D01*
X121100Y862000D01*
X121625Y863750D01*
X121275Y865500D01*
X120400Y867000D01*
X118825Y868000D01*
X116725Y868500D01*
X115500Y869500D01*
X114975Y871250D01*
X115325Y873000D01*
X116200Y874250D01*
X117425Y875000D01*
X118650D01*
X119875Y874500D01*
X120925Y873250D01*
G01X132150Y875000D02*
Y860000D01*
G01X128125Y875000D02*
X136175D01*
G01X157050Y860000D02*
Y875000D01*
X161250D01*
X162650Y874250D01*
X163700Y872500D01*
X164050Y870500D01*
X163700Y868500D01*
X162825Y867000D01*
X161250Y866250D01*
X157050D01*
G01X170375Y860000D02*
X174750Y875000D01*
X179125Y860000D01*
G01X177550Y865250D02*
X171950D01*
G01X185100Y860000D02*
Y875000D01*
X188600D01*
X190000Y874250D01*
X191050Y873250D01*
X191925Y871750D01*
X192625Y870000D01*
X192800Y867500D01*
X192625Y865000D01*
X191925Y863250D01*
X191050Y861750D01*
X190000Y860750D01*
X188600Y860000D01*
X185100D01*
G01X212975Y875000D02*
X217350Y860000D01*
X221725Y875000D01*
G01X229450D02*
X233650D01*
G01X231550D02*
Y860000D01*
G01X229450D02*
X233650D01*
G01X241375D02*
X245750Y875000D01*
X250125Y860000D01*
G01X248550Y865250D02*
X242950D01*
G01X259950Y859500D02*
X259600Y859750D01*
Y860250D01*
X259950Y860500D01*
X260300Y860250D01*
Y859750D01*
X259950Y859500D01*
G01Y866250D02*
X259600Y866500D01*
Y867000D01*
X259950Y867250D01*
X260300Y867000D01*
Y866500D01*
X259950Y866250D01*
G01X-394125Y890000D02*
X-395875Y892500D01*
X-396750Y895000D01*
Y905000D01*
X-395875Y907500D01*
X-394125Y910000D01*
G01X-382900D02*
Y899250D01*
X-382200Y897000D01*
X-380800Y895500D01*
X-379050Y895000D01*
X-377300Y895500D01*
X-375900Y897000D01*
X-375200Y899250D01*
Y910000D01*
G01X-368525Y897000D02*
X-367125Y895750D01*
X-365550Y895000D01*
X-364150D01*
X-362750Y895750D01*
X-361700Y897000D01*
X-361175Y898750D01*
X-361525Y900500D01*
X-362400Y902000D01*
X-363975Y903000D01*
X-366075Y903500D01*
X-367300Y904500D01*
X-367825Y906250D01*
X-367475Y908000D01*
X-366600Y909250D01*
X-365375Y910000D01*
X-364150D01*
X-362925Y909500D01*
X-361875Y908250D01*
G01X-347150Y895000D02*
X-354150D01*
Y910000D01*
X-347150D01*
G01X-349950Y902750D02*
X-354150D01*
G01X-325575Y895000D02*
Y910000D01*
X-318925D01*
G01X-321375Y902750D02*
X-325575D01*
G01X-308050Y895000D02*
X-309450Y895250D01*
X-310675Y896250D01*
X-311725Y897750D01*
X-312425Y899500D01*
X-312775Y901500D01*
Y903500D01*
X-312425Y905500D01*
X-311725Y907250D01*
X-310675Y908750D01*
X-309450Y909750D01*
X-308050Y910000D01*
X-306650Y909750D01*
X-305425Y908750D01*
X-304375Y907250D01*
X-303675Y905500D01*
X-303325Y903500D01*
Y901500D01*
X-303675Y899500D01*
X-304375Y897750D01*
X-305425Y896250D01*
X-306650Y895250D01*
X-308050Y895000D01*
G01X-297350D02*
Y910000D01*
X-292975D01*
X-291575Y909250D01*
X-290700Y908250D01*
X-290350Y906250D01*
X-290700Y904250D01*
X-291750Y903000D01*
X-292975Y902250D01*
X-297350D01*
G01X-292975D02*
X-290350Y895000D01*
G01X-265450D02*
X-266850Y895250D01*
X-268075Y896250D01*
X-269125Y897750D01*
X-269825Y899500D01*
X-270175Y901500D01*
Y903500D01*
X-269825Y905500D01*
X-269125Y907250D01*
X-268075Y908750D01*
X-266850Y909750D01*
X-265450Y910000D01*
X-264050Y909750D01*
X-262825Y908750D01*
X-261775Y907250D01*
X-261075Y905500D01*
X-260725Y903500D01*
Y901500D01*
X-261075Y899500D01*
X-261775Y897750D01*
X-262825Y896250D01*
X-264050Y895250D01*
X-265450Y895000D01*
G01X-254925Y897000D02*
X-253525Y895750D01*
X-251950Y895000D01*
X-250550D01*
X-249150Y895750D01*
X-248100Y897000D01*
X-247575Y898750D01*
X-247925Y900500D01*
X-248800Y902000D01*
X-250375Y903000D01*
X-252475Y903500D01*
X-253700Y904500D01*
X-254225Y906250D01*
X-253875Y908000D01*
X-253000Y909250D01*
X-251775Y910000D01*
X-250550D01*
X-249325Y909500D01*
X-248275Y908250D01*
G01X-240550Y895000D02*
Y910000D01*
X-236350D01*
X-234950Y909250D01*
X-233900Y907500D01*
X-233550Y905500D01*
X-233900Y903500D01*
X-234775Y902000D01*
X-236350Y901250D01*
X-240550D01*
G01X-208650Y895000D02*
X-210050Y895250D01*
X-211275Y896250D01*
X-212325Y897750D01*
X-213025Y899500D01*
X-213375Y901500D01*
Y903500D01*
X-213025Y905500D01*
X-212325Y907250D01*
X-211275Y908750D01*
X-210050Y909750D01*
X-208650Y910000D01*
X-207250Y909750D01*
X-206025Y908750D01*
X-204975Y907250D01*
X-204275Y905500D01*
X-203925Y903500D01*
Y901500D01*
X-204275Y899500D01*
X-204975Y897750D01*
X-206025Y896250D01*
X-207250Y895250D01*
X-208650Y895000D01*
G01X-198475D02*
Y910000D01*
X-190425Y895000D01*
Y910000D01*
G01X-183750D02*
Y895000D01*
X-176750D01*
G01X-166050D02*
Y901750D01*
X-169550Y910000D01*
G01X-162550D02*
X-166050Y901750D01*
G01X-150975Y890000D02*
X-149225Y892500D01*
X-148350Y895000D01*
Y905000D01*
X-149225Y907500D01*
X-150975Y910000D01*
G01X-340475Y930000D02*
Y945000D01*
X-332425Y930000D01*
Y945000D01*
G01X-322250Y930000D02*
X-323650Y930250D01*
X-324875Y931250D01*
X-325925Y932750D01*
X-326625Y934500D01*
X-326975Y936500D01*
Y938500D01*
X-326625Y940500D01*
X-325925Y942250D01*
X-324875Y943750D01*
X-323650Y944750D01*
X-322250Y945000D01*
X-320850Y944750D01*
X-319625Y943750D01*
X-318575Y942250D01*
X-317875Y940500D01*
X-317525Y938500D01*
Y936500D01*
X-317875Y934500D01*
X-318575Y932750D01*
X-319625Y931250D01*
X-320850Y930250D01*
X-322250Y930000D01*
G01X-290000Y943750D02*
X-291050Y944500D01*
X-292275Y945000D01*
X-293675D01*
X-295250Y944250D01*
X-296475Y943000D01*
X-297350Y941500D01*
X-298050Y939000D01*
X-298225Y936750D01*
X-297875Y934500D01*
X-297350Y933000D01*
X-296300Y931500D01*
X-295075Y930500D01*
X-293850Y930000D01*
X-292625D01*
X-291400Y930500D01*
X-290350Y931250D01*
X-289475Y932250D01*
G01X-283325Y930000D02*
Y945000D01*
G01X-275975D02*
Y930000D01*
G01Y937500D02*
X-283325D01*
G01X-269825Y930000D02*
X-265450Y945000D01*
X-261075Y930000D01*
G01X-262650Y935250D02*
X-268250D01*
G01X-255275Y930000D02*
Y945000D01*
X-247225Y930000D01*
Y945000D01*
G01X-236000Y937500D02*
X-232500D01*
Y933000D01*
X-233550Y931500D01*
X-234775Y930500D01*
X-236525Y930000D01*
X-238275Y930500D01*
X-239500Y931500D01*
X-240550Y933000D01*
X-241250Y934750D01*
X-241600Y936750D01*
Y938500D01*
X-241250Y940000D01*
X-240550Y941750D01*
X-239500Y943250D01*
X-238450Y944250D01*
X-237050Y945000D01*
X-235825D01*
X-234425Y944500D01*
X-233375Y943500D01*
G01X-219350Y930000D02*
X-226350D01*
Y945000D01*
X-219350D01*
G01X-222150Y937750D02*
X-226350D01*
G01X-198825Y930000D02*
X-194450Y945000D01*
X-190075Y930000D01*
G01X-191650Y935250D02*
X-197250D01*
G01X-183750Y945000D02*
Y930000D01*
X-176750D01*
G01X-169550Y945000D02*
Y930000D01*
X-162550D01*
G01X-151850D02*
X-153250Y930250D01*
X-154475Y931250D01*
X-155525Y932750D01*
X-156225Y934500D01*
X-156575Y936500D01*
Y938500D01*
X-156225Y940500D01*
X-155525Y942250D01*
X-154475Y943750D01*
X-153250Y944750D01*
X-151850Y945000D01*
X-150450Y944750D01*
X-149225Y943750D01*
X-148175Y942250D01*
X-147475Y940500D01*
X-147125Y938500D01*
Y936500D01*
X-147475Y934500D01*
X-148175Y932750D01*
X-149225Y931250D01*
X-150450Y930250D01*
X-151850Y930000D01*
G01X-142900Y945000D02*
X-140450Y930000D01*
X-137650Y945000D01*
X-134850Y930000D01*
X-132400Y945000D01*
G01X-119950Y930000D02*
X-126950D01*
Y945000D01*
X-119950D01*
G01X-122750Y937750D02*
X-126950D01*
G01X-113100Y930000D02*
Y945000D01*
X-109600D01*
X-108200Y944250D01*
X-107150Y943250D01*
X-106275Y941750D01*
X-105575Y940000D01*
X-105400Y937500D01*
X-105575Y935000D01*
X-106275Y933250D01*
X-107150Y931750D01*
X-108200Y930750D01*
X-109600Y930000D01*
X-113100D01*
G01X-86100Y945000D02*
X-83650Y930000D01*
X-80850Y945000D01*
X-78050Y930000D01*
X-75600Y945000D01*
G01X-68750D02*
X-64550D01*
G01X-66650D02*
Y930000D01*
G01X-68750D02*
X-64550D01*
G01X-52450Y945000D02*
Y930000D01*
G01X-56475Y945000D02*
X-48425D01*
G01X-41925Y930000D02*
Y945000D01*
G01X-34575D02*
Y930000D01*
G01Y937500D02*
X-41925D01*
G01X-24050Y930000D02*
X-25450Y930250D01*
X-26675Y931250D01*
X-27725Y932750D01*
X-28425Y934500D01*
X-28775Y936500D01*
Y938500D01*
X-28425Y940500D01*
X-27725Y942250D01*
X-26675Y943750D01*
X-25450Y944750D01*
X-24050Y945000D01*
X-22650Y944750D01*
X-21425Y943750D01*
X-20375Y942250D01*
X-19675Y940500D01*
X-19325Y938500D01*
Y936500D01*
X-19675Y934500D01*
X-20375Y932750D01*
X-21425Y931250D01*
X-22650Y930250D01*
X-24050Y930000D01*
G01X-13700Y945000D02*
Y934250D01*
X-13000Y932000D01*
X-11600Y930500D01*
X-9850Y930000D01*
X-8100Y930500D01*
X-6700Y932000D01*
X-6000Y934250D01*
Y945000D01*
G01X4350D02*
Y930000D01*
G01X325Y945000D02*
X8375D01*
G01X28200Y930000D02*
Y945000D01*
X32750Y932500D01*
X37300Y945000D01*
Y930000D01*
G01X44850Y945000D02*
X49050D01*
G01X46950D02*
Y930000D01*
G01X44850D02*
X49050D01*
G01X65000Y943750D02*
X63950Y944500D01*
X62725Y945000D01*
X61325D01*
X59750Y944250D01*
X58525Y943000D01*
X57650Y941500D01*
X56950Y939000D01*
X56775Y936750D01*
X57125Y934500D01*
X57650Y933000D01*
X58700Y931500D01*
X59925Y930500D01*
X61150Y930000D01*
X62375D01*
X63600Y930500D01*
X64650Y931250D01*
X65525Y932250D01*
G01X71850Y930000D02*
Y945000D01*
X76225D01*
X77625Y944250D01*
X78500Y943250D01*
X78850Y941250D01*
X78500Y939250D01*
X77450Y938000D01*
X76225Y937250D01*
X71850D01*
G01X76225D02*
X78850Y930000D01*
G01X89550D02*
X88150Y930250D01*
X86925Y931250D01*
X85875Y932750D01*
X85175Y934500D01*
X84825Y936500D01*
Y938500D01*
X85175Y940500D01*
X85875Y942250D01*
X86925Y943750D01*
X88150Y944750D01*
X89550Y945000D01*
X90950Y944750D01*
X92175Y943750D01*
X93225Y942250D01*
X93925Y940500D01*
X94275Y938500D01*
Y936500D01*
X93925Y934500D01*
X93225Y932750D01*
X92175Y931250D01*
X90950Y930250D01*
X89550Y930000D01*
G01X100075Y932000D02*
X101475Y930750D01*
X103050Y930000D01*
X104450D01*
X105850Y930750D01*
X106900Y932000D01*
X107425Y933750D01*
X107075Y935500D01*
X106200Y937000D01*
X104625Y938000D01*
X102525Y938500D01*
X101300Y939500D01*
X100775Y941250D01*
X101125Y943000D01*
X102000Y944250D01*
X103225Y945000D01*
X104450D01*
X105675Y944500D01*
X106725Y943250D01*
G01X117950Y930000D02*
X116550Y930250D01*
X115325Y931250D01*
X114275Y932750D01*
X113575Y934500D01*
X113225Y936500D01*
Y938500D01*
X113575Y940500D01*
X114275Y942250D01*
X115325Y943750D01*
X116550Y944750D01*
X117950Y945000D01*
X119350Y944750D01*
X120575Y943750D01*
X121625Y942250D01*
X122325Y940500D01*
X122675Y938500D01*
Y936500D01*
X122325Y934500D01*
X121625Y932750D01*
X120575Y931250D01*
X119350Y930250D01*
X117950Y930000D01*
G01X128825D02*
Y945000D01*
X135475D01*
G01X133025Y937750D02*
X128825D01*
G01X146350Y945000D02*
Y930000D01*
G01X142325Y945000D02*
X150375D01*
G01X170375Y930000D02*
X174750Y945000D01*
X179125Y930000D01*
G01X177550Y935250D02*
X171950D01*
G01X185450Y930000D02*
Y945000D01*
X189650D01*
X191050Y944250D01*
X192100Y942500D01*
X192450Y940500D01*
X192100Y938500D01*
X191225Y937000D01*
X189650Y936250D01*
X185450D01*
G01X199650Y930000D02*
Y945000D01*
X203850D01*
X205250Y944250D01*
X206300Y942500D01*
X206650Y940500D01*
X206300Y938500D01*
X205425Y937000D01*
X203850Y936250D01*
X199650D01*
G01X213850Y930000D02*
Y945000D01*
X218225D01*
X219625Y944250D01*
X220500Y943250D01*
X220850Y941250D01*
X220500Y939250D01*
X219450Y938000D01*
X218225Y937250D01*
X213850D01*
G01X218225D02*
X220850Y930000D01*
G01X231550D02*
X230150Y930250D01*
X228925Y931250D01*
X227875Y932750D01*
X227175Y934500D01*
X226825Y936500D01*
Y938500D01*
X227175Y940500D01*
X227875Y942250D01*
X228925Y943750D01*
X230150Y944750D01*
X231550Y945000D01*
X232950Y944750D01*
X234175Y943750D01*
X235225Y942250D01*
X235925Y940500D01*
X236275Y938500D01*
Y936500D01*
X235925Y934500D01*
X235225Y932750D01*
X234175Y931250D01*
X232950Y930250D01*
X231550Y930000D01*
G01X241375Y945000D02*
X245750Y930000D01*
X250125Y945000D01*
G01X255575Y930000D02*
X259950Y945000D01*
X264325Y930000D01*
G01X262750Y935250D02*
X257150D01*
G01X270650Y945000D02*
Y930000D01*
X277650D01*
G01X288350Y929500D02*
X288000Y929750D01*
Y930250D01*
X288350Y930500D01*
X288700Y930250D01*
Y929750D01*
X288350Y929500D01*
G01X-336450Y959500D02*
X-336800Y959750D01*
Y960250D01*
X-336450Y960500D01*
X-336100Y960250D01*
Y959750D01*
X-336450Y959500D01*
G01X-322250Y975000D02*
X-323650Y974500D01*
X-324700Y973250D01*
X-325400Y971750D01*
X-325925Y969750D01*
X-326100Y967500D01*
X-325925Y965250D01*
X-325400Y963250D01*
X-324700Y961750D01*
X-323650Y960500D01*
X-322250Y960000D01*
X-320850Y960500D01*
X-319800Y961750D01*
X-319100Y963250D01*
X-318575Y965250D01*
X-318400Y967500D01*
X-318575Y969750D01*
X-319100Y971750D01*
X-319800Y973250D01*
X-320850Y974500D01*
X-322250Y975000D01*
G01X-308050D02*
X-309450Y974500D01*
X-310500Y973250D01*
X-311200Y971750D01*
X-311725Y969750D01*
X-311900Y967500D01*
X-311725Y965250D01*
X-311200Y963250D01*
X-310500Y961750D01*
X-309450Y960500D01*
X-308050Y960000D01*
X-306650Y960500D01*
X-305600Y961750D01*
X-304900Y963250D01*
X-304375Y965250D01*
X-304200Y967500D01*
X-304375Y969750D01*
X-304900Y971750D01*
X-305600Y973250D01*
X-306650Y974500D01*
X-308050Y975000D01*
G01X-297175Y972500D02*
X-296125Y974000D01*
X-294900Y974750D01*
X-293500Y975000D01*
X-291750Y974500D01*
X-290525Y973250D01*
X-290175Y971750D01*
X-290350Y970250D01*
X-291050Y969000D01*
X-294550Y966500D01*
X-296125Y964750D01*
X-297175Y962250D01*
X-297525Y960000D01*
X-290175D01*
G01X-281225Y971750D02*
X-280350Y975000D01*
G01X-278075D02*
X-278950Y971750D01*
G01X-251250Y960000D02*
X-252650Y960250D01*
X-253875Y961250D01*
X-254925Y962750D01*
X-255625Y964500D01*
X-255975Y966500D01*
Y968500D01*
X-255625Y970500D01*
X-254925Y972250D01*
X-253875Y973750D01*
X-252650Y974750D01*
X-251250Y975000D01*
X-249850Y974750D01*
X-248625Y973750D01*
X-247575Y972250D01*
X-246875Y970500D01*
X-246525Y968500D01*
Y966500D01*
X-246875Y964500D01*
X-247575Y962750D01*
X-248625Y961250D01*
X-249850Y960250D01*
X-251250Y960000D01*
G01X-241425Y975000D02*
X-237050Y960000D01*
X-232675Y975000D01*
G01X-219350Y960000D02*
X-226350D01*
Y975000D01*
X-219350D01*
G01X-222150Y967750D02*
X-226350D01*
G01X-212150Y960000D02*
Y975000D01*
X-207775D01*
X-206375Y974250D01*
X-205500Y973250D01*
X-205150Y971250D01*
X-205500Y969250D01*
X-206550Y968000D01*
X-207775Y967250D01*
X-212150D01*
G01X-207775D02*
X-205150Y960000D01*
G01X-198125Y962000D02*
X-196725Y960750D01*
X-195150Y960000D01*
X-193750D01*
X-192350Y960750D01*
X-191300Y962000D01*
X-190775Y963750D01*
X-191125Y965500D01*
X-192000Y967000D01*
X-193575Y968000D01*
X-195675Y968500D01*
X-196900Y969500D01*
X-197425Y971250D01*
X-197075Y973000D01*
X-196200Y974250D01*
X-194975Y975000D01*
X-193750D01*
X-192525Y974500D01*
X-191475Y973250D01*
G01X-182350Y975000D02*
X-178150D01*
G01X-180250D02*
Y960000D01*
G01X-182350D02*
X-178150D01*
G01X-169375Y975000D02*
X-162725D01*
X-169375Y960000D01*
X-162725D01*
G01X-148350D02*
X-155350D01*
Y975000D01*
X-148350D01*
G01X-151150Y967750D02*
X-155350D01*
G01X-126950Y960000D02*
Y975000D01*
X-122750D01*
X-121350Y974250D01*
X-120300Y972500D01*
X-119950Y970500D01*
X-120300Y968500D01*
X-121175Y967000D01*
X-122750Y966250D01*
X-126950D01*
G01X-105750Y960000D02*
X-112750D01*
Y975000D01*
X-105750D01*
G01X-108550Y967750D02*
X-112750D01*
G01X-98550Y960000D02*
Y975000D01*
X-94175D01*
X-92775Y974250D01*
X-91900Y973250D01*
X-91550Y971250D01*
X-91900Y969250D01*
X-92950Y968000D01*
X-94175Y967250D01*
X-98550D01*
G01X-94175D02*
X-91550Y960000D01*
G01X-70325Y962000D02*
X-68925Y960750D01*
X-67350Y960000D01*
X-65950D01*
X-64550Y960750D01*
X-63500Y962000D01*
X-62975Y963750D01*
X-63325Y965500D01*
X-64200Y967000D01*
X-65775Y968000D01*
X-67875Y968500D01*
X-69100Y969500D01*
X-69625Y971250D01*
X-69275Y973000D01*
X-68400Y974250D01*
X-67175Y975000D01*
X-65950D01*
X-64725Y974500D01*
X-63675Y973250D01*
G01X-54550Y975000D02*
X-50350D01*
G01X-52450D02*
Y960000D01*
G01X-54550D02*
X-50350D01*
G01X-42100D02*
Y975000D01*
X-38600D01*
X-37200Y974250D01*
X-36150Y973250D01*
X-35275Y971750D01*
X-34575Y970000D01*
X-34400Y967500D01*
X-34575Y965000D01*
X-35275Y963250D01*
X-36150Y961750D01*
X-37200Y960750D01*
X-38600Y960000D01*
X-42100D01*
G01X-20550D02*
X-27550D01*
Y975000D01*
X-20550D01*
G01X-23350Y967750D02*
X-27550D01*
G01X-900Y975000D02*
X1550Y960000D01*
X4350Y975000D01*
X7150Y960000D01*
X9600Y975000D01*
G01X16450D02*
X20650D01*
G01X18550D02*
Y960000D01*
G01X16450D02*
X20650D01*
G01X32750Y975000D02*
Y960000D01*
G01X28725Y975000D02*
X36775D01*
G01X43275Y960000D02*
Y975000D01*
G01X50625D02*
Y960000D01*
G01Y967500D02*
X43275D01*
G01X61150Y960000D02*
X59750Y960250D01*
X58525Y961250D01*
X57475Y962750D01*
X56775Y964500D01*
X56425Y966500D01*
Y968500D01*
X56775Y970500D01*
X57475Y972250D01*
X58525Y973750D01*
X59750Y974750D01*
X61150Y975000D01*
X62550Y974750D01*
X63775Y973750D01*
X64825Y972250D01*
X65525Y970500D01*
X65875Y968500D01*
Y966500D01*
X65525Y964500D01*
X64825Y962750D01*
X63775Y961250D01*
X62550Y960250D01*
X61150Y960000D01*
G01X71500Y975000D02*
Y964250D01*
X72200Y962000D01*
X73600Y960500D01*
X75350Y960000D01*
X77100Y960500D01*
X78500Y962000D01*
X79200Y964250D01*
Y975000D01*
G01X89550D02*
Y960000D01*
G01X85525Y975000D02*
X93575D01*
G01X121450Y960000D02*
X114450D01*
Y975000D01*
X121450D01*
G01X118650Y967750D02*
X114450D01*
G01X128475Y960000D02*
X135825Y975000D01*
G01X128475D02*
X135825Y960000D01*
G01X150200Y973750D02*
X149150Y974500D01*
X147925Y975000D01*
X146525D01*
X144950Y974250D01*
X143725Y973000D01*
X142850Y971500D01*
X142150Y969000D01*
X141975Y966750D01*
X142325Y964500D01*
X142850Y963000D01*
X143900Y961500D01*
X145125Y960500D01*
X146350Y960000D01*
X147575D01*
X148800Y960500D01*
X149850Y961250D01*
X150725Y962250D01*
G01X164050Y960000D02*
X157050D01*
Y975000D01*
X164050D01*
G01X161250Y967750D02*
X157050D01*
G01X171250Y960000D02*
Y975000D01*
X175450D01*
X176850Y974250D01*
X177900Y972500D01*
X178250Y970500D01*
X177900Y968500D01*
X177025Y967000D01*
X175450Y966250D01*
X171250D01*
G01X188950Y975000D02*
Y960000D01*
G01X184925Y975000D02*
X192975D01*
G01X201050D02*
X205250D01*
G01X203150D02*
Y960000D01*
G01X201050D02*
X205250D01*
G01X217350D02*
X215950Y960250D01*
X214725Y961250D01*
X213675Y962750D01*
X212975Y964500D01*
X212625Y966500D01*
Y968500D01*
X212975Y970500D01*
X213675Y972250D01*
X214725Y973750D01*
X215950Y974750D01*
X217350Y975000D01*
X218750Y974750D01*
X219975Y973750D01*
X221025Y972250D01*
X221725Y970500D01*
X222075Y968500D01*
Y966500D01*
X221725Y964500D01*
X221025Y962750D01*
X219975Y961250D01*
X218750Y960250D01*
X217350Y960000D01*
G01X227525D02*
Y975000D01*
X235575Y960000D01*
Y975000D01*
G01X245750Y959500D02*
X245400Y959750D01*
Y960250D01*
X245750Y960500D01*
X246100Y960250D01*
Y959750D01*
X245750Y959500D01*
G01X-338550Y1005000D02*
X-334350D01*
G01X-336450D02*
Y990000D01*
G01X-338550D02*
X-334350D01*
G01X-326275D02*
Y1005000D01*
X-318225Y990000D01*
Y1005000D01*
G01X-304200Y1003750D02*
X-305250Y1004500D01*
X-306475Y1005000D01*
X-307875D01*
X-309450Y1004250D01*
X-310675Y1003000D01*
X-311550Y1001500D01*
X-312250Y999000D01*
X-312425Y996750D01*
X-312075Y994500D01*
X-311550Y993000D01*
X-310500Y991500D01*
X-309275Y990500D01*
X-308050Y990000D01*
X-306825D01*
X-305600Y990500D01*
X-304550Y991250D01*
X-303675Y992250D01*
G01X-297350Y1005000D02*
Y990000D01*
X-290350D01*
G01X-283500Y1005000D02*
Y994250D01*
X-282800Y992000D01*
X-281400Y990500D01*
X-279650Y990000D01*
X-277900Y990500D01*
X-276500Y992000D01*
X-275800Y994250D01*
Y1005000D01*
G01X-269300Y990000D02*
Y1005000D01*
X-265800D01*
X-264400Y1004250D01*
X-263350Y1003250D01*
X-262475Y1001750D01*
X-261775Y1000000D01*
X-261600Y997500D01*
X-261775Y995000D01*
X-262475Y993250D01*
X-263350Y991750D01*
X-264400Y990750D01*
X-265800Y990000D01*
X-269300D01*
G01X-253350Y1005000D02*
X-249150D01*
G01X-251250D02*
Y990000D01*
G01X-253350D02*
X-249150D01*
G01X-241075D02*
Y1005000D01*
X-233025Y990000D01*
Y1005000D01*
G01X-221800Y997500D02*
X-218300D01*
Y993000D01*
X-219350Y991500D01*
X-220575Y990500D01*
X-222325Y990000D01*
X-224075Y990500D01*
X-225300Y991500D01*
X-226350Y993000D01*
X-227050Y994750D01*
X-227400Y996750D01*
Y998500D01*
X-227050Y1000000D01*
X-226350Y1001750D01*
X-225300Y1003250D01*
X-224250Y1004250D01*
X-222850Y1005000D01*
X-221625D01*
X-220225Y1004500D01*
X-219175Y1003500D01*
G01X-198125Y992000D02*
X-196725Y990750D01*
X-195150Y990000D01*
X-193750D01*
X-192350Y990750D01*
X-191300Y992000D01*
X-190775Y993750D01*
X-191125Y995500D01*
X-192000Y997000D01*
X-193575Y998000D01*
X-195675Y998500D01*
X-196900Y999500D01*
X-197425Y1001250D01*
X-197075Y1003000D01*
X-196200Y1004250D01*
X-194975Y1005000D01*
X-193750D01*
X-192525Y1004500D01*
X-191475Y1003250D01*
G01X-180250Y990000D02*
X-181650Y990250D01*
X-182875Y991250D01*
X-183925Y992750D01*
X-184625Y994500D01*
X-184975Y996500D01*
Y998500D01*
X-184625Y1000500D01*
X-183925Y1002250D01*
X-182875Y1003750D01*
X-181650Y1004750D01*
X-180250Y1005000D01*
X-178850Y1004750D01*
X-177625Y1003750D01*
X-176575Y1002250D01*
X-175875Y1000500D01*
X-175525Y998500D01*
Y996500D01*
X-175875Y994500D01*
X-176575Y992750D01*
X-177625Y991250D01*
X-178850Y990250D01*
X-180250Y990000D01*
G01X-169550Y1005000D02*
Y990000D01*
X-162550D01*
G01X-155700D02*
Y1005000D01*
X-152200D01*
X-150800Y1004250D01*
X-149750Y1003250D01*
X-148875Y1001750D01*
X-148175Y1000000D01*
X-148000Y997500D01*
X-148175Y995000D01*
X-148875Y993250D01*
X-149750Y991750D01*
X-150800Y990750D01*
X-152200Y990000D01*
X-155700D01*
G01X-134150D02*
X-141150D01*
Y1005000D01*
X-134150D01*
G01X-136950Y997750D02*
X-141150D01*
G01X-126950Y990000D02*
Y1005000D01*
X-122575D01*
X-121175Y1004250D01*
X-120300Y1003250D01*
X-119950Y1001250D01*
X-120300Y999250D01*
X-121350Y998000D01*
X-122575Y997250D01*
X-126950D01*
G01X-122575D02*
X-119950Y990000D01*
G01X-113800D02*
Y1005000D01*
X-109250Y992500D01*
X-104700Y1005000D01*
Y990000D01*
G01X-99425D02*
X-95050Y1005000D01*
X-90675Y990000D01*
G01X-92250Y995250D02*
X-97850D01*
G01X-84525Y992000D02*
X-83125Y990750D01*
X-81550Y990000D01*
X-80150D01*
X-78750Y990750D01*
X-77700Y992000D01*
X-77175Y993750D01*
X-77525Y995500D01*
X-78400Y997000D01*
X-79975Y998000D01*
X-82075Y998500D01*
X-83300Y999500D01*
X-83825Y1001250D01*
X-83475Y1003000D01*
X-82600Y1004250D01*
X-81375Y1005000D01*
X-80150D01*
X-78925Y1004500D01*
X-77875Y1003250D01*
G01X-70500Y990000D02*
Y1005000D01*
G01X-63850D02*
X-70500Y995750D01*
G01X-62800Y990000D02*
X-67525Y1000000D01*
G01X-42100Y990000D02*
Y1005000D01*
X-38600D01*
X-37200Y1004250D01*
X-36150Y1003250D01*
X-35275Y1001750D01*
X-34575Y1000000D01*
X-34400Y997500D01*
X-34575Y995000D01*
X-35275Y993250D01*
X-36150Y991750D01*
X-37200Y990750D01*
X-38600Y990000D01*
X-42100D01*
G01X-20550D02*
X-27550D01*
Y1005000D01*
X-20550D01*
G01X-23350Y997750D02*
X-27550D01*
G01X-13175Y990000D02*
Y1005000D01*
X-6525D01*
G01X-8975Y997750D02*
X-13175D01*
G01X2250Y1005000D02*
X6450D01*
G01X4350D02*
Y990000D01*
G01X2250D02*
X6450D01*
G01X14525D02*
Y1005000D01*
X22575Y990000D01*
Y1005000D01*
G01X36250Y990000D02*
X29250D01*
Y1005000D01*
X36250D01*
G01X33450Y997750D02*
X29250D01*
G01X43100Y990000D02*
Y1005000D01*
X46600D01*
X48000Y1004250D01*
X49050Y1003250D01*
X49925Y1001750D01*
X50625Y1000000D01*
X50800Y997500D01*
X50625Y995000D01*
X49925Y993250D01*
X49050Y991750D01*
X48000Y990750D01*
X46600Y990000D01*
X43100D01*
G01X71850D02*
Y1005000D01*
X76050D01*
X77450Y1004250D01*
X78500Y1002500D01*
X78850Y1000500D01*
X78500Y998500D01*
X77625Y997000D01*
X76050Y996250D01*
X71850D01*
G01X85175Y990000D02*
X89550Y1005000D01*
X93925Y990000D01*
G01X92350Y995250D02*
X86750D01*
G01X99900Y990000D02*
Y1005000D01*
X103400D01*
X104800Y1004250D01*
X105850Y1003250D01*
X106725Y1001750D01*
X107425Y1000000D01*
X107600Y997500D01*
X107425Y995000D01*
X106725Y993250D01*
X105850Y991750D01*
X104800Y990750D01*
X103400Y990000D01*
X99900D01*
G01X114275Y992000D02*
X115675Y990750D01*
X117250Y990000D01*
X118650D01*
X120050Y990750D01*
X121100Y992000D01*
X121625Y993750D01*
X121275Y995500D01*
X120400Y997000D01*
X118825Y998000D01*
X116725Y998500D01*
X115500Y999500D01*
X114975Y1001250D01*
X115325Y1003000D01*
X116200Y1004250D01*
X117425Y1005000D01*
X118650D01*
X119875Y1004500D01*
X120925Y1003250D01*
G01X132150Y989500D02*
X131800Y989750D01*
Y990250D01*
X132150Y990500D01*
X132500Y990250D01*
Y989750D01*
X132150Y989500D01*
G01X156875Y992000D02*
X158275Y990750D01*
X159850Y990000D01*
X161250D01*
X162650Y990750D01*
X163700Y992000D01*
X164225Y993750D01*
X163875Y995500D01*
X163000Y997000D01*
X161425Y998000D01*
X159325Y998500D01*
X158100Y999500D01*
X157575Y1001250D01*
X157925Y1003000D01*
X158800Y1004250D01*
X160025Y1005000D01*
X161250D01*
X162475Y1004500D01*
X163525Y1003250D01*
G01X174750Y990000D02*
X173350Y990250D01*
X172125Y991250D01*
X171075Y992750D01*
X170375Y994500D01*
X170025Y996500D01*
Y998500D01*
X170375Y1000500D01*
X171075Y1002250D01*
X172125Y1003750D01*
X173350Y1004750D01*
X174750Y1005000D01*
X176150Y1004750D01*
X177375Y1003750D01*
X178425Y1002250D01*
X179125Y1000500D01*
X179475Y998500D01*
Y996500D01*
X179125Y994500D01*
X178425Y992750D01*
X177375Y991250D01*
X176150Y990250D01*
X174750Y990000D01*
G01X185450Y1005000D02*
Y990000D01*
X192450D01*
G01X199300D02*
Y1005000D01*
X202800D01*
X204200Y1004250D01*
X205250Y1003250D01*
X206125Y1001750D01*
X206825Y1000000D01*
X207000Y997500D01*
X206825Y995000D01*
X206125Y993250D01*
X205250Y991750D01*
X204200Y990750D01*
X202800Y990000D01*
X199300D01*
G01X220850D02*
X213850D01*
Y1005000D01*
X220850D01*
G01X218050Y997750D02*
X213850D01*
G01X228050Y990000D02*
Y1005000D01*
X232425D01*
X233825Y1004250D01*
X234700Y1003250D01*
X235050Y1001250D01*
X234700Y999250D01*
X233650Y998000D01*
X232425Y997250D01*
X228050D01*
G01X232425D02*
X235050Y990000D01*
G01X241200D02*
Y1005000D01*
X245750Y992500D01*
X250300Y1005000D01*
Y990000D01*
G01X255575D02*
X259950Y1005000D01*
X264325Y990000D01*
G01X262750Y995250D02*
X257150D01*
G01X270475Y992000D02*
X271875Y990750D01*
X273450Y990000D01*
X274850D01*
X276250Y990750D01*
X277300Y992000D01*
X277825Y993750D01*
X277475Y995500D01*
X276600Y997000D01*
X275025Y998000D01*
X272925Y998500D01*
X271700Y999500D01*
X271175Y1001250D01*
X271525Y1003000D01*
X272400Y1004250D01*
X273625Y1005000D01*
X274850D01*
X276075Y1004500D01*
X277125Y1003250D01*
G01X284500Y990000D02*
Y1005000D01*
G01X291150D02*
X284500Y995750D01*
G01X292200Y990000D02*
X287475Y1000000D01*
G01X312900Y990000D02*
Y1005000D01*
X316400D01*
X317800Y1004250D01*
X318850Y1003250D01*
X319725Y1001750D01*
X320425Y1000000D01*
X320600Y997500D01*
X320425Y995000D01*
X319725Y993250D01*
X318850Y991750D01*
X317800Y990750D01*
X316400Y990000D01*
X312900D01*
G01X334450D02*
X327450D01*
Y1005000D01*
X334450D01*
G01X331650Y997750D02*
X327450D01*
G01X341825Y990000D02*
Y1005000D01*
X348475D01*
G01X346025Y997750D02*
X341825D01*
G01X357250Y1005000D02*
X361450D01*
G01X359350D02*
Y990000D01*
G01X357250D02*
X361450D01*
G01X369525D02*
Y1005000D01*
X377575Y990000D01*
Y1005000D01*
G01X391250Y990000D02*
X384250D01*
Y1005000D01*
X391250D01*
G01X388450Y997750D02*
X384250D01*
G01X398100Y990000D02*
Y1005000D01*
X401600D01*
X403000Y1004250D01*
X404050Y1003250D01*
X404925Y1001750D01*
X405625Y1000000D01*
X405800Y997500D01*
X405625Y995000D01*
X404925Y993250D01*
X404050Y991750D01*
X403000Y990750D01*
X401600Y990000D01*
X398100D01*
G01X426850D02*
Y1005000D01*
X431050D01*
X432450Y1004250D01*
X433500Y1002500D01*
X433850Y1000500D01*
X433500Y998500D01*
X432625Y997000D01*
X431050Y996250D01*
X426850D01*
G01X440175Y990000D02*
X444550Y1005000D01*
X448925Y990000D01*
G01X447350Y995250D02*
X441750D01*
G01X454900Y990000D02*
Y1005000D01*
X458400D01*
X459800Y1004250D01*
X460850Y1003250D01*
X461725Y1001750D01*
X462425Y1000000D01*
X462600Y997500D01*
X462425Y995000D01*
X461725Y993250D01*
X460850Y991750D01*
X459800Y990750D01*
X458400Y990000D01*
X454900D01*
G01X469275Y992000D02*
X470675Y990750D01*
X472250Y990000D01*
X473650D01*
X475050Y990750D01*
X476100Y992000D01*
X476625Y993750D01*
X476275Y995500D01*
X475400Y997000D01*
X473825Y998000D01*
X471725Y998500D01*
X470500Y999500D01*
X469975Y1001250D01*
X470325Y1003000D01*
X471200Y1004250D01*
X472425Y1005000D01*
X473650D01*
X474875Y1004500D01*
X475925Y1003250D01*
G01X497675Y992000D02*
X499075Y990750D01*
X500650Y990000D01*
X502050D01*
X503450Y990750D01*
X504500Y992000D01*
X505025Y993750D01*
X504675Y995500D01*
X503800Y997000D01*
X502225Y998000D01*
X500125Y998500D01*
X498900Y999500D01*
X498375Y1001250D01*
X498725Y1003000D01*
X499600Y1004250D01*
X500825Y1005000D01*
X502050D01*
X503275Y1004500D01*
X504325Y1003250D01*
G01X511875Y990000D02*
Y1005000D01*
G01X519225D02*
Y990000D01*
G01Y997500D02*
X511875D01*
G01X525375Y990000D02*
X529750Y1005000D01*
X534125Y990000D01*
G01X532550Y995250D02*
X526950D01*
G01X540450Y1005000D02*
Y990000D01*
X547450D01*
G01X554650Y1005000D02*
Y990000D01*
X561650D01*
G01X582875Y992000D02*
X584275Y990750D01*
X585850Y990000D01*
X587250D01*
X588650Y990750D01*
X589700Y992000D01*
X590225Y993750D01*
X589875Y995500D01*
X589000Y997000D01*
X587425Y998000D01*
X585325Y998500D01*
X584100Y999500D01*
X583575Y1001250D01*
X583925Y1003000D01*
X584800Y1004250D01*
X586025Y1005000D01*
X587250D01*
X588475Y1004500D01*
X589525Y1003250D01*
G01X600750Y1005000D02*
Y990000D01*
G01X596725Y1005000D02*
X604775D01*
G01X611450Y990000D02*
Y1005000D01*
X615825D01*
X617225Y1004250D01*
X618100Y1003250D01*
X618450Y1001250D01*
X618100Y999250D01*
X617050Y998000D01*
X615825Y997250D01*
X611450D01*
G01X615825D02*
X618450Y990000D01*
G01X627050Y1005000D02*
X631250D01*
G01X629150D02*
Y990000D01*
G01X627050D02*
X631250D01*
G01X647200Y1003750D02*
X646150Y1004500D01*
X644925Y1005000D01*
X643525D01*
X641950Y1004250D01*
X640725Y1003000D01*
X639850Y1001500D01*
X639150Y999000D01*
X638975Y996750D01*
X639325Y994500D01*
X639850Y993000D01*
X640900Y991500D01*
X642125Y990500D01*
X643350Y990000D01*
X644575D01*
X645800Y990500D01*
X646850Y991250D01*
X647725Y992250D01*
G01X657550Y1005000D02*
Y990000D01*
G01X653525Y1005000D02*
X661575D01*
G01X668250D02*
Y990000D01*
X675250D01*
G01X685950D02*
Y996750D01*
X682450Y1005000D01*
G01X689450D02*
X685950Y996750D01*
G01X711025Y990000D02*
Y1005000D01*
X717675D01*
G01X715225Y997750D02*
X711025D01*
G01X728550Y990000D02*
X727150Y990250D01*
X725925Y991250D01*
X724875Y992750D01*
X724175Y994500D01*
X723825Y996500D01*
Y998500D01*
X724175Y1000500D01*
X724875Y1002250D01*
X725925Y1003750D01*
X727150Y1004750D01*
X728550Y1005000D01*
X729950Y1004750D01*
X731175Y1003750D01*
X732225Y1002250D01*
X732925Y1000500D01*
X733275Y998500D01*
Y996500D01*
X732925Y994500D01*
X732225Y992750D01*
X731175Y991250D01*
X729950Y990250D01*
X728550Y990000D01*
G01X739250Y1005000D02*
Y990000D01*
X746250D01*
G01X753450Y1005000D02*
Y990000D01*
X760450D01*
G01X771150D02*
X769750Y990250D01*
X768525Y991250D01*
X767475Y992750D01*
X766775Y994500D01*
X766425Y996500D01*
Y998500D01*
X766775Y1000500D01*
X767475Y1002250D01*
X768525Y1003750D01*
X769750Y1004750D01*
X771150Y1005000D01*
X772550Y1004750D01*
X773775Y1003750D01*
X774825Y1002250D01*
X775525Y1000500D01*
X775875Y998500D01*
Y996500D01*
X775525Y994500D01*
X774825Y992750D01*
X773775Y991250D01*
X772550Y990250D01*
X771150Y990000D01*
G01X780100Y1005000D02*
X782550Y990000D01*
X785350Y1005000D01*
X788150Y990000D01*
X790600Y1005000D01*
G01X-340125Y1022000D02*
X-338725Y1020750D01*
X-337150Y1020000D01*
X-335750D01*
X-334350Y1020750D01*
X-333300Y1022000D01*
X-332775Y1023750D01*
X-333125Y1025500D01*
X-334000Y1027000D01*
X-335575Y1028000D01*
X-337675Y1028500D01*
X-338900Y1029500D01*
X-339425Y1031250D01*
X-339075Y1033000D01*
X-338200Y1034250D01*
X-336975Y1035000D01*
X-335750D01*
X-334525Y1034500D01*
X-333475Y1033250D01*
G01X-322250Y1020000D02*
X-323650Y1020250D01*
X-324875Y1021250D01*
X-325925Y1022750D01*
X-326625Y1024500D01*
X-326975Y1026500D01*
Y1028500D01*
X-326625Y1030500D01*
X-325925Y1032250D01*
X-324875Y1033750D01*
X-323650Y1034750D01*
X-322250Y1035000D01*
X-320850Y1034750D01*
X-319625Y1033750D01*
X-318575Y1032250D01*
X-317875Y1030500D01*
X-317525Y1028500D01*
Y1026500D01*
X-317875Y1024500D01*
X-318575Y1022750D01*
X-319625Y1021250D01*
X-320850Y1020250D01*
X-322250Y1020000D01*
G01X-311550Y1035000D02*
Y1020000D01*
X-304550D01*
G01X-297700D02*
Y1035000D01*
X-294200D01*
X-292800Y1034250D01*
X-291750Y1033250D01*
X-290875Y1031750D01*
X-290175Y1030000D01*
X-290000Y1027500D01*
X-290175Y1025000D01*
X-290875Y1023250D01*
X-291750Y1021750D01*
X-292800Y1020750D01*
X-294200Y1020000D01*
X-297700D01*
G01X-276150D02*
X-283150D01*
Y1035000D01*
X-276150D01*
G01X-278950Y1027750D02*
X-283150D01*
G01X-268950Y1020000D02*
Y1035000D01*
X-264575D01*
X-263175Y1034250D01*
X-262300Y1033250D01*
X-261950Y1031250D01*
X-262300Y1029250D01*
X-263350Y1028000D01*
X-264575Y1027250D01*
X-268950D01*
G01X-264575D02*
X-261950Y1020000D01*
G01X-255800D02*
Y1035000D01*
X-251250Y1022500D01*
X-246700Y1035000D01*
Y1020000D01*
G01X-241425D02*
X-237050Y1035000D01*
X-232675Y1020000D01*
G01X-234250Y1025250D02*
X-239850D01*
G01X-226525Y1022000D02*
X-225125Y1020750D01*
X-223550Y1020000D01*
X-222150D01*
X-220750Y1020750D01*
X-219700Y1022000D01*
X-219175Y1023750D01*
X-219525Y1025500D01*
X-220400Y1027000D01*
X-221975Y1028000D01*
X-224075Y1028500D01*
X-225300Y1029500D01*
X-225825Y1031250D01*
X-225475Y1033000D01*
X-224600Y1034250D01*
X-223375Y1035000D01*
X-222150D01*
X-220925Y1034500D01*
X-219875Y1033250D01*
G01X-212500Y1020000D02*
Y1035000D01*
G01X-205850D02*
X-212500Y1025750D01*
G01X-204800Y1020000D02*
X-209525Y1030000D01*
G01X-183750Y1020000D02*
Y1035000D01*
X-179550D01*
X-178150Y1034250D01*
X-177100Y1032500D01*
X-176750Y1030500D01*
X-177100Y1028500D01*
X-177975Y1027000D01*
X-179550Y1026250D01*
X-183750D01*
G01X-170425Y1020000D02*
X-166050Y1035000D01*
X-161675Y1020000D01*
G01X-163250Y1025250D02*
X-168850D01*
G01X-155700Y1020000D02*
Y1035000D01*
X-152200D01*
X-150800Y1034250D01*
X-149750Y1033250D01*
X-148875Y1031750D01*
X-148175Y1030000D01*
X-148000Y1027500D01*
X-148175Y1025000D01*
X-148875Y1023250D01*
X-149750Y1021750D01*
X-150800Y1020750D01*
X-152200Y1020000D01*
X-155700D01*
G01X-141325Y1022000D02*
X-139925Y1020750D01*
X-138350Y1020000D01*
X-136950D01*
X-135550Y1020750D01*
X-134500Y1022000D01*
X-133975Y1023750D01*
X-134325Y1025500D01*
X-135200Y1027000D01*
X-136775Y1028000D01*
X-138875Y1028500D01*
X-140100Y1029500D01*
X-140625Y1031250D01*
X-140275Y1033000D01*
X-139400Y1034250D01*
X-138175Y1035000D01*
X-136950D01*
X-135725Y1034500D01*
X-134675Y1033250D01*
G01X-112925Y1022000D02*
X-111525Y1020750D01*
X-109950Y1020000D01*
X-108550D01*
X-107150Y1020750D01*
X-106100Y1022000D01*
X-105575Y1023750D01*
X-105925Y1025500D01*
X-106800Y1027000D01*
X-108375Y1028000D01*
X-110475Y1028500D01*
X-111700Y1029500D01*
X-112225Y1031250D01*
X-111875Y1033000D01*
X-111000Y1034250D01*
X-109775Y1035000D01*
X-108550D01*
X-107325Y1034500D01*
X-106275Y1033250D01*
G01X-98725Y1020000D02*
Y1035000D01*
G01X-91375D02*
Y1020000D01*
G01Y1027500D02*
X-98725D01*
G01X-85225Y1020000D02*
X-80850Y1035000D01*
X-76475Y1020000D01*
G01X-78050Y1025250D02*
X-83650D01*
G01X-70150Y1035000D02*
Y1020000D01*
X-63150D01*
G01X-55950Y1035000D02*
Y1020000D01*
X-48950D01*
G01X-22650Y1028000D02*
X-21950Y1028750D01*
X-21425Y1030000D01*
X-21075Y1031750D01*
X-21425Y1033250D01*
X-22125Y1034250D01*
X-23350Y1035000D01*
X-28075D01*
Y1020000D01*
X-22300D01*
X-21075Y1021000D01*
X-20375Y1022500D01*
X-20025Y1024250D01*
X-20375Y1026000D01*
X-21425Y1027500D01*
X-22650Y1028000D01*
X-28075D01*
G01X-6350Y1020000D02*
X-13350D01*
Y1035000D01*
X-6350D01*
G01X-9150Y1027750D02*
X-13350D01*
G01X22050Y1020000D02*
X15050D01*
Y1035000D01*
X22050D01*
G01X19250Y1027750D02*
X15050D01*
G01X28725Y1020000D02*
Y1035000D01*
X36775Y1020000D01*
Y1035000D01*
G01X43450D02*
Y1020000D01*
X50450D01*
G01X56775D02*
X61150Y1035000D01*
X65525Y1020000D01*
G01X63950Y1025250D02*
X58350D01*
G01X71850Y1020000D02*
Y1035000D01*
X76225D01*
X77625Y1034250D01*
X78500Y1033250D01*
X78850Y1031250D01*
X78500Y1029250D01*
X77450Y1028000D01*
X76225Y1027250D01*
X71850D01*
G01X76225D02*
X78850Y1020000D01*
G01X90600Y1027500D02*
X94100D01*
Y1023000D01*
X93050Y1021500D01*
X91825Y1020500D01*
X90075Y1020000D01*
X88325Y1020500D01*
X87100Y1021500D01*
X86050Y1023000D01*
X85350Y1024750D01*
X85000Y1026750D01*
Y1028500D01*
X85350Y1030000D01*
X86050Y1031750D01*
X87100Y1033250D01*
X88150Y1034250D01*
X89550Y1035000D01*
X90775D01*
X92175Y1034500D01*
X93225Y1033500D01*
G01X107250Y1020000D02*
X100250D01*
Y1035000D01*
X107250D01*
G01X104450Y1027750D02*
X100250D01*
G01X114100Y1020000D02*
Y1035000D01*
X117600D01*
X119000Y1034250D01*
X120050Y1033250D01*
X120925Y1031750D01*
X121625Y1030000D01*
X121800Y1027500D01*
X121625Y1025000D01*
X120925Y1023250D01*
X120050Y1021750D01*
X119000Y1020750D01*
X117600Y1020000D01*
X114100D01*
G01X147750Y1028000D02*
X148450Y1028750D01*
X148975Y1030000D01*
X149325Y1031750D01*
X148975Y1033250D01*
X148275Y1034250D01*
X147050Y1035000D01*
X142325D01*
Y1020000D01*
X148100D01*
X149325Y1021000D01*
X150025Y1022500D01*
X150375Y1024250D01*
X150025Y1026000D01*
X148975Y1027500D01*
X147750Y1028000D01*
X142325D01*
G01X160550Y1020000D02*
Y1026750D01*
X157050Y1035000D01*
G01X164050D02*
X160550Y1026750D01*
G01X188950Y1019500D02*
X188600Y1019750D01*
Y1020250D01*
X188950Y1020500D01*
X189300Y1020250D01*
Y1019750D01*
X188950Y1019500D01*
G01X203150Y1035000D02*
X201750Y1034500D01*
X200700Y1033250D01*
X200000Y1031750D01*
X199475Y1029750D01*
X199300Y1027500D01*
X199475Y1025250D01*
X200000Y1023250D01*
X200700Y1021750D01*
X201750Y1020500D01*
X203150Y1020000D01*
X204550Y1020500D01*
X205600Y1021750D01*
X206300Y1023250D01*
X206825Y1025250D01*
X207000Y1027500D01*
X206825Y1029750D01*
X206300Y1031750D01*
X205600Y1033250D01*
X204550Y1034500D01*
X203150Y1035000D01*
G01X217350D02*
X215950Y1034500D01*
X214900Y1033250D01*
X214200Y1031750D01*
X213675Y1029750D01*
X213500Y1027500D01*
X213675Y1025250D01*
X214200Y1023250D01*
X214900Y1021750D01*
X215950Y1020500D01*
X217350Y1020000D01*
X218750Y1020500D01*
X219800Y1021750D01*
X220500Y1023250D01*
X221025Y1025250D01*
X221200Y1027500D01*
X221025Y1029750D01*
X220500Y1031750D01*
X219800Y1033250D01*
X218750Y1034500D01*
X217350Y1035000D01*
G01X233650Y1020000D02*
Y1035000D01*
X227175Y1024250D01*
X235925D01*
G01X244175Y1031750D02*
X245050Y1035000D01*
G01X247325D02*
X246450Y1031750D01*
G01X274150Y1020000D02*
X272750Y1020250D01*
X271525Y1021250D01*
X270475Y1022750D01*
X269775Y1024500D01*
X269425Y1026500D01*
Y1028500D01*
X269775Y1030500D01*
X270475Y1032250D01*
X271525Y1033750D01*
X272750Y1034750D01*
X274150Y1035000D01*
X275550Y1034750D01*
X276775Y1033750D01*
X277825Y1032250D01*
X278525Y1030500D01*
X278875Y1028500D01*
Y1026500D01*
X278525Y1024500D01*
X277825Y1022750D01*
X276775Y1021250D01*
X275550Y1020250D01*
X274150Y1020000D01*
G01X283975Y1035000D02*
X288350Y1020000D01*
X292725Y1035000D01*
G01X306050Y1020000D02*
X299050D01*
Y1035000D01*
X306050D01*
G01X303250Y1027750D02*
X299050D01*
G01X313250Y1020000D02*
Y1035000D01*
X317625D01*
X319025Y1034250D01*
X319900Y1033250D01*
X320250Y1031250D01*
X319900Y1029250D01*
X318850Y1028000D01*
X317625Y1027250D01*
X313250D01*
G01X317625D02*
X320250Y1020000D01*
G01X326575D02*
X330950Y1035000D01*
X335325Y1020000D01*
G01X333750Y1025250D02*
X328150D01*
G01X341650Y1035000D02*
Y1020000D01*
X348650D01*
G01X355850Y1035000D02*
Y1020000D01*
X362850D01*
G01X387750D02*
X386350Y1020250D01*
X385125Y1021250D01*
X384075Y1022750D01*
X383375Y1024500D01*
X383025Y1026500D01*
Y1028500D01*
X383375Y1030500D01*
X384075Y1032250D01*
X385125Y1033750D01*
X386350Y1034750D01*
X387750Y1035000D01*
X389150Y1034750D01*
X390375Y1033750D01*
X391425Y1032250D01*
X392125Y1030500D01*
X392475Y1028500D01*
Y1026500D01*
X392125Y1024500D01*
X391425Y1022750D01*
X390375Y1021250D01*
X389150Y1020250D01*
X387750Y1020000D01*
G01X398450D02*
Y1035000D01*
X402825D01*
X404225Y1034250D01*
X405100Y1033250D01*
X405450Y1031250D01*
X405100Y1029250D01*
X404050Y1028000D01*
X402825Y1027250D01*
X398450D01*
G01X402825D02*
X405450Y1020000D01*
G01X430350Y1019500D02*
X430000Y1019750D01*
Y1020250D01*
X430350Y1020500D01*
X430700Y1020250D01*
Y1019750D01*
X430350Y1019500D01*
G01X444550Y1035000D02*
X443150Y1034500D01*
X442100Y1033250D01*
X441400Y1031750D01*
X440875Y1029750D01*
X440700Y1027500D01*
X440875Y1025250D01*
X441400Y1023250D01*
X442100Y1021750D01*
X443150Y1020500D01*
X444550Y1020000D01*
X445950Y1020500D01*
X447000Y1021750D01*
X447700Y1023250D01*
X448225Y1025250D01*
X448400Y1027500D01*
X448225Y1029750D01*
X447700Y1031750D01*
X447000Y1033250D01*
X445950Y1034500D01*
X444550Y1035000D01*
G01X458750D02*
X457350Y1034500D01*
X456300Y1033250D01*
X455600Y1031750D01*
X455075Y1029750D01*
X454900Y1027500D01*
X455075Y1025250D01*
X455600Y1023250D01*
X456300Y1021750D01*
X457350Y1020500D01*
X458750Y1020000D01*
X460150Y1020500D01*
X461200Y1021750D01*
X461900Y1023250D01*
X462425Y1025250D01*
X462600Y1027500D01*
X462425Y1029750D01*
X461900Y1031750D01*
X461200Y1033250D01*
X460150Y1034500D01*
X458750Y1035000D01*
G01X469625Y1032500D02*
X470675Y1034000D01*
X471900Y1034750D01*
X473300Y1035000D01*
X475050Y1034500D01*
X476275Y1033250D01*
X476625Y1031750D01*
X476450Y1030250D01*
X475750Y1029000D01*
X472250Y1026500D01*
X470675Y1024750D01*
X469625Y1022250D01*
X469275Y1020000D01*
X476625D01*
G01X485575Y1031750D02*
X486450Y1035000D01*
G01X488725D02*
X487850Y1031750D01*
G01X512050Y1020000D02*
Y1035000D01*
X516250D01*
X517650Y1034250D01*
X518700Y1032500D01*
X519050Y1030500D01*
X518700Y1028500D01*
X517825Y1027000D01*
X516250Y1026250D01*
X512050D01*
G01X533250Y1020000D02*
X526250D01*
Y1035000D01*
X533250D01*
G01X530450Y1027750D02*
X526250D01*
G01X540450Y1020000D02*
Y1035000D01*
X544825D01*
X546225Y1034250D01*
X547100Y1033250D01*
X547450Y1031250D01*
X547100Y1029250D01*
X546050Y1028000D01*
X544825Y1027250D01*
X540450D01*
G01X544825D02*
X547450Y1020000D01*
G01X568675Y1022000D02*
X570075Y1020750D01*
X571650Y1020000D01*
X573050D01*
X574450Y1020750D01*
X575500Y1022000D01*
X576025Y1023750D01*
X575675Y1025500D01*
X574800Y1027000D01*
X573225Y1028000D01*
X571125Y1028500D01*
X569900Y1029500D01*
X569375Y1031250D01*
X569725Y1033000D01*
X570600Y1034250D01*
X571825Y1035000D01*
X573050D01*
X574275Y1034500D01*
X575325Y1033250D01*
G01X584450Y1035000D02*
X588650D01*
G01X586550D02*
Y1020000D01*
G01X584450D02*
X588650D01*
G01X596900D02*
Y1035000D01*
X600400D01*
X601800Y1034250D01*
X602850Y1033250D01*
X603725Y1031750D01*
X604425Y1030000D01*
X604600Y1027500D01*
X604425Y1025000D01*
X603725Y1023250D01*
X602850Y1021750D01*
X601800Y1020750D01*
X600400Y1020000D01*
X596900D01*
G01X618450D02*
X611450D01*
Y1035000D01*
X618450D01*
G01X615650Y1027750D02*
X611450D01*
G01X-396575Y1062500D02*
X-395525Y1064000D01*
X-394300Y1064750D01*
X-392900Y1065000D01*
X-391150Y1064500D01*
X-389925Y1063250D01*
X-389575Y1061750D01*
X-389750Y1060250D01*
X-390450Y1059000D01*
X-393950Y1056500D01*
X-395525Y1054750D01*
X-396575Y1052250D01*
X-396925Y1050000D01*
X-389575D01*
G01X-382900Y1053000D02*
X-381850Y1051250D01*
X-380450Y1050250D01*
X-378875Y1050000D01*
X-377475Y1050250D01*
X-376075Y1051500D01*
X-375200Y1053000D01*
X-375025Y1054500D01*
X-375375Y1056250D01*
X-376600Y1057500D01*
X-377825Y1058000D01*
X-379400D01*
G01X-377825D02*
X-376775Y1058750D01*
X-375900Y1060000D01*
X-375550Y1061500D01*
X-375900Y1063000D01*
X-376775Y1064250D01*
X-378350Y1065000D01*
X-379925Y1064750D01*
X-381500Y1063750D01*
G01X-364850Y1049500D02*
X-365200Y1049750D01*
Y1050250D01*
X-364850Y1050500D01*
X-364500Y1050250D01*
Y1049750D01*
X-364850Y1049500D01*
G01X-340125Y1052000D02*
X-338725Y1050750D01*
X-337150Y1050000D01*
X-335750D01*
X-334350Y1050750D01*
X-333300Y1052000D01*
X-332775Y1053750D01*
X-333125Y1055500D01*
X-334000Y1057000D01*
X-335575Y1058000D01*
X-337675Y1058500D01*
X-338900Y1059500D01*
X-339425Y1061250D01*
X-339075Y1063000D01*
X-338200Y1064250D01*
X-336975Y1065000D01*
X-335750D01*
X-334525Y1064500D01*
X-333475Y1063250D01*
G01X-322250Y1050000D02*
X-323650Y1050250D01*
X-324875Y1051250D01*
X-325925Y1052750D01*
X-326625Y1054500D01*
X-326975Y1056500D01*
Y1058500D01*
X-326625Y1060500D01*
X-325925Y1062250D01*
X-324875Y1063750D01*
X-323650Y1064750D01*
X-322250Y1065000D01*
X-320850Y1064750D01*
X-319625Y1063750D01*
X-318575Y1062250D01*
X-317875Y1060500D01*
X-317525Y1058500D01*
Y1056500D01*
X-317875Y1054500D01*
X-318575Y1052750D01*
X-319625Y1051250D01*
X-320850Y1050250D01*
X-322250Y1050000D01*
G01X-311550Y1065000D02*
Y1050000D01*
X-304550D01*
G01X-297700D02*
Y1065000D01*
X-294200D01*
X-292800Y1064250D01*
X-291750Y1063250D01*
X-290875Y1061750D01*
X-290175Y1060000D01*
X-290000Y1057500D01*
X-290175Y1055000D01*
X-290875Y1053250D01*
X-291750Y1051750D01*
X-292800Y1050750D01*
X-294200Y1050000D01*
X-297700D01*
G01X-276150D02*
X-283150D01*
Y1065000D01*
X-276150D01*
G01X-278950Y1057750D02*
X-283150D01*
G01X-268950Y1050000D02*
Y1065000D01*
X-264575D01*
X-263175Y1064250D01*
X-262300Y1063250D01*
X-261950Y1061250D01*
X-262300Y1059250D01*
X-263350Y1058000D01*
X-264575Y1057250D01*
X-268950D01*
G01X-264575D02*
X-261950Y1050000D01*
G01X-255800D02*
Y1065000D01*
X-251250Y1052500D01*
X-246700Y1065000D01*
Y1050000D01*
G01X-241425D02*
X-237050Y1065000D01*
X-232675Y1050000D01*
G01X-234250Y1055250D02*
X-239850D01*
G01X-226525Y1052000D02*
X-225125Y1050750D01*
X-223550Y1050000D01*
X-222150D01*
X-220750Y1050750D01*
X-219700Y1052000D01*
X-219175Y1053750D01*
X-219525Y1055500D01*
X-220400Y1057000D01*
X-221975Y1058000D01*
X-224075Y1058500D01*
X-225300Y1059500D01*
X-225825Y1061250D01*
X-225475Y1063000D01*
X-224600Y1064250D01*
X-223375Y1065000D01*
X-222150D01*
X-220925Y1064500D01*
X-219875Y1063250D01*
G01X-212500Y1050000D02*
Y1065000D01*
G01X-205850D02*
X-212500Y1055750D01*
G01X-204800Y1050000D02*
X-209525Y1060000D01*
G01X-178850Y1058000D02*
X-178150Y1058750D01*
X-177625Y1060000D01*
X-177275Y1061750D01*
X-177625Y1063250D01*
X-178325Y1064250D01*
X-179550Y1065000D01*
X-184275D01*
Y1050000D01*
X-178500D01*
X-177275Y1051000D01*
X-176575Y1052500D01*
X-176225Y1054250D01*
X-176575Y1056000D01*
X-177625Y1057500D01*
X-178850Y1058000D01*
X-184275D01*
G01X-166050Y1050000D02*
X-167450Y1050250D01*
X-168675Y1051250D01*
X-169725Y1052750D01*
X-170425Y1054500D01*
X-170775Y1056500D01*
Y1058500D01*
X-170425Y1060500D01*
X-169725Y1062250D01*
X-168675Y1063750D01*
X-167450Y1064750D01*
X-166050Y1065000D01*
X-164650Y1064750D01*
X-163425Y1063750D01*
X-162375Y1062250D01*
X-161675Y1060500D01*
X-161325Y1058500D01*
Y1056500D01*
X-161675Y1054500D01*
X-162375Y1052750D01*
X-163425Y1051250D01*
X-164650Y1050250D01*
X-166050Y1050000D01*
G01X-151850Y1065000D02*
Y1050000D01*
G01X-155875Y1065000D02*
X-147825D01*
G01X-141325Y1050000D02*
Y1065000D01*
G01X-133975D02*
Y1050000D01*
G01Y1057500D02*
X-141325D01*
G01X-112925Y1052000D02*
X-111525Y1050750D01*
X-109950Y1050000D01*
X-108550D01*
X-107150Y1050750D01*
X-106100Y1052000D01*
X-105575Y1053750D01*
X-105925Y1055500D01*
X-106800Y1057000D01*
X-108375Y1058000D01*
X-110475Y1058500D01*
X-111700Y1059500D01*
X-112225Y1061250D01*
X-111875Y1063000D01*
X-111000Y1064250D01*
X-109775Y1065000D01*
X-108550D01*
X-107325Y1064500D01*
X-106275Y1063250D01*
G01X-97150Y1065000D02*
X-92950D01*
G01X-95050D02*
Y1050000D01*
G01X-97150D02*
X-92950D01*
G01X-84700D02*
Y1065000D01*
X-81200D01*
X-79800Y1064250D01*
X-78750Y1063250D01*
X-77875Y1061750D01*
X-77175Y1060000D01*
X-77000Y1057500D01*
X-77175Y1055000D01*
X-77875Y1053250D01*
X-78750Y1051750D01*
X-79800Y1050750D01*
X-81200Y1050000D01*
X-84700D01*
G01X-63150D02*
X-70150D01*
Y1065000D01*
X-63150D01*
G01X-65950Y1057750D02*
X-70150D01*
G01X-56125Y1052000D02*
X-54725Y1050750D01*
X-53150Y1050000D01*
X-51750D01*
X-50350Y1050750D01*
X-49300Y1052000D01*
X-48775Y1053750D01*
X-49125Y1055500D01*
X-50000Y1057000D01*
X-51575Y1058000D01*
X-53675Y1058500D01*
X-54900Y1059500D01*
X-55425Y1061250D01*
X-55075Y1063000D01*
X-54200Y1064250D01*
X-52975Y1065000D01*
X-51750D01*
X-50525Y1064500D01*
X-49475Y1063250D01*
G01X-38600Y1047250D02*
X-37900Y1050500D01*
G01X-13700Y1065000D02*
Y1054250D01*
X-13000Y1052000D01*
X-11600Y1050500D01*
X-9850Y1050000D01*
X-8100Y1050500D01*
X-6700Y1052000D01*
X-6000Y1054250D01*
Y1065000D01*
G01X675Y1052000D02*
X2075Y1050750D01*
X3650Y1050000D01*
X5050D01*
X6450Y1050750D01*
X7500Y1052000D01*
X8025Y1053750D01*
X7675Y1055500D01*
X6800Y1057000D01*
X5225Y1058000D01*
X3125Y1058500D01*
X1900Y1059500D01*
X1375Y1061250D01*
X1725Y1063000D01*
X2600Y1064250D01*
X3825Y1065000D01*
X5050D01*
X6275Y1064500D01*
X7325Y1063250D01*
G01X16450Y1065000D02*
X20650D01*
G01X18550D02*
Y1050000D01*
G01X16450D02*
X20650D01*
G01X28725D02*
Y1065000D01*
X36775Y1050000D01*
Y1065000D01*
G01X48000Y1057500D02*
X51500D01*
Y1053000D01*
X50450Y1051500D01*
X49225Y1050500D01*
X47475Y1050000D01*
X45725Y1050500D01*
X44500Y1051500D01*
X43450Y1053000D01*
X42750Y1054750D01*
X42400Y1056750D01*
Y1058500D01*
X42750Y1060000D01*
X43450Y1061750D01*
X44500Y1063250D01*
X45550Y1064250D01*
X46950Y1065000D01*
X48175D01*
X49575Y1064500D01*
X50625Y1063500D01*
G01X76400Y1057500D02*
X79900D01*
Y1053000D01*
X78850Y1051500D01*
X77625Y1050500D01*
X75875Y1050000D01*
X74125Y1050500D01*
X72900Y1051500D01*
X71850Y1053000D01*
X71150Y1054750D01*
X70800Y1056750D01*
Y1058500D01*
X71150Y1060000D01*
X71850Y1061750D01*
X72900Y1063250D01*
X73950Y1064250D01*
X75350Y1065000D01*
X76575D01*
X77975Y1064500D01*
X79025Y1063500D01*
G01X86050Y1050000D02*
Y1065000D01*
X90425D01*
X91825Y1064250D01*
X92700Y1063250D01*
X93050Y1061250D01*
X92700Y1059250D01*
X91650Y1058000D01*
X90425Y1057250D01*
X86050D01*
G01X90425D02*
X93050Y1050000D01*
G01X107250D02*
X100250D01*
Y1065000D01*
X107250D01*
G01X104450Y1057750D02*
X100250D01*
G01X121450Y1050000D02*
X114450D01*
Y1065000D01*
X121450D01*
G01X118650Y1057750D02*
X114450D01*
G01X128125Y1050000D02*
Y1065000D01*
X136175Y1050000D01*
Y1065000D01*
G01X157050D02*
Y1050000D01*
X164050D01*
G01X171250D02*
Y1065000D01*
X175450D01*
X176850Y1064250D01*
X177900Y1062500D01*
X178250Y1060500D01*
X177900Y1058500D01*
X177025Y1057000D01*
X175450Y1056250D01*
X171250D01*
G01X186850Y1065000D02*
X191050D01*
G01X188950D02*
Y1050000D01*
G01X186850D02*
X191050D01*
G01X212800D02*
Y1065000D01*
X217350Y1052500D01*
X221900Y1065000D01*
Y1050000D01*
G01X227175D02*
X231550Y1065000D01*
X235925Y1050000D01*
G01X234350Y1055250D02*
X228750D01*
G01X245750Y1065000D02*
Y1050000D01*
G01X241725Y1065000D02*
X249775D01*
G01X259950D02*
Y1050000D01*
G01X255925Y1065000D02*
X263975D01*
G01X277650Y1050000D02*
X270650D01*
Y1065000D01*
X277650D01*
G01X274850Y1057750D02*
X270650D01*
G01X302550Y1050000D02*
X301150Y1050250D01*
X299925Y1051250D01*
X298875Y1052750D01*
X298175Y1054500D01*
X297825Y1056500D01*
Y1058500D01*
X298175Y1060500D01*
X298875Y1062250D01*
X299925Y1063750D01*
X301150Y1064750D01*
X302550Y1065000D01*
X303950Y1064750D01*
X305175Y1063750D01*
X306225Y1062250D01*
X306925Y1060500D01*
X307275Y1058500D01*
Y1056500D01*
X306925Y1054500D01*
X306225Y1052750D01*
X305175Y1051250D01*
X303950Y1050250D01*
X302550Y1050000D01*
G01X313250D02*
Y1065000D01*
X317625D01*
X319025Y1064250D01*
X319900Y1063250D01*
X320250Y1061250D01*
X319900Y1059250D01*
X318850Y1058000D01*
X317625Y1057250D01*
X313250D01*
G01X317625D02*
X320250Y1050000D01*
G01X346200Y1057500D02*
X349700D01*
Y1053000D01*
X348650Y1051500D01*
X347425Y1050500D01*
X345675Y1050000D01*
X343925Y1050500D01*
X342700Y1051500D01*
X341650Y1053000D01*
X340950Y1054750D01*
X340600Y1056750D01*
Y1058500D01*
X340950Y1060000D01*
X341650Y1061750D01*
X342700Y1063250D01*
X343750Y1064250D01*
X345150Y1065000D01*
X346375D01*
X347775Y1064500D01*
X348825Y1063500D01*
G01X355850Y1065000D02*
Y1050000D01*
X362850D01*
G01X373550D02*
X372150Y1050250D01*
X370925Y1051250D01*
X369875Y1052750D01*
X369175Y1054500D01*
X368825Y1056500D01*
Y1058500D01*
X369175Y1060500D01*
X369875Y1062250D01*
X370925Y1063750D01*
X372150Y1064750D01*
X373550Y1065000D01*
X374950Y1064750D01*
X376175Y1063750D01*
X377225Y1062250D01*
X377925Y1060500D01*
X378275Y1058500D01*
Y1056500D01*
X377925Y1054500D01*
X377225Y1052750D01*
X376175Y1051250D01*
X374950Y1050250D01*
X373550Y1050000D01*
G01X384075Y1052000D02*
X385475Y1050750D01*
X387050Y1050000D01*
X388450D01*
X389850Y1050750D01*
X390900Y1052000D01*
X391425Y1053750D01*
X391075Y1055500D01*
X390200Y1057000D01*
X388625Y1058000D01*
X386525Y1058500D01*
X385300Y1059500D01*
X384775Y1061250D01*
X385125Y1063000D01*
X386000Y1064250D01*
X387225Y1065000D01*
X388450D01*
X389675Y1064500D01*
X390725Y1063250D01*
G01X398275Y1052000D02*
X399675Y1050750D01*
X401250Y1050000D01*
X402650D01*
X404050Y1050750D01*
X405100Y1052000D01*
X405625Y1053750D01*
X405275Y1055500D01*
X404400Y1057000D01*
X402825Y1058000D01*
X400725Y1058500D01*
X399500Y1059500D01*
X398975Y1061250D01*
X399325Y1063000D01*
X400200Y1064250D01*
X401425Y1065000D01*
X402650D01*
X403875Y1064500D01*
X404925Y1063250D01*
G01X426675Y1052000D02*
X428075Y1050750D01*
X429650Y1050000D01*
X431050D01*
X432450Y1050750D01*
X433500Y1052000D01*
X434025Y1053750D01*
X433675Y1055500D01*
X432800Y1057000D01*
X431225Y1058000D01*
X429125Y1058500D01*
X427900Y1059500D01*
X427375Y1061250D01*
X427725Y1063000D01*
X428600Y1064250D01*
X429825Y1065000D01*
X431050D01*
X432275Y1064500D01*
X433325Y1063250D01*
G01X444550Y1050000D02*
X443150Y1050250D01*
X441925Y1051250D01*
X440875Y1052750D01*
X440175Y1054500D01*
X439825Y1056500D01*
Y1058500D01*
X440175Y1060500D01*
X440875Y1062250D01*
X441925Y1063750D01*
X443150Y1064750D01*
X444550Y1065000D01*
X445950Y1064750D01*
X447175Y1063750D01*
X448225Y1062250D01*
X448925Y1060500D01*
X449275Y1058500D01*
Y1056500D01*
X448925Y1054500D01*
X448225Y1052750D01*
X447175Y1051250D01*
X445950Y1050250D01*
X444550Y1050000D01*
G01X455250Y1065000D02*
Y1050000D01*
X462250D01*
G01X469100D02*
Y1065000D01*
X472600D01*
X474000Y1064250D01*
X475050Y1063250D01*
X475925Y1061750D01*
X476625Y1060000D01*
X476800Y1057500D01*
X476625Y1055000D01*
X475925Y1053250D01*
X475050Y1051750D01*
X474000Y1050750D01*
X472600Y1050000D01*
X469100D01*
G01X490650D02*
X483650D01*
Y1065000D01*
X490650D01*
G01X487850Y1057750D02*
X483650D01*
G01X497850Y1050000D02*
Y1065000D01*
X502225D01*
X503625Y1064250D01*
X504500Y1063250D01*
X504850Y1061250D01*
X504500Y1059250D01*
X503450Y1058000D01*
X502225Y1057250D01*
X497850D01*
G01X502225D02*
X504850Y1050000D01*
G01X511000D02*
Y1065000D01*
X515550Y1052500D01*
X520100Y1065000D01*
Y1050000D01*
G01X525375D02*
X529750Y1065000D01*
X534125Y1050000D01*
G01X532550Y1055250D02*
X526950D01*
G01X540275Y1052000D02*
X541675Y1050750D01*
X543250Y1050000D01*
X544650D01*
X546050Y1050750D01*
X547100Y1052000D01*
X547625Y1053750D01*
X547275Y1055500D01*
X546400Y1057000D01*
X544825Y1058000D01*
X542725Y1058500D01*
X541500Y1059500D01*
X540975Y1061250D01*
X541325Y1063000D01*
X542200Y1064250D01*
X543425Y1065000D01*
X544650D01*
X545875Y1064500D01*
X546925Y1063250D01*
G01X554300Y1050000D02*
Y1065000D01*
G01X560950D02*
X554300Y1055750D01*
G01X562000Y1050000D02*
X557275Y1060000D01*
G01X583050Y1050000D02*
Y1065000D01*
X587250D01*
X588650Y1064250D01*
X589700Y1062500D01*
X590050Y1060500D01*
X589700Y1058500D01*
X588825Y1057000D01*
X587250Y1056250D01*
X583050D01*
G01X604250Y1050000D02*
X597250D01*
Y1065000D01*
X604250D01*
G01X601450Y1057750D02*
X597250D01*
G01X611450Y1050000D02*
Y1065000D01*
X615825D01*
X617225Y1064250D01*
X618100Y1063250D01*
X618450Y1061250D01*
X618100Y1059250D01*
X617050Y1058000D01*
X615825Y1057250D01*
X611450D01*
G01X615825D02*
X618450Y1050000D01*
G01X641250Y1065000D02*
X645450D01*
G01X643350D02*
Y1050000D01*
G01X641250D02*
X645450D01*
G01X654050D02*
Y1065000D01*
X658250D01*
X659650Y1064250D01*
X660700Y1062500D01*
X661050Y1060500D01*
X660700Y1058500D01*
X659825Y1057000D01*
X658250Y1056250D01*
X654050D01*
G01X675600Y1063750D02*
X674550Y1064500D01*
X673325Y1065000D01*
X671925D01*
X670350Y1064250D01*
X669125Y1063000D01*
X668250Y1061500D01*
X667550Y1059000D01*
X667375Y1056750D01*
X667725Y1054500D01*
X668250Y1053000D01*
X669300Y1051500D01*
X670525Y1050500D01*
X671750Y1050000D01*
X672975D01*
X674200Y1050500D01*
X675250Y1051250D01*
X676125Y1052250D01*
G01X683675Y1055000D02*
X688225D01*
G01X696475Y1052000D02*
X697875Y1050750D01*
X699450Y1050000D01*
X700850D01*
X702250Y1050750D01*
X703300Y1052000D01*
X703825Y1053750D01*
X703475Y1055500D01*
X702600Y1057000D01*
X701025Y1058000D01*
X698925Y1058500D01*
X697700Y1059500D01*
X697175Y1061250D01*
X697525Y1063000D01*
X698400Y1064250D01*
X699625Y1065000D01*
X700850D01*
X702075Y1064500D01*
X703125Y1063250D01*
G01X709800Y1050000D02*
Y1065000D01*
X714350Y1052500D01*
X718900Y1065000D01*
Y1050000D01*
G01X726275Y1055000D02*
X730825D01*
G01X742750Y1050000D02*
X743975Y1050250D01*
X745375Y1051000D01*
X746250Y1052250D01*
X746600Y1054000D01*
X746250Y1055750D01*
X745200Y1057250D01*
X743625Y1058000D01*
X741875D01*
X740825Y1058500D01*
X739950Y1059750D01*
X739600Y1061500D01*
X740125Y1063250D01*
X741350Y1064500D01*
X742750Y1065000D01*
X744150Y1064500D01*
X745375Y1063250D01*
X745900Y1061500D01*
X745550Y1059750D01*
X744675Y1058500D01*
X743625Y1058000D01*
X741875D01*
X740300Y1057250D01*
X739250Y1055750D01*
X738900Y1054000D01*
X739250Y1052250D01*
X740125Y1051000D01*
X741525Y1050250D01*
X742750Y1050000D01*
G01X759050D02*
Y1065000D01*
X752575Y1054250D01*
X761325D01*
G01X771150Y1065000D02*
X769750Y1064500D01*
X768700Y1063250D01*
X768000Y1061750D01*
X767475Y1059750D01*
X767300Y1057500D01*
X767475Y1055250D01*
X768000Y1053250D01*
X768700Y1051750D01*
X769750Y1050500D01*
X771150Y1050000D01*
X772550Y1050500D01*
X773600Y1051750D01*
X774300Y1053250D01*
X774825Y1055250D01*
X775000Y1057500D01*
X774825Y1059750D01*
X774300Y1061750D01*
X773600Y1063250D01*
X772550Y1064500D01*
X771150Y1065000D01*
G01X785350Y1049500D02*
X785000Y1049750D01*
Y1050250D01*
X785350Y1050500D01*
X785700Y1050250D01*
Y1049750D01*
X785350Y1049500D01*
G01X-200000Y-800000D02*
Y-850000D01*
G01Y1350000D02*
Y1300000D01*
G01X225000Y-800000D02*
Y-850000D01*
G01Y1350000D02*
Y1300000D01*
G01X890000Y-735000D02*
X640000D01*
G01X890000Y-705000D02*
X640000D01*
G01X890000Y-675000D02*
X640000D01*
G01X890000Y-640000D02*
X640000D01*
G01X890000Y-610000D02*
X640000D01*
G01X890000Y-580000D02*
X640000D01*
G01X650000Y-800000D02*
Y-850000D01*
G01Y1350000D02*
Y1300000D01*
G01X808000Y-550000D02*
Y-800000D01*
G01X940000Y-770000D02*
Y-720000D01*
G01X990000Y-770000D02*
Y-720000D01*
G01X1018875Y-655000D02*
Y-640000D01*
X1025525D01*
G01X1023075Y-647250D02*
X1018875D01*
G01X1032025Y-655000D02*
X1036400Y-640000D01*
X1040775Y-655000D01*
G01X1039200Y-649750D02*
X1033600D01*
G01X1052000Y-647000D02*
X1052700Y-646250D01*
X1053225Y-645000D01*
X1053575Y-643250D01*
X1053225Y-641750D01*
X1052525Y-640750D01*
X1051300Y-640000D01*
X1046575D01*
Y-655000D01*
X1052350D01*
X1053575Y-654000D01*
X1054275Y-652500D01*
X1054625Y-650750D01*
X1054275Y-649000D01*
X1053225Y-647500D01*
X1052000Y-647000D01*
X1046575D01*
G01X1061300Y-655000D02*
Y-640000D01*
X1065675D01*
X1067075Y-640750D01*
X1067950Y-641750D01*
X1068300Y-643750D01*
X1067950Y-645750D01*
X1066900Y-647000D01*
X1065675Y-647750D01*
X1061300D01*
G01X1065675D02*
X1068300Y-655000D01*
G01X1076900Y-640000D02*
X1081100D01*
G01X1079000D02*
Y-655000D01*
G01X1076900D02*
X1081100D01*
G01X1097050Y-641250D02*
X1096000Y-640500D01*
X1094775Y-640000D01*
X1093375D01*
X1091800Y-640750D01*
X1090575Y-642000D01*
X1089700Y-643500D01*
X1089000Y-646000D01*
X1088825Y-648250D01*
X1089175Y-650500D01*
X1089700Y-652000D01*
X1090750Y-653500D01*
X1091975Y-654500D01*
X1093200Y-655000D01*
X1094425D01*
X1095650Y-654500D01*
X1096700Y-653750D01*
X1097575Y-652750D01*
G01X1103025Y-655000D02*
X1107400Y-640000D01*
X1111775Y-655000D01*
G01X1110200Y-649750D02*
X1104600D01*
G01X1121600Y-640000D02*
Y-655000D01*
G01X1117575Y-640000D02*
X1125625D01*
G01X1133700D02*
X1137900D01*
G01X1135800D02*
Y-655000D01*
G01X1133700D02*
X1137900D01*
G01X1150000D02*
X1148600Y-654750D01*
X1147375Y-653750D01*
X1146325Y-652250D01*
X1145625Y-650500D01*
X1145275Y-648500D01*
Y-646500D01*
X1145625Y-644500D01*
X1146325Y-642750D01*
X1147375Y-641250D01*
X1148600Y-640250D01*
X1150000Y-640000D01*
X1151400Y-640250D01*
X1152625Y-641250D01*
X1153675Y-642750D01*
X1154375Y-644500D01*
X1154725Y-646500D01*
Y-648500D01*
X1154375Y-650500D01*
X1153675Y-652250D01*
X1152625Y-653750D01*
X1151400Y-654750D01*
X1150000Y-655000D01*
G01X1160175D02*
Y-640000D01*
X1168225Y-655000D01*
Y-640000D01*
G01X1188750Y-655000D02*
Y-640000D01*
X1192250D01*
X1193650Y-640750D01*
X1194700Y-641750D01*
X1195575Y-643250D01*
X1196275Y-645000D01*
X1196450Y-647500D01*
X1196275Y-650000D01*
X1195575Y-651750D01*
X1194700Y-653250D01*
X1193650Y-654250D01*
X1192250Y-655000D01*
X1188750D01*
G01X1203300D02*
Y-640000D01*
X1207675D01*
X1209075Y-640750D01*
X1209950Y-641750D01*
X1210300Y-643750D01*
X1209950Y-645750D01*
X1208900Y-647000D01*
X1207675Y-647750D01*
X1203300D01*
G01X1207675D02*
X1210300Y-655000D01*
G01X1216625D02*
X1221000Y-640000D01*
X1225375Y-655000D01*
G01X1223800Y-649750D02*
X1218200D01*
G01X1229950Y-640000D02*
X1232400Y-655000D01*
X1235200Y-640000D01*
X1238000Y-655000D01*
X1240450Y-640000D01*
G01X1247300D02*
X1251500D01*
G01X1249400D02*
Y-655000D01*
G01X1247300D02*
X1251500D01*
G01X1259575D02*
Y-640000D01*
X1267625Y-655000D01*
Y-640000D01*
G01X1278850Y-647500D02*
X1282350D01*
Y-652000D01*
X1281300Y-653500D01*
X1280075Y-654500D01*
X1278325Y-655000D01*
X1276575Y-654500D01*
X1275350Y-653500D01*
X1274300Y-652000D01*
X1273600Y-650250D01*
X1273250Y-648250D01*
Y-646500D01*
X1273600Y-645000D01*
X1274300Y-643250D01*
X1275350Y-641750D01*
X1276400Y-640750D01*
X1277800Y-640000D01*
X1279025D01*
X1280425Y-640500D01*
X1281475Y-641500D01*
G01X1075000Y-800000D02*
Y-850000D01*
G01Y1350000D02*
Y1300000D01*
G01X1105000Y-770000D02*
Y-720000D01*
G01X1230000Y-800000D02*
Y-770000D01*
G01X1305250Y-790000D02*
Y-775000D01*
X1303150Y-778000D01*
G01Y-790000D02*
X1307350D01*
G01X1350000Y-770000D02*
Y-720000D01*
G01X1366925Y-777500D02*
X1367975Y-776000D01*
X1369200Y-775250D01*
X1370600Y-775000D01*
X1372350Y-775500D01*
X1373575Y-776750D01*
X1373925Y-778250D01*
X1373750Y-779750D01*
X1373050Y-781000D01*
X1369550Y-783500D01*
X1367975Y-785250D01*
X1366925Y-787750D01*
X1366575Y-790000D01*
X1373925D01*
G01X1450000Y-300000D02*
X1400000D01*
G01Y250000D02*
X1450000D01*
G01Y800000D02*
X1400000D01*
G54D16*
G01X370000Y-800000D02*
Y-550000D01*
X1400000D01*
G01X640000Y-800000D02*
Y-550000D01*
G01X890000D02*
Y-800000D01*
G01X1400000Y-770000D02*
X890000D01*
G01X1400000Y-720000D02*
X890000D01*
G01X1400000Y-620000D02*
X890000D01*
G01Y-550160D02*
Y-500160D01*
G01X1399900Y-500220D02*
X889900D01*
G54D17*
G01X-1930084Y-565000D02*
X-1925000Y-547500D01*
X-1919916Y-565000D01*
G01X-1921747Y-558875D02*
X-1928254D01*
G01X-1923373Y-20667D02*
X-1922560Y-19792D01*
X-1921950Y-18334D01*
X-1921543Y-16291D01*
X-1921950Y-14542D01*
X-1922763Y-13375D01*
X-1924187Y-12500D01*
X-1929677D01*
Y-30000D01*
X-1922967D01*
X-1921543Y-28834D01*
X-1920730Y-27083D01*
X-1920323Y-25042D01*
X-1920730Y-23000D01*
X-1921950Y-21250D01*
X-1923373Y-20667D01*
X-1929677D01*
G01X-1920527Y526041D02*
X-1921747Y526917D01*
X-1923170Y527500D01*
X-1924797D01*
X-1926627Y526625D01*
X-1928050Y525167D01*
X-1929067Y523416D01*
X-1929880Y520500D01*
X-1930084Y517875D01*
X-1929677Y515250D01*
X-1929067Y513500D01*
X-1927847Y511750D01*
X-1926423Y510583D01*
X-1925000Y510000D01*
X-1923577D01*
X-1922153Y510583D01*
X-1920933Y511458D01*
X-1919916Y512624D01*
G01X-1929473Y1050000D02*
Y1067500D01*
X-1925407D01*
X-1923780Y1066625D01*
X-1922560Y1065458D01*
X-1921543Y1063709D01*
X-1920730Y1061666D01*
X-1920527Y1058750D01*
X-1920730Y1055833D01*
X-1921543Y1053791D01*
X-1922560Y1052041D01*
X-1923780Y1050875D01*
X-1925407Y1050000D01*
X-1929473D01*
G01X-1710000Y-830000D02*
X-1708577Y-829708D01*
X-1706950Y-828834D01*
X-1705933Y-827376D01*
X-1705527Y-825333D01*
X-1705933Y-823292D01*
X-1707153Y-821542D01*
X-1708983Y-820667D01*
X-1711017D01*
X-1712237Y-820083D01*
X-1713254Y-818625D01*
X-1713660Y-816584D01*
X-1713050Y-814542D01*
X-1711627Y-813083D01*
X-1710000Y-812500D01*
X-1708373Y-813083D01*
X-1706950Y-814542D01*
X-1706340Y-816584D01*
X-1706747Y-818625D01*
X-1707763Y-820083D01*
X-1708983Y-820667D01*
X-1711017D01*
X-1712847Y-821542D01*
X-1714067Y-823292D01*
X-1714473Y-825333D01*
X-1714067Y-827376D01*
X-1713050Y-828834D01*
X-1711423Y-829708D01*
X-1710000Y-830000D01*
G01Y1315000D02*
X-1708577Y1315292D01*
X-1706950Y1316166D01*
X-1705933Y1317624D01*
X-1705527Y1319667D01*
X-1705933Y1321708D01*
X-1707153Y1323458D01*
X-1708983Y1324333D01*
X-1711017D01*
X-1712237Y1324917D01*
X-1713254Y1326375D01*
X-1713660Y1328416D01*
X-1713050Y1330458D01*
X-1711627Y1331917D01*
X-1710000Y1332500D01*
X-1708373Y1331917D01*
X-1706950Y1330458D01*
X-1706340Y1328416D01*
X-1706747Y1326375D01*
X-1707763Y1324917D01*
X-1708983Y1324333D01*
X-1711017D01*
X-1712847Y1323458D01*
X-1714067Y1321708D01*
X-1714473Y1319667D01*
X-1714067Y1317624D01*
X-1713050Y1316166D01*
X-1711423Y1315292D01*
X-1710000Y1315000D01*
G01X-1265407Y-830000D02*
X-1265000Y-826209D01*
X-1264390Y-823000D01*
X-1263577Y-820083D01*
X-1262560Y-816875D01*
X-1260933Y-812500D01*
X-1269067D01*
G01X-1265407Y1315000D02*
X-1265000Y1318791D01*
X-1264390Y1322000D01*
X-1263577Y1324917D01*
X-1262560Y1328125D01*
X-1260933Y1332500D01*
X-1269067D01*
G01X-838863Y-822709D02*
X-837440Y-820667D01*
X-836220Y-819500D01*
X-834593Y-818917D01*
X-833170Y-819500D01*
X-832153Y-820667D01*
X-831340Y-822417D01*
X-831137Y-824458D01*
X-831340Y-826209D01*
X-832153Y-827959D01*
X-833373Y-829417D01*
X-834797Y-830000D01*
X-836423Y-829417D01*
X-837847Y-827667D01*
X-838660Y-825042D01*
X-838863Y-822125D01*
X-838457Y-818334D01*
X-837847Y-816291D01*
X-836830Y-814250D01*
X-835407Y-812792D01*
X-833983Y-812500D01*
X-832560Y-813083D01*
X-831543Y-814542D01*
G01X-838863Y1322291D02*
X-837440Y1324333D01*
X-836220Y1325500D01*
X-834593Y1326083D01*
X-833170Y1325500D01*
X-832153Y1324333D01*
X-831340Y1322583D01*
X-831137Y1320542D01*
X-831340Y1318791D01*
X-832153Y1317041D01*
X-833373Y1315583D01*
X-834797Y1315000D01*
X-836423Y1315583D01*
X-837847Y1317333D01*
X-838660Y1319958D01*
X-838863Y1322875D01*
X-838457Y1326666D01*
X-837847Y1328709D01*
X-836830Y1330750D01*
X-835407Y1332208D01*
X-833983Y1332500D01*
X-832560Y1331917D01*
X-831543Y1330458D01*
G01X-414473Y-827376D02*
X-413254Y-828834D01*
X-411830Y-829708D01*
X-410000Y-830000D01*
X-408170Y-829417D01*
X-406747Y-828250D01*
X-405730Y-826209D01*
X-405527Y-823875D01*
X-405933Y-821542D01*
X-406950Y-820083D01*
X-408373Y-818917D01*
X-409797Y-818625D01*
X-411220Y-818917D01*
X-413050Y-820083D01*
X-412440Y-812500D01*
X-406950D01*
G01X-414473Y1317624D02*
X-413254Y1316166D01*
X-411830Y1315292D01*
X-410000Y1315000D01*
X-408170Y1315583D01*
X-406747Y1316750D01*
X-405730Y1318791D01*
X-405527Y1321125D01*
X-405933Y1323458D01*
X-406950Y1324917D01*
X-408373Y1326083D01*
X-409797Y1326375D01*
X-411220Y1326083D01*
X-413050Y1324917D01*
X-412440Y1332500D01*
X-406950D01*
G01X22440Y-830000D02*
Y-812500D01*
X14916Y-825042D01*
X25084D01*
G01X22440Y1315000D02*
Y1332500D01*
X14916Y1319958D01*
X25084D01*
G01X435527Y-826500D02*
X436746Y-828542D01*
X438373Y-829708D01*
X440203Y-830000D01*
X441830Y-829708D01*
X443457Y-828250D01*
X444473Y-826500D01*
X444677Y-824750D01*
X444270Y-822709D01*
X442847Y-821250D01*
X441423Y-820667D01*
X439593D01*
G01X441423D02*
X442643Y-819792D01*
X443660Y-818334D01*
X444067Y-816584D01*
X443660Y-814833D01*
X442643Y-813375D01*
X440813Y-812500D01*
X438983Y-812792D01*
X437153Y-813959D01*
G01X435527Y1318500D02*
X436746Y1316458D01*
X438373Y1315292D01*
X440203Y1315000D01*
X441830Y1315292D01*
X443457Y1316750D01*
X444473Y1318500D01*
X444677Y1320250D01*
X444270Y1322291D01*
X442847Y1323750D01*
X441423Y1324333D01*
X439593D01*
G01X441423D02*
X442643Y1325208D01*
X443660Y1326666D01*
X444067Y1328416D01*
X443660Y1330167D01*
X442643Y1331625D01*
X440813Y1332500D01*
X438983Y1332208D01*
X437153Y1331041D01*
G01X866137Y-815417D02*
X867357Y-813667D01*
X868780Y-812792D01*
X870407Y-812500D01*
X872440Y-813083D01*
X873863Y-814542D01*
X874270Y-816291D01*
X874067Y-818042D01*
X873253Y-819500D01*
X869187Y-822417D01*
X867357Y-824458D01*
X866137Y-827376D01*
X865730Y-830000D01*
X874270D01*
G01X866137Y1329583D02*
X867357Y1331333D01*
X868780Y1332208D01*
X870407Y1332500D01*
X872440Y1331917D01*
X873863Y1330458D01*
X874270Y1328709D01*
X874067Y1326958D01*
X873253Y1325500D01*
X869187Y1322583D01*
X867357Y1320542D01*
X866137Y1317624D01*
X865730Y1315000D01*
X874270D01*
G01X931770Y-566600D02*
X923460Y-604100D01*
X933630D01*
X940050Y-578300D01*
X940620Y-604100D01*
X947610D01*
X960900Y-578630D01*
X955140Y-604100D01*
X965430D01*
X973740Y-566600D01*
X959190D01*
X947190Y-590480D01*
X946680Y-566600D01*
X931770D01*
G01X943650Y-603500D02*
X949050Y-592400D01*
X948300Y-591800D01*
X942150Y-603050D01*
X941700Y-600050D01*
X947250Y-591350D01*
X942450Y-600200D01*
X941250Y-597950D01*
X946650Y-590600D01*
X945600Y-570950D01*
X945450Y-568100D01*
X932850D01*
X924900Y-602750D01*
X932400D01*
X939300Y-577250D01*
X940500Y-577100D01*
X941850Y-596000D01*
X945450Y-590000D01*
X944100Y-569450D01*
X933750Y-569600D01*
X926400Y-601400D01*
X931350D01*
X938550Y-575450D01*
X941100Y-575750D01*
X942750Y-592700D01*
X944100Y-589700D01*
X942900Y-570800D01*
X934500Y-570950D01*
X928050Y-600200D01*
X930300Y-600350D01*
X937500Y-574700D01*
X941700D01*
X943200Y-586550D01*
X941700Y-572000D01*
X935250Y-572450D01*
X929550Y-599150D01*
X936450Y-573350D01*
X940800D01*
G01X937500Y-682500D02*
Y-700000D01*
G01X932823Y-682500D02*
X942177D01*
G01X950033Y-700000D02*
Y-682500D01*
X955117D01*
X956743Y-683375D01*
X957760Y-684542D01*
X958167Y-686875D01*
X957760Y-689208D01*
X956540Y-690667D01*
X955117Y-691542D01*
X950033D01*
G01X955117D02*
X958167Y-700000D01*
G01X965616D02*
X970700Y-682500D01*
X975784Y-700000D01*
G01X973953Y-693875D02*
X967446D01*
G01X987300Y-700000D02*
Y-692125D01*
X983233Y-682500D01*
G01X991367D02*
X987300Y-692125D01*
G01X1022127Y-690667D02*
X1022940Y-689792D01*
X1023550Y-688334D01*
X1023957Y-686291D01*
X1023550Y-684542D01*
X1022737Y-683375D01*
X1021313Y-682500D01*
X1015823D01*
Y-700000D01*
X1022533D01*
X1023957Y-698834D01*
X1024770Y-697083D01*
X1025177Y-695042D01*
X1024770Y-693000D01*
X1023550Y-691250D01*
X1022127Y-690667D01*
X1015823D01*
G01X1032016Y-700000D02*
X1037100Y-682500D01*
X1042184Y-700000D01*
G01X1040353Y-693875D02*
X1033846D01*
G01X1058173Y-683959D02*
X1056953Y-683083D01*
X1055530Y-682500D01*
X1053903D01*
X1052073Y-683375D01*
X1050650Y-684833D01*
X1049633Y-686584D01*
X1048820Y-689500D01*
X1048616Y-692125D01*
X1049023Y-694750D01*
X1049633Y-696500D01*
X1050853Y-698250D01*
X1052277Y-699417D01*
X1053700Y-700000D01*
X1055123D01*
X1056547Y-699417D01*
X1057767Y-698542D01*
X1058784Y-697376D01*
G01X1065827Y-700000D02*
Y-682500D01*
G01X1073553D02*
X1065827Y-693292D01*
G01X1074773Y-700000D02*
X1069283Y-688334D01*
G01X1082833Y-700000D02*
Y-682500D01*
X1087713D01*
X1089340Y-683375D01*
X1090560Y-685417D01*
X1090967Y-687750D01*
X1090560Y-690083D01*
X1089543Y-691833D01*
X1087713Y-692709D01*
X1082833D01*
G01X1099433Y-682500D02*
Y-700000D01*
X1107567D01*
G01X1115016D02*
X1120100Y-682500D01*
X1125184Y-700000D01*
G01X1123353Y-693875D02*
X1116846D01*
G01X1132023Y-700000D02*
Y-682500D01*
X1141377Y-700000D01*
Y-682500D01*
G01X1157367Y-700000D02*
X1149233D01*
Y-682500D01*
X1157367D01*
G01X1154113Y-690958D02*
X1149233D01*
G01X1182637Y-700000D02*
Y-682500D01*
X1190363D01*
G01X1187517Y-690958D02*
X1182637D01*
G01X1198016Y-700000D02*
X1203100Y-682500D01*
X1208184Y-700000D01*
G01X1206353Y-693875D02*
X1199846D01*
G01X1221327Y-690667D02*
X1222140Y-689792D01*
X1222750Y-688334D01*
X1223157Y-686291D01*
X1222750Y-684542D01*
X1221937Y-683375D01*
X1220513Y-682500D01*
X1215023D01*
Y-700000D01*
X1221733D01*
X1223157Y-698834D01*
X1223970Y-697083D01*
X1224377Y-695042D01*
X1223970Y-693000D01*
X1222750Y-691250D01*
X1221327Y-690667D01*
X1215023D01*
G01X1254527D02*
X1255340Y-689792D01*
X1255950Y-688334D01*
X1256357Y-686291D01*
X1255950Y-684542D01*
X1255137Y-683375D01*
X1253713Y-682500D01*
X1248223D01*
Y-700000D01*
X1254933D01*
X1256357Y-698834D01*
X1257170Y-697083D01*
X1257577Y-695042D01*
X1257170Y-693000D01*
X1255950Y-691250D01*
X1254527Y-690667D01*
X1248223D01*
G01X1285083Y-705833D02*
X1283050Y-702917D01*
X1282033Y-700000D01*
Y-688334D01*
X1283050Y-685417D01*
X1285083Y-682500D01*
G01X1302700Y-700000D02*
X1301073Y-699708D01*
X1299650Y-698542D01*
X1298430Y-696792D01*
X1297616Y-694750D01*
X1297210Y-692417D01*
Y-690083D01*
X1297616Y-687750D01*
X1298430Y-685708D01*
X1299650Y-683959D01*
X1301073Y-682792D01*
X1302700Y-682500D01*
X1304327Y-682792D01*
X1305750Y-683959D01*
X1306970Y-685708D01*
X1307784Y-687750D01*
X1308190Y-690083D01*
Y-692417D01*
X1307784Y-694750D01*
X1306970Y-696792D01*
X1305750Y-698542D01*
X1304327Y-699708D01*
X1302700Y-700000D01*
G01X1315030Y-697667D02*
X1316657Y-699125D01*
X1318487Y-700000D01*
X1320113D01*
X1321740Y-699125D01*
X1322960Y-697667D01*
X1323570Y-695625D01*
X1323163Y-693584D01*
X1322147Y-691833D01*
X1320317Y-690667D01*
X1317877Y-690083D01*
X1316453Y-688917D01*
X1315843Y-686875D01*
X1316250Y-684833D01*
X1317267Y-683375D01*
X1318690Y-682500D01*
X1320113D01*
X1321537Y-683083D01*
X1322757Y-684542D01*
G01X1331833Y-700000D02*
Y-682500D01*
X1336713D01*
X1338340Y-683375D01*
X1339560Y-685417D01*
X1339967Y-687750D01*
X1339560Y-690083D01*
X1338543Y-691833D01*
X1336713Y-692709D01*
X1331833D01*
G01X1353517Y-705833D02*
X1355550Y-702917D01*
X1356567Y-700000D01*
Y-688334D01*
X1355550Y-685417D01*
X1353517Y-682500D01*
G01X972300Y-567500D02*
X964350Y-602600D01*
X956850Y-602750D01*
X957000Y-601100D01*
X963300Y-601400D01*
X964050Y-599750D01*
X957150Y-599900D01*
X957450Y-598250D01*
X964050D01*
X964800Y-597050D01*
X958050Y-596900D01*
X958200Y-595400D01*
X964950D01*
X965400Y-593900D01*
X958350Y-594050D01*
X958650Y-592700D01*
X965550Y-592550D01*
X966000Y-591050D01*
X958950Y-591200D01*
X959400Y-589550D01*
X966450Y-589700D01*
X967050Y-587900D01*
X958950Y-588500D01*
X960000Y-587000D01*
X966750Y-587150D01*
X967500Y-585800D01*
X960150D01*
X960600Y-584150D01*
X967350Y-584450D01*
X967800Y-583100D01*
X961200D01*
X961350Y-582050D01*
X967800D01*
X968550Y-581000D01*
X961500Y-580850D01*
X961650Y-579950D01*
X968400Y-580100D01*
X968700Y-579050D01*
X962250Y-578750D01*
X961350Y-578000D01*
X969300D01*
X969750Y-576500D01*
X971100Y-567950D01*
X960000D01*
X959250Y-569300D01*
X969600D01*
X969300Y-570800D01*
X958500Y-570650D01*
X957900Y-571850D01*
X969150Y-572000D01*
X969300Y-573500D01*
X957150Y-573050D01*
X956700Y-574100D01*
X969000Y-574700D01*
X968550Y-576200D01*
X956100Y-575450D01*
X967650Y-577100D01*
X955500Y-576650D01*
X960750Y-577850D01*
X955050Y-577700D01*
X948450Y-591050D01*
X952200Y-592850D01*
X959250Y-579050D01*
X955650Y-578900D01*
X950100Y-591050D01*
X951750Y-591500D01*
X957000Y-579950D01*
G01X951750Y-593600D02*
X946800Y-602750D01*
G01X950550Y-592700D02*
X945000Y-603650D01*
G01X975870Y-576800D02*
X969690Y-604100D01*
X978930D01*
X984840Y-576800D01*
X975870D01*
G01X976800Y-577850D02*
X971100Y-602900D01*
X977700Y-602750D01*
X983550Y-578150D01*
X981750D01*
X976650Y-601250D01*
X972600Y-601700D01*
X977850Y-578000D01*
X980400Y-577850D01*
X975600Y-600050D01*
X974250Y-600350D01*
X978900Y-579050D01*
G01X1006050Y-586100D02*
Y-585380D01*
X1005540Y-583610D01*
X1004550Y-582050D01*
X1003200Y-581600D01*
X1001130D01*
X998910Y-582980D01*
X996960Y-584750D01*
X995640Y-586580D01*
X994680Y-589130D01*
X994050Y-591320D01*
X993750Y-593840D01*
Y-595280D01*
X994470Y-597080D01*
X996330Y-599300D01*
X1000260D01*
X1002240Y-597500D01*
X1003530Y-595550D01*
X1003590Y-595400D01*
X1013730D01*
X1013640Y-595610D01*
X1012740Y-597260D01*
X1012470Y-597950D01*
X1011390Y-599300D01*
X1010250Y-600440D01*
X1008510Y-601880D01*
X1006770Y-603050D01*
X1005390Y-603860D01*
X1001430Y-605000D01*
X993540D01*
X992190Y-604730D01*
X989670Y-603890D01*
X988650Y-603110D01*
X986640Y-601100D01*
X985830Y-600020D01*
X985590Y-599570D01*
X985020Y-597740D01*
X984750Y-596210D01*
Y-590420D01*
X985590Y-587060D01*
X986430Y-585620D01*
X987030Y-584420D01*
X987870Y-583070D01*
X990450Y-580460D01*
X991890Y-579320D01*
X993000Y-578480D01*
X995640Y-577310D01*
X996750Y-576740D01*
X997800Y-576470D01*
X1000110Y-576200D01*
X1004520D01*
X1007970Y-576500D01*
X1009590Y-577040D01*
X1010130Y-577280D01*
X1012110Y-578420D01*
X1012590Y-578900D01*
X1014270Y-580880D01*
X1015410Y-583700D01*
X1015650Y-584450D01*
Y-586100D01*
X1006050D01*
G01X1011900Y-596600D02*
X1008300Y-601100D01*
X1001250Y-603800D01*
X992850Y-603650D01*
X989100Y-601700D01*
X987300Y-599750D01*
X986400Y-597500D01*
X985950Y-594650D01*
X986250Y-590150D01*
X987900Y-585050D01*
X990750Y-581900D01*
X995700Y-578600D01*
X1001850Y-577550D01*
X1007550Y-577850D01*
X1011900Y-580100D01*
X1014750Y-584600D01*
X1007250Y-584750D01*
X1005900Y-582050D01*
X1003350Y-580400D01*
X1000800Y-580250D01*
X998100Y-581600D01*
X995550Y-584300D01*
X993300Y-588650D01*
X992400Y-593150D01*
X993750Y-598850D01*
X995700Y-600500D01*
X998550Y-600650D01*
X1001550Y-600350D01*
X1004250Y-596900D01*
X1010550Y-596750D01*
X1007250Y-600050D01*
X1003650Y-601250D01*
X1000200Y-602450D01*
X992550Y-602300D01*
X988650Y-599150D01*
X987300Y-594350D01*
X987750Y-590900D01*
X988950Y-586250D01*
X991050Y-583550D01*
X996300Y-579800D01*
X1002900Y-578750D01*
X1009050Y-579650D01*
X1012800Y-583400D01*
X1007850D01*
X1004550Y-580100D01*
X1010850Y-581450D01*
X1011750Y-582350D01*
X1007100Y-581750D01*
G01X999150Y-580250D02*
X995550Y-581900D01*
X992250Y-584600D01*
X990150Y-587150D01*
X988800Y-594650D01*
X989700Y-598250D01*
X994500Y-601700D01*
X1001400Y-601550D01*
X1008600Y-597650D01*
X1002900Y-598850D01*
X994350Y-600350D01*
X992850Y-599300D01*
X991950Y-596750D01*
X991350Y-593900D01*
X991950Y-589400D01*
X995250Y-583100D01*
X990900Y-588800D01*
X990600Y-591800D01*
X990150Y-594800D01*
X991500Y-598100D01*
G01X977970Y-566600D02*
X977010Y-571100D01*
X986430D01*
X987390Y-566600D01*
X977970D01*
G01X978600Y-568400D02*
X985950Y-568250D01*
X985500Y-569750D01*
X978450D01*
G01X1034910Y-584390D02*
X1033740Y-584630D01*
X1032390Y-584960D01*
X1030680Y-585980D01*
X1029450Y-587210D01*
X1028070Y-588260D01*
X1027740Y-589280D01*
X1026840Y-590480D01*
X1026510Y-591470D01*
X1025910Y-592670D01*
X1025580Y-593690D01*
X1025280Y-595790D01*
X1024980Y-596660D01*
X1024680Y-598160D01*
X1024380Y-599060D01*
X1023450Y-602720D01*
X1023270Y-604100D01*
X1014540D01*
X1015620Y-599840D01*
X1015920Y-598910D01*
X1016250Y-596450D01*
X1016520Y-595040D01*
X1016820Y-594140D01*
X1017120Y-592640D01*
X1017420Y-591740D01*
X1018050Y-589250D01*
X1018320Y-586580D01*
X1018620Y-585740D01*
X1018920Y-584240D01*
X1019220Y-583340D01*
X1020420Y-578450D01*
X1020630Y-576800D01*
X1029180D01*
X1028850Y-577490D01*
Y-581360D01*
X1031250Y-578990D01*
X1032330Y-578180D01*
X1033980Y-577340D01*
X1035660Y-576770D01*
X1037310Y-576500D01*
X1038420D01*
X1037310Y-580910D01*
X1034910Y-584390D01*
G01X1035750Y-582050D02*
X1020750Y-582200D01*
X1020450Y-583400D01*
X1034550Y-583250D01*
X1031250Y-584450D01*
X1019700Y-584750D01*
X1019400Y-586100D01*
X1029600Y-585950D01*
X1027800Y-587450D01*
X1019250Y-587300D01*
X1019100Y-588650D01*
X1027050Y-588800D01*
X1025850Y-590450D01*
X1018500Y-590150D01*
Y-591500D01*
X1025100Y-591800D01*
X1024800Y-593300D01*
X1018050Y-593000D01*
X1017750Y-594350D01*
X1024500Y-594650D01*
X1024200Y-596300D01*
X1017600Y-595850D01*
X1017150Y-596900D01*
X1023750Y-597500D01*
X1023450Y-599300D01*
X1016850Y-598250D01*
X1016700Y-599300D01*
X1023150Y-600050D01*
X1022850Y-601250D01*
X1016550Y-600800D01*
X1015950Y-601700D01*
X1022850Y-602300D01*
X1022700Y-602900D01*
X1015800Y-603050D01*
G01X1021350Y-578000D02*
X1027650Y-578150D01*
X1027800Y-579650D01*
X1021350Y-579500D01*
X1021050Y-581000D01*
X1036350Y-580850D01*
X1037100Y-577850D01*
X1031850Y-579650D01*
X1035750D01*
G01X1037190Y-583940D02*
X1039980Y-580460D01*
X1041090Y-579620D01*
X1042500Y-578510D01*
X1043280Y-578240D01*
X1044090Y-577850D01*
X1044390Y-577550D01*
X1044780Y-577340D01*
X1045680Y-577040D01*
X1046280Y-576740D01*
X1047060Y-576470D01*
X1049100Y-576200D01*
X1050840Y-575900D01*
X1054590D01*
X1058640Y-576470D01*
X1059420Y-576740D01*
X1060470Y-577280D01*
X1061730Y-578210D01*
X1062570Y-578480D01*
X1062690Y-578600D01*
X1064700Y-580910D01*
X1065510Y-582530D01*
X1065810Y-583400D01*
X1066350Y-584780D01*
Y-589850D01*
X1065870Y-591290D01*
X1064550Y-591530D01*
X1063920Y-591860D01*
X1063020Y-592160D01*
X1061820Y-592760D01*
X1060920Y-593060D01*
X1060350Y-593330D01*
X1058850Y-593630D01*
X1058220Y-593960D01*
X1057260Y-594290D01*
X1054230Y-596300D01*
X1064010D01*
X1063170Y-597950D01*
X1062660Y-598730D01*
X1059780Y-601580D01*
X1056090Y-603860D01*
X1052130Y-605000D01*
X1042800D01*
X1042050Y-604760D01*
X1039170Y-603590D01*
X1038420Y-603110D01*
X1036140Y-600830D01*
X1035660Y-600110D01*
X1035360Y-599240D01*
X1034790Y-598220D01*
X1034520Y-596930D01*
X1034250Y-596270D01*
Y-590720D01*
X1034520Y-589640D01*
X1034790Y-588830D01*
X1035090Y-588230D01*
X1035420Y-587240D01*
X1035660Y-586250D01*
X1038180Y-583730D01*
X1037190Y-583940D01*
G01X1057050Y-592850D02*
X1065300Y-589850D01*
X1065150Y-584900D01*
X1063800Y-581750D01*
X1060800Y-579200D01*
X1056000Y-577400D01*
X1051800Y-577100D01*
X1046550Y-577700D01*
X1041600Y-580400D01*
X1038900Y-584000D01*
X1036650Y-587150D01*
X1035600Y-591650D01*
X1035750Y-596900D01*
X1037850Y-601100D01*
X1041600Y-603200D01*
X1047450Y-603950D01*
X1054500Y-603350D01*
X1058700Y-600950D01*
X1061100Y-598400D01*
X1062000Y-597500D01*
X1054800Y-597800D01*
X1052550Y-599900D01*
X1059150Y-598850D01*
X1055550Y-600950D01*
X1051200Y-600350D01*
X1055100Y-602150D01*
X1051500D01*
X1050450Y-601100D01*
X1050900Y-602750D01*
X1049100Y-601100D01*
X1046700D01*
X1049850Y-602900D01*
X1045200Y-602300D01*
X1040850Y-601400D01*
X1038750Y-599600D01*
X1037100Y-596150D01*
X1036950Y-592250D01*
X1037400Y-588800D01*
X1038900Y-585650D01*
X1041600Y-582500D01*
X1043850Y-580550D01*
X1047150Y-579050D01*
X1052700Y-578300D01*
X1056600Y-579200D01*
X1060500Y-580850D01*
X1062750Y-582500D01*
X1064100Y-586100D01*
X1064250Y-589100D01*
X1057800Y-591050D01*
X1058100Y-589250D01*
X1063350Y-587900D01*
X1063050Y-586250D01*
X1058250Y-587750D01*
X1058100Y-585800D01*
X1062600Y-585200D01*
X1062150Y-583550D01*
X1058400Y-584300D01*
X1057650Y-583100D01*
X1061100Y-582350D01*
X1060350Y-581600D01*
X1056900Y-581750D01*
X1057800Y-581000D01*
X1055100Y-580250D01*
X1052400Y-579350D01*
X1049700Y-579500D01*
X1046700Y-580400D01*
X1044150Y-581750D01*
X1040250Y-586550D01*
X1038300Y-590450D01*
Y-594800D01*
X1039950Y-598700D01*
X1042950Y-601250D01*
X1046100Y-601100D01*
X1044150Y-598700D01*
X1042650Y-596300D01*
Y-591500D01*
X1044150Y-586700D01*
X1046250Y-583100D01*
X1049850Y-580550D01*
X1044000Y-583250D01*
X1043850Y-585500D01*
X1042950Y-585050D01*
X1040550Y-588650D01*
X1039500Y-592250D01*
X1039950Y-595400D01*
X1041750Y-599150D01*
X1044450Y-600350D01*
X1042050Y-596900D01*
X1041300Y-594650D01*
X1043100Y-586550D01*
X1040400Y-593450D01*
G01X1035600Y-584600D02*
X1037850Y-581750D01*
G01X1048350Y-599900D02*
X1049910D01*
X1050330Y-599480D01*
X1051200Y-599210D01*
X1052880Y-597860D01*
X1054800Y-595610D01*
X1055430Y-594350D01*
X1055730Y-593900D01*
X1056060Y-593240D01*
X1056690Y-591830D01*
X1057020Y-590840D01*
X1057350Y-589520D01*
Y-585080D01*
X1056960Y-583550D01*
X1056510Y-583100D01*
X1054950Y-581210D01*
X1054170Y-580700D01*
X1050990D01*
X1050450Y-581210D01*
X1048050Y-583010D01*
X1047360Y-583730D01*
X1046730Y-584660D01*
X1045410Y-586280D01*
X1045110Y-587570D01*
X1044510Y-588740D01*
X1043850Y-590750D01*
Y-596210D01*
X1044570Y-597650D01*
X1045290Y-598760D01*
X1047030Y-599900D01*
X1048350D01*
G01X1065330Y-596300D02*
X1075350D01*
Y-597860D01*
X1075800Y-598340D01*
X1076220Y-599150D01*
X1077270Y-599480D01*
X1077510Y-599750D01*
X1078320Y-600140D01*
X1079400Y-600500D01*
X1082460D01*
X1085190Y-599150D01*
X1085850Y-598460D01*
Y-597920D01*
X1086240Y-597320D01*
X1085430Y-594860D01*
X1083840Y-593660D01*
X1082160Y-593330D01*
X1077390Y-592130D01*
X1075590Y-591530D01*
X1074600Y-591290D01*
X1074390Y-591050D01*
X1073190Y-590450D01*
X1072290Y-589550D01*
X1071690Y-589250D01*
X1071300Y-588860D01*
X1071000Y-588260D01*
X1070730Y-588020D01*
X1070250Y-586550D01*
Y-582950D01*
X1070520Y-582140D01*
X1070790Y-581000D01*
X1071000Y-580640D01*
X1072500Y-579140D01*
X1072710Y-578660D01*
X1077120Y-576470D01*
X1080570Y-575900D01*
X1082910Y-575600D01*
X1085220D01*
X1088130Y-575900D01*
X1091640Y-576470D01*
X1093320Y-577040D01*
X1093800Y-577280D01*
X1095480Y-578390D01*
X1096260Y-579200D01*
X1097070Y-580280D01*
X1097250Y-580610D01*
Y-583700D01*
X1088250D01*
Y-582050D01*
X1086630Y-580820D01*
X1085760Y-580400D01*
X1082430D01*
X1081080Y-580790D01*
X1079970Y-581660D01*
X1079490Y-583100D01*
X1079910Y-584330D01*
X1080390Y-585260D01*
X1083210Y-586670D01*
X1086900Y-587000D01*
X1088010Y-587270D01*
X1088850Y-587540D01*
X1091250Y-588440D01*
X1093020Y-589040D01*
X1093410Y-589250D01*
X1095270Y-591080D01*
X1095780Y-592640D01*
X1096050Y-593990D01*
Y-595880D01*
X1095210Y-599300D01*
X1095000Y-599690D01*
X1093290Y-601700D01*
X1093080Y-601910D01*
X1091100Y-603320D01*
X1090020Y-603860D01*
X1086600Y-605000D01*
X1073640D01*
X1072260Y-604730D01*
X1071120Y-604430D01*
X1069710Y-603890D01*
X1068660Y-603350D01*
X1066950Y-601940D01*
X1066230Y-601220D01*
X1065990Y-600470D01*
X1065720Y-599900D01*
X1065450Y-598730D01*
X1065330Y-596300D01*
G01X1063350D02*
X1066800D01*
G01X1066350Y-597350D02*
X1074150Y-597800D01*
X1076250Y-600350D01*
X1080900Y-601700D01*
X1084500Y-601250D01*
X1087050Y-599150D01*
X1087500Y-596600D01*
X1086750Y-594800D01*
X1085550Y-593150D01*
X1083300Y-592250D01*
X1081050Y-591500D01*
X1078050Y-590750D01*
X1074150Y-589250D01*
X1072350Y-588050D01*
X1071300Y-584750D01*
X1071750Y-581750D01*
X1073100Y-579800D01*
X1076250Y-578300D01*
X1079100Y-577400D01*
X1083150Y-577100D01*
X1086150Y-576950D01*
X1090650Y-577700D01*
X1093500Y-578750D01*
X1095450Y-580250D01*
X1096050Y-582350D01*
X1089600Y-582500D01*
X1088850Y-581450D01*
X1094550Y-581000D01*
X1094100Y-579950D01*
X1088700Y-580550D01*
X1092000Y-579350D01*
X1087350Y-579800D01*
X1090350Y-578600D01*
X1085850Y-579200D01*
X1087200Y-578150D01*
X1081350Y-578450D01*
X1085100Y-579200D01*
X1080900Y-579800D01*
X1080600Y-578750D01*
X1074150Y-580850D01*
X1080000Y-580400D01*
X1073100Y-581900D01*
X1072800Y-585500D01*
X1074450Y-588650D01*
X1079400Y-589700D01*
X1084200Y-591350D01*
X1087800Y-594200D01*
X1088550Y-599000D01*
X1086150Y-602150D01*
X1080750Y-603200D01*
X1077600Y-602150D01*
X1072800Y-599000D01*
X1067100Y-598550D01*
X1067850Y-600950D01*
X1068450Y-600200D01*
X1072050Y-600500D01*
X1069050Y-601700D01*
X1072950Y-600650D01*
X1080000Y-603500D01*
X1072350D01*
X1069500Y-602600D01*
X1075200Y-602450D01*
X1081950Y-603800D01*
X1087500Y-603650D01*
X1091250Y-601700D01*
X1093950Y-599150D01*
X1094550Y-594200D01*
X1093800Y-591200D01*
X1087800Y-588650D01*
X1083600Y-587600D01*
X1080900Y-587000D01*
X1078800Y-585500D01*
X1078500Y-581600D01*
X1073850Y-582950D01*
X1075200Y-587300D01*
X1078500Y-588350D01*
X1083000Y-589400D01*
X1086600Y-590900D01*
X1088700Y-593000D01*
X1089450Y-596000D01*
X1089750Y-598400D01*
X1087200Y-602450D01*
X1090800Y-600350D01*
X1093050Y-598250D01*
X1090050Y-599600D01*
X1093500Y-596450D01*
X1093200Y-592400D01*
X1081950Y-587300D01*
X1079700Y-587600D01*
X1076100Y-585950D01*
X1075200Y-583700D01*
X1077300Y-582950D01*
X1076100Y-584750D01*
X1078050Y-583850D01*
X1077600Y-585350D01*
X1090950Y-593000D01*
X1092150Y-593900D01*
X1092450Y-595850D01*
X1090800Y-597500D01*
X1089300Y-592550D01*
X1092150Y-596450D01*
G01X1117050Y-579800D02*
X1117350Y-576650D01*
X1123200Y-577700D01*
X1126950Y-580100D01*
X1129350Y-584450D01*
X1129650Y-591050D01*
X1126650Y-597350D01*
X1123050Y-601100D01*
X1117500Y-603500D01*
X1106550Y-603200D01*
X1100550Y-596300D01*
X1100400Y-590150D01*
X1102200Y-584900D01*
X1108500Y-579050D01*
X1113000Y-577550D01*
X1119600Y-577700D01*
X1126500Y-581300D01*
X1128450Y-586550D01*
X1128000Y-591800D01*
X1125900Y-596150D01*
X1122450Y-599750D01*
X1117650Y-602150D01*
X1110450Y-602750D01*
X1107150Y-603650D01*
X1103550Y-602600D01*
X1100100Y-597200D01*
X1108350Y-602150D01*
X1114800Y-601550D01*
X1120200Y-599300D01*
X1123200Y-596900D01*
X1126050Y-593000D01*
X1127250Y-588350D01*
X1126650Y-583400D01*
X1120500Y-579350D01*
X1117950Y-579050D01*
X1120500Y-581000D01*
X1123350Y-582950D01*
X1125300Y-584600D01*
X1125900Y-587900D01*
X1125600Y-591650D01*
X1123800Y-594500D01*
X1121400Y-597050D01*
X1118250Y-598550D01*
X1115700Y-599300D01*
X1113750Y-600350D01*
X1111050Y-600650D01*
X1107900Y-600500D01*
X1102500Y-597200D01*
X1101600Y-592850D01*
X1101450Y-588800D01*
X1103100Y-585050D01*
X1105950Y-582050D01*
X1110150Y-579650D01*
X1114350Y-578750D01*
X1116600D01*
X1115700Y-579500D01*
X1111050Y-580250D01*
X1108050Y-582500D01*
X1105650Y-584150D01*
X1104150Y-586400D01*
X1102800Y-589700D01*
X1102950Y-593600D01*
X1103700Y-596900D01*
X1105650Y-598550D01*
X1109550Y-599600D01*
X1107450Y-597200D01*
X1107300Y-592100D01*
X1108050Y-587600D01*
X1114200Y-580550D01*
X1110600Y-581600D01*
X1106400Y-585200D01*
X1104300Y-589550D01*
Y-594050D01*
X1104900Y-597200D01*
X1106550Y-597800D01*
X1105350Y-592850D01*
X1106100Y-588350D01*
X1108950Y-583250D01*
X1112100Y-581450D01*
X1108050Y-585800D01*
X1105950Y-594350D01*
G01X1114740Y-575900D02*
X1120260D01*
X1123110Y-576470D01*
X1123890Y-576710D01*
X1125930Y-577880D01*
X1127010Y-578450D01*
X1127970Y-579380D01*
X1128270Y-580280D01*
X1129200Y-581240D01*
X1129500Y-581840D01*
X1129740Y-582050D01*
X1129950Y-582920D01*
Y-583460D01*
X1130400Y-583940D01*
X1130580Y-584270D01*
X1130850Y-585860D01*
Y-589610D01*
X1130580Y-590990D01*
X1130280Y-592220D01*
X1129980Y-593930D01*
X1129170Y-595520D01*
X1128240Y-596780D01*
X1127940Y-597650D01*
X1126890Y-599000D01*
X1124280Y-601610D01*
X1123500Y-602120D01*
X1122870Y-602420D01*
X1121670Y-603320D01*
X1120620Y-603860D01*
X1116930Y-605000D01*
X1107600D01*
X1104210Y-603860D01*
X1103760Y-603650D01*
X1101750Y-601940D01*
X1101270Y-601430D01*
X1100430Y-600050D01*
X1099290Y-598040D01*
X1099050Y-597350D01*
Y-590120D01*
X1099320Y-589070D01*
X1099890Y-587600D01*
X1100190Y-586730D01*
X1101030Y-584750D01*
X1102740Y-582500D01*
X1105650Y-579590D01*
X1106730Y-578780D01*
X1107900Y-578180D01*
X1109340Y-577310D01*
X1110750Y-576740D01*
X1111590Y-576470D01*
X1114740Y-575900D01*
G01X1119300Y-581120D02*
X1120500Y-581930D01*
X1120860Y-583010D01*
X1121490Y-583940D01*
X1121850Y-585710D01*
Y-588890D01*
X1121520Y-590540D01*
X1120920Y-592340D01*
X1120590Y-593630D01*
X1120200Y-594440D01*
X1119540Y-595070D01*
X1118940Y-595970D01*
X1116060Y-598880D01*
X1114470Y-599510D01*
X1113870Y-599900D01*
X1111920D01*
X1110990Y-599510D01*
X1110210Y-599150D01*
X1109460Y-598370D01*
X1108770Y-597350D01*
X1108350Y-596510D01*
Y-590630D01*
X1108680Y-589430D01*
X1109370Y-587420D01*
X1109760Y-587030D01*
X1110570Y-585800D01*
X1111200Y-584510D01*
X1112250Y-583460D01*
X1112820Y-583040D01*
X1113420Y-582290D01*
X1115100Y-581120D01*
X1115940Y-580700D01*
X1118460D01*
X1119300Y-581120D01*
G01X1131630Y-581900D02*
X1132890Y-576800D01*
X1138650D01*
Y-575420D01*
X1138920Y-574340D01*
X1139490Y-572630D01*
X1140090Y-571430D01*
X1140390Y-570530D01*
X1140600Y-570140D01*
X1142490Y-568250D01*
X1142880Y-568040D01*
X1145130Y-567470D01*
X1146840Y-567200D01*
X1151790D01*
X1152840Y-567350D01*
X1152780Y-567560D01*
X1152480Y-568790D01*
X1152180Y-570170D01*
X1152000Y-571100D01*
X1150890D01*
X1150410Y-571550D01*
X1149210Y-572150D01*
X1148670Y-572720D01*
X1148280Y-573860D01*
X1147560Y-576800D01*
X1154970D01*
X1155420Y-575870D01*
X1155750Y-573350D01*
X1156590Y-569900D01*
X1165110D01*
X1165080Y-570020D01*
X1164780Y-572420D01*
X1164210Y-574670D01*
X1163850Y-575390D01*
Y-576800D01*
X1168800D01*
X1168680Y-577160D01*
X1168380Y-578660D01*
X1168080Y-579560D01*
X1167780Y-581090D01*
X1167570Y-581900D01*
X1162350D01*
Y-583250D01*
X1162080Y-584060D01*
X1161780Y-585560D01*
X1161480Y-586460D01*
X1161180Y-587690D01*
X1160850Y-589250D01*
X1160580Y-591590D01*
X1160280Y-592460D01*
X1159980Y-593960D01*
X1159680Y-594860D01*
X1159440Y-595850D01*
X1159050Y-596240D01*
Y-597950D01*
X1160550Y-599090D01*
X1161090Y-599600D01*
X1163670D01*
X1162980Y-602420D01*
X1162680Y-604430D01*
Y-604460D01*
X1159920Y-604700D01*
X1156710D01*
X1154430Y-604430D01*
X1152210Y-603860D01*
X1151040Y-603170D01*
X1150560Y-602240D01*
X1150350Y-601670D01*
Y-598490D01*
X1150620Y-597140D01*
X1150950Y-596210D01*
X1151250Y-593510D01*
X1151520Y-592640D01*
X1151820Y-591140D01*
X1152120Y-590240D01*
X1152420Y-588740D01*
X1152720Y-587840D01*
X1153020Y-586340D01*
X1153320Y-585410D01*
X1153770Y-581900D01*
X1146150D01*
Y-583580D01*
X1145580Y-585920D01*
X1145280Y-588320D01*
X1144080Y-593060D01*
X1143780Y-593960D01*
X1143450Y-595550D01*
X1143180Y-597890D01*
X1142880Y-598760D01*
X1142580Y-600290D01*
X1142280Y-601460D01*
X1141980Y-602360D01*
X1141680Y-603860D01*
X1141590Y-604100D01*
X1132290D01*
X1133550Y-599180D01*
X1133850Y-596780D01*
X1134120Y-595640D01*
X1134420Y-594740D01*
X1134720Y-593240D01*
X1135020Y-592340D01*
X1135320Y-590840D01*
X1135620Y-589940D01*
X1135950Y-588350D01*
X1136250Y-586280D01*
X1136790Y-584000D01*
X1137150Y-583310D01*
Y-581900D01*
X1131630D01*
G01X1118550Y-597350D02*
X1122900Y-593900D01*
X1125150Y-588800D01*
X1124400Y-585050D01*
X1122150Y-583100D01*
X1123800Y-588500D01*
X1122900Y-588650D01*
X1124100Y-590000D01*
X1122450D01*
X1122900Y-591200D01*
X1121700Y-593450D01*
G01X1151100Y-568100D02*
X1150800Y-570200D01*
X1148100Y-571850D01*
X1146300Y-577400D01*
X1155450Y-578000D01*
X1157550Y-571400D01*
X1163400Y-571250D01*
X1162650Y-576350D01*
X1165200Y-578150D01*
X1167150Y-578450D01*
X1166700Y-580550D01*
X1161000Y-580850D01*
X1158300Y-596600D01*
X1160400Y-600800D01*
X1161900D01*
X1161600Y-603200D01*
X1156350Y-603350D01*
X1151850Y-602450D01*
X1151700Y-599000D01*
X1152150Y-593900D01*
X1154400Y-585350D01*
X1155300Y-581450D01*
X1155750Y-580850D01*
X1153500Y-580550D01*
X1146600D01*
X1144800Y-580700D01*
X1140600Y-603050D01*
X1134000Y-602750D01*
X1138350Y-582350D01*
X1138650Y-580850D01*
X1132950D01*
X1133850Y-578150D01*
X1138650Y-577850D01*
X1138200Y-579800D01*
X1134600Y-579500D01*
X1166250D01*
G01X1145550Y-581900D02*
X1143900Y-590450D01*
G01X1138800Y-580550D02*
X1143900D01*
X1139550Y-602300D01*
X1134900Y-601700D01*
X1139850Y-581450D01*
X1142400Y-581900D01*
X1138350Y-601100D01*
X1136250D01*
X1140900Y-582800D01*
X1137600Y-600500D01*
G01X1149750Y-567950D02*
X1149300Y-569750D01*
X1148250Y-568400D01*
X1143000Y-569300D01*
X1141350Y-571700D01*
X1139850Y-575900D01*
X1139700Y-578150D01*
X1151100Y-578450D01*
G01X1148400Y-569900D02*
X1145100Y-576950D01*
X1141050D01*
X1143900Y-570200D01*
X1147650Y-569750D01*
X1144200Y-575750D01*
X1143000Y-575900D01*
X1145250Y-571250D01*
G01X1158000Y-572600D02*
X1162050D01*
X1164000Y-578750D01*
X1161750Y-573650D01*
X1162350Y-579200D01*
X1156800Y-602450D01*
X1160700Y-602150D01*
G01X1159350Y-602000D02*
X1158900Y-599600D01*
X1158150Y-601550D01*
X1153200D01*
Y-594650D01*
X1158000Y-573800D01*
X1160250Y-573950D01*
X1161000Y-578300D01*
X1155900Y-601100D01*
X1154550Y-600650D01*
X1154700Y-593900D01*
X1158900Y-575000D01*
X1159950Y-578000D01*
X1155450Y-599150D01*
X1156950Y-584900D01*
G01X1245000Y-830000D02*
Y-812500D01*
X1242560Y-816000D01*
G01Y-830000D02*
X1247440D01*
G01X1245000Y1315000D02*
Y1332500D01*
X1242560Y1329000D01*
G01Y1315000D02*
X1247440D01*
G01X1419916Y-565000D02*
X1425000Y-547500D01*
X1430084Y-565000D01*
G01X1428253Y-558875D02*
X1421746D01*
G01X1426627Y-20667D02*
X1427440Y-19792D01*
X1428050Y-18334D01*
X1428457Y-16291D01*
X1428050Y-14542D01*
X1427237Y-13375D01*
X1425813Y-12500D01*
X1420323D01*
Y-30000D01*
X1427033D01*
X1428457Y-28834D01*
X1429270Y-27083D01*
X1429677Y-25042D01*
X1429270Y-23000D01*
X1428050Y-21250D01*
X1426627Y-20667D01*
X1420323D01*
G01X1429473Y526041D02*
X1428253Y526917D01*
X1426830Y527500D01*
X1425203D01*
X1423373Y526625D01*
X1421950Y525167D01*
X1420933Y523416D01*
X1420120Y520500D01*
X1419916Y517875D01*
X1420323Y515250D01*
X1420933Y513500D01*
X1422153Y511750D01*
X1423577Y510583D01*
X1425000Y510000D01*
X1426423D01*
X1427847Y510583D01*
X1429067Y511458D01*
X1430084Y512624D01*
G01X1420527Y1050000D02*
Y1067500D01*
X1424593D01*
X1426220Y1066625D01*
X1427440Y1065458D01*
X1428457Y1063709D01*
X1429270Y1061666D01*
X1429473Y1058750D01*
X1429270Y1055833D01*
X1428457Y1053791D01*
X1427440Y1052041D01*
X1426220Y1050875D01*
X1424593Y1050000D01*
X1420527D01*
G54D18*
G01X-1894720Y1212520D02*
Y1218520D01*
X-1892900Y1213520D01*
X-1891080Y1218520D01*
Y1212520D01*
G01X-1888040Y1218520D02*
X-1886360D01*
G01X-1887200D02*
Y1212520D01*
G01X-1888040D02*
X-1886360D01*
G01X-1879960Y1218020D02*
X-1880380Y1218320D01*
X-1880870Y1218520D01*
X-1881430D01*
X-1882060Y1218220D01*
X-1882550Y1217720D01*
X-1882900Y1217120D01*
X-1883180Y1216120D01*
X-1883250Y1215220D01*
X-1883110Y1214320D01*
X-1882900Y1213720D01*
X-1882480Y1213120D01*
X-1881990Y1212720D01*
X-1881500Y1212520D01*
X-1881010D01*
X-1880520Y1212720D01*
X-1880100Y1213020D01*
X-1879750Y1213420D01*
G01X-1877200Y1212520D02*
Y1218520D01*
X-1875450D01*
X-1874890Y1218220D01*
X-1874540Y1217820D01*
X-1874400Y1217020D01*
X-1874540Y1216220D01*
X-1874960Y1215720D01*
X-1875450Y1215420D01*
X-1877200D01*
G01X-1875450D02*
X-1874400Y1212520D01*
G01X-1870100D02*
X-1870660Y1212620D01*
X-1871150Y1213020D01*
X-1871570Y1213620D01*
X-1871850Y1214320D01*
X-1871990Y1215120D01*
Y1215920D01*
X-1871850Y1216720D01*
X-1871570Y1217420D01*
X-1871150Y1218020D01*
X-1870660Y1218420D01*
X-1870100Y1218520D01*
X-1869540Y1218420D01*
X-1869050Y1218020D01*
X-1868630Y1217420D01*
X-1868350Y1216720D01*
X-1868210Y1215920D01*
Y1215120D01*
X-1868350Y1214320D01*
X-1868630Y1213620D01*
X-1869050Y1213020D01*
X-1869540Y1212620D01*
X-1870100Y1212520D01*
G01X-1865870Y1213320D02*
X-1865310Y1212820D01*
X-1864680Y1212520D01*
X-1864120D01*
X-1863560Y1212820D01*
X-1863140Y1213320D01*
X-1862930Y1214020D01*
X-1863070Y1214720D01*
X-1863420Y1215320D01*
X-1864050Y1215720D01*
X-1864890Y1215920D01*
X-1865380Y1216320D01*
X-1865590Y1217020D01*
X-1865450Y1217720D01*
X-1865100Y1218220D01*
X-1864610Y1218520D01*
X-1864120D01*
X-1863630Y1218320D01*
X-1863210Y1217820D01*
G01X-1858700Y1212520D02*
X-1859260Y1212620D01*
X-1859750Y1213020D01*
X-1860170Y1213620D01*
X-1860450Y1214320D01*
X-1860590Y1215120D01*
Y1215920D01*
X-1860450Y1216720D01*
X-1860170Y1217420D01*
X-1859750Y1218020D01*
X-1859260Y1218420D01*
X-1858700Y1218520D01*
X-1858140Y1218420D01*
X-1857650Y1218020D01*
X-1857230Y1217420D01*
X-1856950Y1216720D01*
X-1856810Y1215920D01*
Y1215120D01*
X-1856950Y1214320D01*
X-1857230Y1213620D01*
X-1857650Y1213020D01*
X-1858140Y1212620D01*
X-1858700Y1212520D01*
G01X-1854330D02*
Y1218520D01*
X-1851670D01*
G01X-1852650Y1215620D02*
X-1854330D01*
G01X-1847300Y1218520D02*
Y1212520D01*
G01X-1848910Y1218520D02*
X-1845690D01*
G01X-1834360Y1218020D02*
X-1834780Y1218320D01*
X-1835270Y1218520D01*
X-1835830D01*
X-1836460Y1218220D01*
X-1836950Y1217720D01*
X-1837300Y1217120D01*
X-1837580Y1216120D01*
X-1837650Y1215220D01*
X-1837510Y1214320D01*
X-1837300Y1213720D01*
X-1836880Y1213120D01*
X-1836390Y1212720D01*
X-1835900Y1212520D01*
X-1835410D01*
X-1834920Y1212720D01*
X-1834500Y1213020D01*
X-1834150Y1213420D01*
G01X-1830200Y1212520D02*
X-1830760Y1212620D01*
X-1831250Y1213020D01*
X-1831670Y1213620D01*
X-1831950Y1214320D01*
X-1832090Y1215120D01*
Y1215920D01*
X-1831950Y1216720D01*
X-1831670Y1217420D01*
X-1831250Y1218020D01*
X-1830760Y1218420D01*
X-1830200Y1218520D01*
X-1829640Y1218420D01*
X-1829150Y1218020D01*
X-1828730Y1217420D01*
X-1828450Y1216720D01*
X-1828310Y1215920D01*
Y1215120D01*
X-1828450Y1214320D01*
X-1828730Y1213620D01*
X-1829150Y1213020D01*
X-1829640Y1212620D01*
X-1830200Y1212520D01*
G01X-1825900D02*
Y1218520D01*
X-1824150D01*
X-1823590Y1218220D01*
X-1823240Y1217820D01*
X-1823100Y1217020D01*
X-1823240Y1216220D01*
X-1823660Y1215720D01*
X-1824150Y1215420D01*
X-1825900D01*
G01X-1824150D02*
X-1823100Y1212520D01*
G01X-1820200D02*
Y1218520D01*
X-1818520D01*
X-1817960Y1218220D01*
X-1817540Y1217520D01*
X-1817400Y1216720D01*
X-1817540Y1215920D01*
X-1817890Y1215320D01*
X-1818520Y1215020D01*
X-1820200D01*
G01X-1813100Y1212520D02*
X-1813660Y1212620D01*
X-1814150Y1213020D01*
X-1814570Y1213620D01*
X-1814850Y1214320D01*
X-1814990Y1215120D01*
Y1215920D01*
X-1814850Y1216720D01*
X-1814570Y1217420D01*
X-1814150Y1218020D01*
X-1813660Y1218420D01*
X-1813100Y1218520D01*
X-1812540Y1218420D01*
X-1812050Y1218020D01*
X-1811630Y1217420D01*
X-1811350Y1216720D01*
X-1811210Y1215920D01*
Y1215120D01*
X-1811350Y1214320D01*
X-1811630Y1213620D01*
X-1812050Y1213020D01*
X-1812540Y1212620D01*
X-1813100Y1212520D01*
G01X-1808800D02*
Y1218520D01*
X-1807050D01*
X-1806490Y1218220D01*
X-1806140Y1217820D01*
X-1806000Y1217020D01*
X-1806140Y1216220D01*
X-1806560Y1215720D01*
X-1807050Y1215420D01*
X-1808800D01*
G01X-1807050D02*
X-1806000Y1212520D01*
G01X-1803450D02*
X-1801700Y1218520D01*
X-1799950Y1212520D01*
G01X-1800580Y1214620D02*
X-1802820D01*
G01X-1796000Y1218520D02*
Y1212520D01*
G01X-1797610Y1218520D02*
X-1794390D01*
G01X-1791140D02*
X-1789460D01*
G01X-1790300D02*
Y1212520D01*
G01X-1791140D02*
X-1789460D01*
G01X-1784600D02*
X-1785160Y1212620D01*
X-1785650Y1213020D01*
X-1786070Y1213620D01*
X-1786350Y1214320D01*
X-1786490Y1215120D01*
Y1215920D01*
X-1786350Y1216720D01*
X-1786070Y1217420D01*
X-1785650Y1218020D01*
X-1785160Y1218420D01*
X-1784600Y1218520D01*
X-1784040Y1218420D01*
X-1783550Y1218020D01*
X-1783130Y1217420D01*
X-1782850Y1216720D01*
X-1782710Y1215920D01*
Y1215120D01*
X-1782850Y1214320D01*
X-1783130Y1213620D01*
X-1783550Y1213020D01*
X-1784040Y1212620D01*
X-1784600Y1212520D01*
G01X-1780510D02*
Y1218520D01*
X-1777290Y1212520D01*
Y1218520D01*
G01X-1773200Y1212320D02*
X-1773340Y1212420D01*
Y1212620D01*
X-1773200Y1212720D01*
X-1773060Y1212620D01*
Y1212420D01*
X-1773200Y1212320D01*
G01X-1891360Y1243020D02*
X-1891780Y1243320D01*
X-1892270Y1243520D01*
X-1892830D01*
X-1893460Y1243220D01*
X-1893950Y1242720D01*
X-1894300Y1242120D01*
X-1894580Y1241120D01*
X-1894650Y1240220D01*
X-1894510Y1239320D01*
X-1894300Y1238720D01*
X-1893880Y1238120D01*
X-1893390Y1237720D01*
X-1892900Y1237520D01*
X-1892410D01*
X-1891920Y1237720D01*
X-1891500Y1238020D01*
X-1891150Y1238420D01*
G01X-1887200Y1237520D02*
X-1887760Y1237620D01*
X-1888250Y1238020D01*
X-1888670Y1238620D01*
X-1888950Y1239320D01*
X-1889090Y1240120D01*
Y1240920D01*
X-1888950Y1241720D01*
X-1888670Y1242420D01*
X-1888250Y1243020D01*
X-1887760Y1243420D01*
X-1887200Y1243520D01*
X-1886640Y1243420D01*
X-1886150Y1243020D01*
X-1885730Y1242420D01*
X-1885450Y1241720D01*
X-1885310Y1240920D01*
Y1240120D01*
X-1885450Y1239320D01*
X-1885730Y1238620D01*
X-1886150Y1238020D01*
X-1886640Y1237620D01*
X-1887200Y1237520D01*
G01X-1883110D02*
Y1243520D01*
X-1879890Y1237520D01*
Y1243520D01*
G01X-1875800D02*
Y1237520D01*
G01X-1877410Y1243520D02*
X-1874190D01*
G01X-1868700Y1237520D02*
X-1871500D01*
Y1243520D01*
X-1868700D01*
G01X-1869820Y1240620D02*
X-1871500D01*
G01X-1866010Y1237520D02*
Y1243520D01*
X-1862790Y1237520D01*
Y1243520D01*
G01X-1858700D02*
Y1237520D01*
G01X-1860310Y1243520D02*
X-1857090D01*
G01X-1854470Y1238320D02*
X-1853910Y1237820D01*
X-1853280Y1237520D01*
X-1852720D01*
X-1852160Y1237820D01*
X-1851740Y1238320D01*
X-1851530Y1239020D01*
X-1851670Y1239720D01*
X-1852020Y1240320D01*
X-1852650Y1240720D01*
X-1853490Y1240920D01*
X-1853980Y1241320D01*
X-1854190Y1242020D01*
X-1854050Y1242720D01*
X-1853700Y1243220D01*
X-1853210Y1243520D01*
X-1852720D01*
X-1852230Y1243320D01*
X-1851810Y1242820D01*
G01X-1843420Y1237520D02*
Y1243520D01*
X-1841600Y1238520D01*
X-1839780Y1243520D01*
Y1237520D01*
G01X-1837650D02*
X-1835900Y1243520D01*
X-1834150Y1237520D01*
G01X-1834780Y1239620D02*
X-1837020D01*
G01X-1830200Y1237520D02*
Y1240220D01*
X-1831600Y1243520D01*
G01X-1828800D02*
X-1830200Y1240220D01*
G01X-1820410Y1237520D02*
Y1243520D01*
X-1817190Y1237520D01*
Y1243520D01*
G01X-1813100Y1237520D02*
X-1813660Y1237620D01*
X-1814150Y1238020D01*
X-1814570Y1238620D01*
X-1814850Y1239320D01*
X-1814990Y1240120D01*
Y1240920D01*
X-1814850Y1241720D01*
X-1814570Y1242420D01*
X-1814150Y1243020D01*
X-1813660Y1243420D01*
X-1813100Y1243520D01*
X-1812540Y1243420D01*
X-1812050Y1243020D01*
X-1811630Y1242420D01*
X-1811350Y1241720D01*
X-1811210Y1240920D01*
Y1240120D01*
X-1811350Y1239320D01*
X-1811630Y1238620D01*
X-1812050Y1238020D01*
X-1812540Y1237620D01*
X-1813100Y1237520D01*
G01X-1807400Y1243520D02*
Y1237520D01*
G01X-1809010Y1243520D02*
X-1805790D01*
G01X-1795440Y1240720D02*
X-1795160Y1241020D01*
X-1794950Y1241520D01*
X-1794810Y1242220D01*
X-1794950Y1242820D01*
X-1795230Y1243220D01*
X-1795720Y1243520D01*
X-1797610D01*
Y1237520D01*
X-1795300D01*
X-1794810Y1237920D01*
X-1794530Y1238520D01*
X-1794390Y1239220D01*
X-1794530Y1239920D01*
X-1794950Y1240520D01*
X-1795440Y1240720D01*
X-1797610D01*
G01X-1788900Y1237520D02*
X-1791700D01*
Y1243520D01*
X-1788900D01*
G01X-1790020Y1240620D02*
X-1791700D01*
G01X-1780440Y1237520D02*
Y1243520D01*
X-1779040D01*
X-1778480Y1243220D01*
X-1778060Y1242820D01*
X-1777710Y1242220D01*
X-1777430Y1241520D01*
X-1777360Y1240520D01*
X-1777430Y1239520D01*
X-1777710Y1238820D01*
X-1778060Y1238220D01*
X-1778480Y1237820D01*
X-1779040Y1237520D01*
X-1780440D01*
G01X-1774040Y1243520D02*
X-1772360D01*
G01X-1773200D02*
Y1237520D01*
G01X-1774040D02*
X-1772360D01*
G01X-1768970Y1238320D02*
X-1768410Y1237820D01*
X-1767780Y1237520D01*
X-1767220D01*
X-1766660Y1237820D01*
X-1766240Y1238320D01*
X-1766030Y1239020D01*
X-1766170Y1239720D01*
X-1766520Y1240320D01*
X-1767150Y1240720D01*
X-1767990Y1240920D01*
X-1768480Y1241320D01*
X-1768690Y1242020D01*
X-1768550Y1242720D01*
X-1768200Y1243220D01*
X-1767710Y1243520D01*
X-1767220D01*
X-1766730Y1243320D01*
X-1766310Y1242820D01*
G01X-1760260Y1243020D02*
X-1760680Y1243320D01*
X-1761170Y1243520D01*
X-1761730D01*
X-1762360Y1243220D01*
X-1762850Y1242720D01*
X-1763200Y1242120D01*
X-1763480Y1241120D01*
X-1763550Y1240220D01*
X-1763410Y1239320D01*
X-1763200Y1238720D01*
X-1762780Y1238120D01*
X-1762290Y1237720D01*
X-1761800Y1237520D01*
X-1761310D01*
X-1760820Y1237720D01*
X-1760400Y1238020D01*
X-1760050Y1238420D01*
G01X-1757500Y1243520D02*
Y1237520D01*
X-1754700D01*
G01X-1750400D02*
X-1750960Y1237620D01*
X-1751450Y1238020D01*
X-1751870Y1238620D01*
X-1752150Y1239320D01*
X-1752290Y1240120D01*
Y1240920D01*
X-1752150Y1241720D01*
X-1751870Y1242420D01*
X-1751450Y1243020D01*
X-1750960Y1243420D01*
X-1750400Y1243520D01*
X-1749840Y1243420D01*
X-1749350Y1243020D01*
X-1748930Y1242420D01*
X-1748650Y1241720D01*
X-1748510Y1240920D01*
Y1240120D01*
X-1748650Y1239320D01*
X-1748930Y1238620D01*
X-1749350Y1238020D01*
X-1749840Y1237620D01*
X-1750400Y1237520D01*
G01X-1746170Y1238320D02*
X-1745610Y1237820D01*
X-1744980Y1237520D01*
X-1744420D01*
X-1743860Y1237820D01*
X-1743440Y1238320D01*
X-1743230Y1239020D01*
X-1743370Y1239720D01*
X-1743720Y1240320D01*
X-1744350Y1240720D01*
X-1745190Y1240920D01*
X-1745680Y1241320D01*
X-1745890Y1242020D01*
X-1745750Y1242720D01*
X-1745400Y1243220D01*
X-1744910Y1243520D01*
X-1744420D01*
X-1743930Y1243320D01*
X-1743510Y1242820D01*
G01X-1737600Y1237520D02*
X-1740400D01*
Y1243520D01*
X-1737600D01*
G01X-1738720Y1240620D02*
X-1740400D01*
G01X-1734840Y1237520D02*
Y1243520D01*
X-1733440D01*
X-1732880Y1243220D01*
X-1732460Y1242820D01*
X-1732110Y1242220D01*
X-1731830Y1241520D01*
X-1731760Y1240520D01*
X-1731830Y1239520D01*
X-1732110Y1238820D01*
X-1732460Y1238220D01*
X-1732880Y1237820D01*
X-1733440Y1237520D01*
X-1734840D01*
G01X-1724000Y1243520D02*
X-1723020Y1237520D01*
X-1721900Y1243520D01*
X-1720780Y1237520D01*
X-1719800Y1243520D01*
G01X-1717040D02*
X-1715360D01*
G01X-1716200D02*
Y1237520D01*
G01X-1717040D02*
X-1715360D01*
G01X-1710500Y1243520D02*
Y1237520D01*
G01X-1712110Y1243520D02*
X-1708890D01*
G01X-1706270Y1237520D02*
Y1243520D01*
G01X-1703330D02*
Y1237520D01*
G01Y1240520D02*
X-1706270D01*
G01X-1700010Y1239520D02*
X-1698190D01*
G01X-1892900Y1225000D02*
X-1893460Y1225100D01*
X-1893950Y1225500D01*
X-1894370Y1226100D01*
X-1894650Y1226800D01*
X-1894790Y1227600D01*
Y1228400D01*
X-1894650Y1229200D01*
X-1894370Y1229900D01*
X-1893950Y1230500D01*
X-1893460Y1230900D01*
X-1892900Y1231000D01*
X-1892340Y1230900D01*
X-1891850Y1230500D01*
X-1891430Y1229900D01*
X-1891150Y1229200D01*
X-1891010Y1228400D01*
Y1227600D01*
X-1891150Y1226800D01*
X-1891430Y1226100D01*
X-1891850Y1225500D01*
X-1892340Y1225100D01*
X-1892900Y1225000D01*
G01X-1888740Y1231000D02*
Y1226700D01*
X-1888460Y1225800D01*
X-1887900Y1225200D01*
X-1887200Y1225000D01*
X-1886500Y1225200D01*
X-1885940Y1225800D01*
X-1885660Y1226700D01*
Y1231000D01*
G01X-1881500D02*
Y1225000D01*
G01X-1883110Y1231000D02*
X-1879890D01*
G01X-1870100D02*
Y1225000D01*
G01X-1871710Y1231000D02*
X-1868490D01*
G01X-1865870Y1225000D02*
Y1231000D01*
G01X-1862930D02*
Y1225000D01*
G01Y1228000D02*
X-1865870D01*
G01X-1857300Y1225000D02*
X-1860100D01*
Y1231000D01*
X-1857300D01*
G01X-1858420Y1228100D02*
X-1860100D01*
G01X-1848700Y1225000D02*
Y1231000D01*
X-1847020D01*
X-1846460Y1230700D01*
X-1846040Y1230000D01*
X-1845900Y1229200D01*
X-1846040Y1228400D01*
X-1846390Y1227800D01*
X-1847020Y1227500D01*
X-1848700D01*
G01X-1843000Y1225000D02*
Y1231000D01*
X-1841250D01*
X-1840690Y1230700D01*
X-1840340Y1230300D01*
X-1840200Y1229500D01*
X-1840340Y1228700D01*
X-1840760Y1228200D01*
X-1841250Y1227900D01*
X-1843000D01*
G01X-1841250D02*
X-1840200Y1225000D01*
G01X-1836740Y1231000D02*
X-1835060D01*
G01X-1835900D02*
Y1225000D01*
G01X-1836740D02*
X-1835060D01*
G01X-1830200D02*
X-1830760Y1225100D01*
X-1831250Y1225500D01*
X-1831670Y1226100D01*
X-1831950Y1226800D01*
X-1832090Y1227600D01*
Y1228400D01*
X-1831950Y1229200D01*
X-1831670Y1229900D01*
X-1831250Y1230500D01*
X-1830760Y1230900D01*
X-1830200Y1231000D01*
X-1829640Y1230900D01*
X-1829150Y1230500D01*
X-1828730Y1229900D01*
X-1828450Y1229200D01*
X-1828310Y1228400D01*
Y1227600D01*
X-1828450Y1226800D01*
X-1828730Y1226100D01*
X-1829150Y1225500D01*
X-1829640Y1225100D01*
X-1830200Y1225000D01*
G01X-1825900D02*
Y1231000D01*
X-1824150D01*
X-1823590Y1230700D01*
X-1823240Y1230300D01*
X-1823100Y1229500D01*
X-1823240Y1228700D01*
X-1823660Y1228200D01*
X-1824150Y1227900D01*
X-1825900D01*
G01X-1824150D02*
X-1823100Y1225000D01*
G01X-1815200Y1231000D02*
X-1814220Y1225000D01*
X-1813100Y1231000D01*
X-1811980Y1225000D01*
X-1811000Y1231000D01*
G01X-1808800Y1225000D02*
Y1231000D01*
X-1807050D01*
X-1806490Y1230700D01*
X-1806140Y1230300D01*
X-1806000Y1229500D01*
X-1806140Y1228700D01*
X-1806560Y1228200D01*
X-1807050Y1227900D01*
X-1808800D01*
G01X-1807050D02*
X-1806000Y1225000D01*
G01X-1802540Y1231000D02*
X-1800860D01*
G01X-1801700D02*
Y1225000D01*
G01X-1802540D02*
X-1800860D01*
G01X-1796000Y1231000D02*
Y1225000D01*
G01X-1797610Y1231000D02*
X-1794390D01*
G01X-1790300D02*
Y1225000D01*
G01X-1791910Y1231000D02*
X-1788690D01*
G01X-1783200Y1225000D02*
X-1786000D01*
Y1231000D01*
X-1783200D01*
G01X-1784320Y1228100D02*
X-1786000D01*
G01X-1780510Y1225000D02*
Y1231000D01*
X-1777290Y1225000D01*
Y1231000D01*
G01X-1765960Y1230500D02*
X-1766380Y1230800D01*
X-1766870Y1231000D01*
X-1767430D01*
X-1768060Y1230700D01*
X-1768550Y1230200D01*
X-1768900Y1229600D01*
X-1769180Y1228600D01*
X-1769250Y1227700D01*
X-1769110Y1226800D01*
X-1768900Y1226200D01*
X-1768480Y1225600D01*
X-1767990Y1225200D01*
X-1767500Y1225000D01*
X-1767010D01*
X-1766520Y1225200D01*
X-1766100Y1225500D01*
X-1765750Y1225900D01*
G01X-1761800Y1225000D02*
X-1762360Y1225100D01*
X-1762850Y1225500D01*
X-1763270Y1226100D01*
X-1763550Y1226800D01*
X-1763690Y1227600D01*
Y1228400D01*
X-1763550Y1229200D01*
X-1763270Y1229900D01*
X-1762850Y1230500D01*
X-1762360Y1230900D01*
X-1761800Y1231000D01*
X-1761240Y1230900D01*
X-1760750Y1230500D01*
X-1760330Y1229900D01*
X-1760050Y1229200D01*
X-1759910Y1228400D01*
Y1227600D01*
X-1760050Y1226800D01*
X-1760330Y1226100D01*
X-1760750Y1225500D01*
X-1761240Y1225100D01*
X-1761800Y1225000D01*
G01X-1757710D02*
Y1231000D01*
X-1754490Y1225000D01*
Y1231000D01*
G01X-1751870Y1225800D02*
X-1751310Y1225300D01*
X-1750680Y1225000D01*
X-1750120D01*
X-1749560Y1225300D01*
X-1749140Y1225800D01*
X-1748930Y1226500D01*
X-1749070Y1227200D01*
X-1749420Y1227800D01*
X-1750050Y1228200D01*
X-1750890Y1228400D01*
X-1751380Y1228800D01*
X-1751590Y1229500D01*
X-1751450Y1230200D01*
X-1751100Y1230700D01*
X-1750610Y1231000D01*
X-1750120D01*
X-1749630Y1230800D01*
X-1749210Y1230300D01*
G01X-1743300Y1225000D02*
X-1746100D01*
Y1231000D01*
X-1743300D01*
G01X-1744420Y1228100D02*
X-1746100D01*
G01X-1740610Y1225000D02*
Y1231000D01*
X-1737390Y1225000D01*
Y1231000D01*
G01X-1733300D02*
Y1225000D01*
G01X-1734910Y1231000D02*
X-1731690D01*
G01X-1721900Y1225000D02*
X-1722460Y1225100D01*
X-1722950Y1225500D01*
X-1723370Y1226100D01*
X-1723650Y1226800D01*
X-1723790Y1227600D01*
Y1228400D01*
X-1723650Y1229200D01*
X-1723370Y1229900D01*
X-1722950Y1230500D01*
X-1722460Y1230900D01*
X-1721900Y1231000D01*
X-1721340Y1230900D01*
X-1720850Y1230500D01*
X-1720430Y1229900D01*
X-1720150Y1229200D01*
X-1720010Y1228400D01*
Y1227600D01*
X-1720150Y1226800D01*
X-1720430Y1226100D01*
X-1720850Y1225500D01*
X-1721340Y1225100D01*
X-1721900Y1225000D01*
G01X-1717530D02*
Y1231000D01*
X-1714870D01*
G01X-1715850Y1228100D02*
X-1717530D01*
G01X-1893740Y1256000D02*
X-1892060D01*
G01X-1892900D02*
Y1250000D01*
G01X-1893740D02*
X-1892060D01*
G01X-1888670Y1250800D02*
X-1888110Y1250300D01*
X-1887480Y1250000D01*
X-1886920D01*
X-1886360Y1250300D01*
X-1885940Y1250800D01*
X-1885730Y1251500D01*
X-1885870Y1252200D01*
X-1886220Y1252800D01*
X-1886850Y1253200D01*
X-1887690Y1253400D01*
X-1888180Y1253800D01*
X-1888390Y1254500D01*
X-1888250Y1255200D01*
X-1887900Y1255700D01*
X-1887410Y1256000D01*
X-1886920D01*
X-1886430Y1255800D01*
X-1886010Y1255300D01*
G01X-1877200Y1250000D02*
Y1256000D01*
X-1875450D01*
X-1874890Y1255700D01*
X-1874540Y1255300D01*
X-1874400Y1254500D01*
X-1874540Y1253700D01*
X-1874960Y1253200D01*
X-1875450Y1252900D01*
X-1877200D01*
G01X-1875450D02*
X-1874400Y1250000D01*
G01X-1868700D02*
X-1871500D01*
Y1256000D01*
X-1868700D01*
G01X-1869820Y1253100D02*
X-1871500D01*
G01X-1862860Y1255500D02*
X-1863280Y1255800D01*
X-1863770Y1256000D01*
X-1864330D01*
X-1864960Y1255700D01*
X-1865450Y1255200D01*
X-1865800Y1254600D01*
X-1866080Y1253600D01*
X-1866150Y1252700D01*
X-1866010Y1251800D01*
X-1865800Y1251200D01*
X-1865380Y1250600D01*
X-1864890Y1250200D01*
X-1864400Y1250000D01*
X-1863910D01*
X-1863420Y1250200D01*
X-1863000Y1250500D01*
X-1862650Y1250900D01*
G01X-1857300Y1250000D02*
X-1860100D01*
Y1256000D01*
X-1857300D01*
G01X-1858420Y1253100D02*
X-1860100D01*
G01X-1853840Y1256000D02*
X-1852160D01*
G01X-1853000D02*
Y1250000D01*
G01X-1853840D02*
X-1852160D01*
G01X-1849050Y1256000D02*
X-1847300Y1250000D01*
X-1845550Y1256000D01*
G01X-1840200Y1250000D02*
X-1843000D01*
Y1256000D01*
X-1840200D01*
G01X-1841320Y1253100D02*
X-1843000D01*
G01X-1837440Y1250000D02*
Y1256000D01*
X-1836040D01*
X-1835480Y1255700D01*
X-1835060Y1255300D01*
X-1834710Y1254700D01*
X-1834430Y1254000D01*
X-1834360Y1253000D01*
X-1834430Y1252000D01*
X-1834710Y1251300D01*
X-1835060Y1250700D01*
X-1835480Y1250300D01*
X-1836040Y1250000D01*
X-1837440D01*
G01X-1825340Y1256000D02*
X-1823660D01*
G01X-1824500D02*
Y1250000D01*
G01X-1825340D02*
X-1823660D01*
G01X-1820410D02*
Y1256000D01*
X-1817190Y1250000D01*
Y1256000D01*
G01X-1805860Y1255500D02*
X-1806280Y1255800D01*
X-1806770Y1256000D01*
X-1807330D01*
X-1807960Y1255700D01*
X-1808450Y1255200D01*
X-1808800Y1254600D01*
X-1809080Y1253600D01*
X-1809150Y1252700D01*
X-1809010Y1251800D01*
X-1808800Y1251200D01*
X-1808380Y1250600D01*
X-1807890Y1250200D01*
X-1807400Y1250000D01*
X-1806910D01*
X-1806420Y1250200D01*
X-1806000Y1250500D01*
X-1805650Y1250900D01*
G01X-1801700Y1250000D02*
X-1802260Y1250100D01*
X-1802750Y1250500D01*
X-1803170Y1251100D01*
X-1803450Y1251800D01*
X-1803590Y1252600D01*
Y1253400D01*
X-1803450Y1254200D01*
X-1803170Y1254900D01*
X-1802750Y1255500D01*
X-1802260Y1255900D01*
X-1801700Y1256000D01*
X-1801140Y1255900D01*
X-1800650Y1255500D01*
X-1800230Y1254900D01*
X-1799950Y1254200D01*
X-1799810Y1253400D01*
Y1252600D01*
X-1799950Y1251800D01*
X-1800230Y1251100D01*
X-1800650Y1250500D01*
X-1801140Y1250100D01*
X-1801700Y1250000D01*
G01X-1797610D02*
Y1256000D01*
X-1794390Y1250000D01*
Y1256000D01*
G01X-1791630Y1250000D02*
Y1256000D01*
X-1788970D01*
G01X-1789950Y1253100D02*
X-1791630D01*
G01X-1785440Y1256000D02*
X-1783760D01*
G01X-1784600D02*
Y1250000D01*
G01X-1785440D02*
X-1783760D01*
G01X-1780440D02*
Y1256000D01*
X-1779040D01*
X-1778480Y1255700D01*
X-1778060Y1255300D01*
X-1777710Y1254700D01*
X-1777430Y1254000D01*
X-1777360Y1253000D01*
X-1777430Y1252000D01*
X-1777710Y1251300D01*
X-1778060Y1250700D01*
X-1778480Y1250300D01*
X-1779040Y1250000D01*
X-1780440D01*
G01X-1771800D02*
X-1774600D01*
Y1256000D01*
X-1771800D01*
G01X-1772920Y1253100D02*
X-1774600D01*
G01X-1769110Y1250000D02*
Y1256000D01*
X-1765890Y1250000D01*
Y1256000D01*
G01X-1760260Y1255500D02*
X-1760680Y1255800D01*
X-1761170Y1256000D01*
X-1761730D01*
X-1762360Y1255700D01*
X-1762850Y1255200D01*
X-1763200Y1254600D01*
X-1763480Y1253600D01*
X-1763550Y1252700D01*
X-1763410Y1251800D01*
X-1763200Y1251200D01*
X-1762780Y1250600D01*
X-1762290Y1250200D01*
X-1761800Y1250000D01*
X-1761310D01*
X-1760820Y1250200D01*
X-1760400Y1250500D01*
X-1760050Y1250900D01*
G01X-1754700Y1250000D02*
X-1757500D01*
Y1256000D01*
X-1754700D01*
G01X-1755820Y1253100D02*
X-1757500D01*
G01X-1746450Y1250000D02*
X-1744700Y1256000D01*
X-1742950Y1250000D01*
G01X-1743580Y1252100D02*
X-1745820D01*
G01X-1740610Y1250000D02*
Y1256000D01*
X-1737390Y1250000D01*
Y1256000D01*
G01X-1734840Y1250000D02*
Y1256000D01*
X-1733440D01*
X-1732880Y1255700D01*
X-1732460Y1255300D01*
X-1732110Y1254700D01*
X-1731830Y1254000D01*
X-1731760Y1253000D01*
X-1731830Y1252000D01*
X-1732110Y1251300D01*
X-1732460Y1250700D01*
X-1732880Y1250300D01*
X-1733440Y1250000D01*
X-1734840D01*
G01X-1722740Y1256000D02*
X-1721060D01*
G01X-1721900D02*
Y1250000D01*
G01X-1722740D02*
X-1721060D01*
G01X-1716200Y1256000D02*
Y1250000D01*
G01X-1717810Y1256000D02*
X-1714590D01*
G01X-1711970Y1250800D02*
X-1711410Y1250300D01*
X-1710780Y1250000D01*
X-1710220D01*
X-1709660Y1250300D01*
X-1709240Y1250800D01*
X-1709030Y1251500D01*
X-1709170Y1252200D01*
X-1709520Y1252800D01*
X-1710150Y1253200D01*
X-1710990Y1253400D01*
X-1711480Y1253800D01*
X-1711690Y1254500D01*
X-1711550Y1255200D01*
X-1711200Y1255700D01*
X-1710710Y1256000D01*
X-1710220D01*
X-1709730Y1255800D01*
X-1709310Y1255300D01*
G01X-1892900Y1262520D02*
X-1893460Y1262620D01*
X-1893950Y1263020D01*
X-1894370Y1263620D01*
X-1894650Y1264320D01*
X-1894790Y1265120D01*
Y1265920D01*
X-1894650Y1266720D01*
X-1894370Y1267420D01*
X-1893950Y1268020D01*
X-1893460Y1268420D01*
X-1892900Y1268520D01*
X-1892340Y1268420D01*
X-1891850Y1268020D01*
X-1891430Y1267420D01*
X-1891150Y1266720D01*
X-1891010Y1265920D01*
Y1265120D01*
X-1891150Y1264320D01*
X-1891430Y1263620D01*
X-1891850Y1263020D01*
X-1892340Y1262620D01*
X-1892900Y1262520D01*
G01X-1888530D02*
Y1268520D01*
X-1885870D01*
G01X-1886850Y1265620D02*
X-1888530D01*
G01X-1877620Y1262520D02*
Y1268520D01*
X-1875800Y1263520D01*
X-1873980Y1268520D01*
Y1262520D01*
G01X-1870940Y1268520D02*
X-1869260D01*
G01X-1870100D02*
Y1262520D01*
G01X-1870940D02*
X-1869260D01*
G01X-1862860Y1268020D02*
X-1863280Y1268320D01*
X-1863770Y1268520D01*
X-1864330D01*
X-1864960Y1268220D01*
X-1865450Y1267720D01*
X-1865800Y1267120D01*
X-1866080Y1266120D01*
X-1866150Y1265220D01*
X-1866010Y1264320D01*
X-1865800Y1263720D01*
X-1865380Y1263120D01*
X-1864890Y1262720D01*
X-1864400Y1262520D01*
X-1863910D01*
X-1863420Y1262720D01*
X-1863000Y1263020D01*
X-1862650Y1263420D01*
G01X-1860100Y1262520D02*
Y1268520D01*
X-1858350D01*
X-1857790Y1268220D01*
X-1857440Y1267820D01*
X-1857300Y1267020D01*
X-1857440Y1266220D01*
X-1857860Y1265720D01*
X-1858350Y1265420D01*
X-1860100D01*
G01X-1858350D02*
X-1857300Y1262520D01*
G01X-1853000D02*
X-1853560Y1262620D01*
X-1854050Y1263020D01*
X-1854470Y1263620D01*
X-1854750Y1264320D01*
X-1854890Y1265120D01*
Y1265920D01*
X-1854750Y1266720D01*
X-1854470Y1267420D01*
X-1854050Y1268020D01*
X-1853560Y1268420D01*
X-1853000Y1268520D01*
X-1852440Y1268420D01*
X-1851950Y1268020D01*
X-1851530Y1267420D01*
X-1851250Y1266720D01*
X-1851110Y1265920D01*
Y1265120D01*
X-1851250Y1264320D01*
X-1851530Y1263620D01*
X-1851950Y1263020D01*
X-1852440Y1262620D01*
X-1853000Y1262520D01*
G01X-1848770Y1263320D02*
X-1848210Y1262820D01*
X-1847580Y1262520D01*
X-1847020D01*
X-1846460Y1262820D01*
X-1846040Y1263320D01*
X-1845830Y1264020D01*
X-1845970Y1264720D01*
X-1846320Y1265320D01*
X-1846950Y1265720D01*
X-1847790Y1265920D01*
X-1848280Y1266320D01*
X-1848490Y1267020D01*
X-1848350Y1267720D01*
X-1848000Y1268220D01*
X-1847510Y1268520D01*
X-1847020D01*
X-1846530Y1268320D01*
X-1846110Y1267820D01*
G01X-1841600Y1262520D02*
X-1842160Y1262620D01*
X-1842650Y1263020D01*
X-1843070Y1263620D01*
X-1843350Y1264320D01*
X-1843490Y1265120D01*
Y1265920D01*
X-1843350Y1266720D01*
X-1843070Y1267420D01*
X-1842650Y1268020D01*
X-1842160Y1268420D01*
X-1841600Y1268520D01*
X-1841040Y1268420D01*
X-1840550Y1268020D01*
X-1840130Y1267420D01*
X-1839850Y1266720D01*
X-1839710Y1265920D01*
Y1265120D01*
X-1839850Y1264320D01*
X-1840130Y1263620D01*
X-1840550Y1263020D01*
X-1841040Y1262620D01*
X-1841600Y1262520D01*
G01X-1837230D02*
Y1268520D01*
X-1834570D01*
G01X-1835550Y1265620D02*
X-1837230D01*
G01X-1830200Y1268520D02*
Y1262520D01*
G01X-1831810Y1268520D02*
X-1828590D01*
G01X-1817260Y1268020D02*
X-1817680Y1268320D01*
X-1818170Y1268520D01*
X-1818730D01*
X-1819360Y1268220D01*
X-1819850Y1267720D01*
X-1820200Y1267120D01*
X-1820480Y1266120D01*
X-1820550Y1265220D01*
X-1820410Y1264320D01*
X-1820200Y1263720D01*
X-1819780Y1263120D01*
X-1819290Y1262720D01*
X-1818800Y1262520D01*
X-1818310D01*
X-1817820Y1262720D01*
X-1817400Y1263020D01*
X-1817050Y1263420D01*
G01X-1813100Y1262520D02*
X-1813660Y1262620D01*
X-1814150Y1263020D01*
X-1814570Y1263620D01*
X-1814850Y1264320D01*
X-1814990Y1265120D01*
Y1265920D01*
X-1814850Y1266720D01*
X-1814570Y1267420D01*
X-1814150Y1268020D01*
X-1813660Y1268420D01*
X-1813100Y1268520D01*
X-1812540Y1268420D01*
X-1812050Y1268020D01*
X-1811630Y1267420D01*
X-1811350Y1266720D01*
X-1811210Y1265920D01*
Y1265120D01*
X-1811350Y1264320D01*
X-1811630Y1263620D01*
X-1812050Y1263020D01*
X-1812540Y1262620D01*
X-1813100Y1262520D01*
G01X-1808800D02*
Y1268520D01*
X-1807050D01*
X-1806490Y1268220D01*
X-1806140Y1267820D01*
X-1806000Y1267020D01*
X-1806140Y1266220D01*
X-1806560Y1265720D01*
X-1807050Y1265420D01*
X-1808800D01*
G01X-1807050D02*
X-1806000Y1262520D01*
G01X-1803100D02*
Y1268520D01*
X-1801420D01*
X-1800860Y1268220D01*
X-1800440Y1267520D01*
X-1800300Y1266720D01*
X-1800440Y1265920D01*
X-1800790Y1265320D01*
X-1801420Y1265020D01*
X-1803100D01*
G01X-1796000Y1262520D02*
X-1796560Y1262620D01*
X-1797050Y1263020D01*
X-1797470Y1263620D01*
X-1797750Y1264320D01*
X-1797890Y1265120D01*
Y1265920D01*
X-1797750Y1266720D01*
X-1797470Y1267420D01*
X-1797050Y1268020D01*
X-1796560Y1268420D01*
X-1796000Y1268520D01*
X-1795440Y1268420D01*
X-1794950Y1268020D01*
X-1794530Y1267420D01*
X-1794250Y1266720D01*
X-1794110Y1265920D01*
Y1265120D01*
X-1794250Y1264320D01*
X-1794530Y1263620D01*
X-1794950Y1263020D01*
X-1795440Y1262620D01*
X-1796000Y1262520D01*
G01X-1791700D02*
Y1268520D01*
X-1789950D01*
X-1789390Y1268220D01*
X-1789040Y1267820D01*
X-1788900Y1267020D01*
X-1789040Y1266220D01*
X-1789460Y1265720D01*
X-1789950Y1265420D01*
X-1791700D01*
G01X-1789950D02*
X-1788900Y1262520D01*
G01X-1786350D02*
X-1784600Y1268520D01*
X-1782850Y1262520D01*
G01X-1783480Y1264620D02*
X-1785720D01*
G01X-1778900Y1268520D02*
Y1262520D01*
G01X-1780510Y1268520D02*
X-1777290D01*
G01X-1774040D02*
X-1772360D01*
G01X-1773200D02*
Y1262520D01*
G01X-1774040D02*
X-1772360D01*
G01X-1767500D02*
X-1768060Y1262620D01*
X-1768550Y1263020D01*
X-1768970Y1263620D01*
X-1769250Y1264320D01*
X-1769390Y1265120D01*
Y1265920D01*
X-1769250Y1266720D01*
X-1768970Y1267420D01*
X-1768550Y1268020D01*
X-1768060Y1268420D01*
X-1767500Y1268520D01*
X-1766940Y1268420D01*
X-1766450Y1268020D01*
X-1766030Y1267420D01*
X-1765750Y1266720D01*
X-1765610Y1265920D01*
Y1265120D01*
X-1765750Y1264320D01*
X-1766030Y1263620D01*
X-1766450Y1263020D01*
X-1766940Y1262620D01*
X-1767500Y1262520D01*
G01X-1763410D02*
Y1268520D01*
X-1760190Y1262520D01*
Y1268520D01*
G01X-1756100Y1262320D02*
X-1756240Y1262420D01*
Y1262620D01*
X-1756100Y1262720D01*
X-1755960Y1262620D01*
Y1262420D01*
X-1756100Y1262320D01*
G01X-1744700Y1268520D02*
Y1262520D01*
G01X-1746310Y1268520D02*
X-1743090D01*
G01X-1740470Y1262520D02*
Y1268520D01*
G01X-1737530D02*
Y1262520D01*
G01Y1265520D02*
X-1740470D01*
G01X-1734140Y1268520D02*
X-1732460D01*
G01X-1733300D02*
Y1262520D01*
G01X-1734140D02*
X-1732460D01*
G01X-1729070Y1263320D02*
X-1728510Y1262820D01*
X-1727880Y1262520D01*
X-1727320D01*
X-1726760Y1262820D01*
X-1726340Y1263320D01*
X-1726130Y1264020D01*
X-1726270Y1264720D01*
X-1726620Y1265320D01*
X-1727250Y1265720D01*
X-1728090Y1265920D01*
X-1728580Y1266320D01*
X-1728790Y1267020D01*
X-1728650Y1267720D01*
X-1728300Y1268220D01*
X-1727810Y1268520D01*
X-1727320D01*
X-1726830Y1268320D01*
X-1726410Y1267820D01*
G01X-1717740Y1262520D02*
Y1268520D01*
X-1716340D01*
X-1715780Y1268220D01*
X-1715360Y1267820D01*
X-1715010Y1267220D01*
X-1714730Y1266520D01*
X-1714660Y1265520D01*
X-1714730Y1264520D01*
X-1715010Y1263820D01*
X-1715360Y1263220D01*
X-1715780Y1262820D01*
X-1716340Y1262520D01*
X-1717740D01*
G01X-1711900D02*
Y1268520D01*
X-1710150D01*
X-1709590Y1268220D01*
X-1709240Y1267820D01*
X-1709100Y1267020D01*
X-1709240Y1266220D01*
X-1709660Y1265720D01*
X-1710150Y1265420D01*
X-1711900D01*
G01X-1710150D02*
X-1709100Y1262520D01*
G01X-1706550D02*
X-1704800Y1268520D01*
X-1703050Y1262520D01*
G01X-1703680Y1264620D02*
X-1705920D01*
G01X-1701200Y1268520D02*
X-1700220Y1262520D01*
X-1699100Y1268520D01*
X-1697980Y1262520D01*
X-1697000Y1268520D01*
G01X-1694240D02*
X-1692560D01*
G01X-1693400D02*
Y1262520D01*
G01X-1694240D02*
X-1692560D01*
G01X-1689310D02*
Y1268520D01*
X-1686090Y1262520D01*
Y1268520D01*
G01X-1681580Y1265520D02*
X-1680180D01*
Y1263720D01*
X-1680600Y1263120D01*
X-1681090Y1262720D01*
X-1681790Y1262520D01*
X-1682490Y1262720D01*
X-1682980Y1263120D01*
X-1683400Y1263720D01*
X-1683680Y1264420D01*
X-1683820Y1265220D01*
Y1265920D01*
X-1683680Y1266520D01*
X-1683400Y1267220D01*
X-1682980Y1267820D01*
X-1682560Y1268220D01*
X-1682000Y1268520D01*
X-1681510D01*
X-1680950Y1268320D01*
X-1680530Y1267920D01*
G01X-1895000Y1281000D02*
X-1894020Y1275000D01*
X-1892900Y1281000D01*
X-1891780Y1275000D01*
X-1890800Y1281000D01*
G01X-1888670Y1275000D02*
Y1281000D01*
G01X-1885730D02*
Y1275000D01*
G01Y1278000D02*
X-1888670D01*
G01X-1882340Y1281000D02*
X-1880660D01*
G01X-1881500D02*
Y1275000D01*
G01X-1882340D02*
X-1880660D01*
G01X-1874260Y1280500D02*
X-1874680Y1280800D01*
X-1875170Y1281000D01*
X-1875730D01*
X-1876360Y1280700D01*
X-1876850Y1280200D01*
X-1877200Y1279600D01*
X-1877480Y1278600D01*
X-1877550Y1277700D01*
X-1877410Y1276800D01*
X-1877200Y1276200D01*
X-1876780Y1275600D01*
X-1876290Y1275200D01*
X-1875800Y1275000D01*
X-1875310D01*
X-1874820Y1275200D01*
X-1874400Y1275500D01*
X-1874050Y1275900D01*
G01X-1871570Y1275000D02*
Y1281000D01*
G01X-1868630D02*
Y1275000D01*
G01Y1278000D02*
X-1871570D01*
G01X-1859540Y1281000D02*
X-1857860D01*
G01X-1858700D02*
Y1275000D01*
G01X-1859540D02*
X-1857860D01*
G01X-1854470Y1275800D02*
X-1853910Y1275300D01*
X-1853280Y1275000D01*
X-1852720D01*
X-1852160Y1275300D01*
X-1851740Y1275800D01*
X-1851530Y1276500D01*
X-1851670Y1277200D01*
X-1852020Y1277800D01*
X-1852650Y1278200D01*
X-1853490Y1278400D01*
X-1853980Y1278800D01*
X-1854190Y1279500D01*
X-1854050Y1280200D01*
X-1853700Y1280700D01*
X-1853210Y1281000D01*
X-1852720D01*
X-1852230Y1280800D01*
X-1851810Y1280300D01*
G01X-1841600Y1281000D02*
Y1275000D01*
G01X-1843210Y1281000D02*
X-1839990D01*
G01X-1837370Y1275000D02*
Y1281000D01*
G01X-1834430D02*
Y1275000D01*
G01Y1278000D02*
X-1837370D01*
G01X-1828800Y1275000D02*
X-1831600D01*
Y1281000D01*
X-1828800D01*
G01X-1829920Y1278100D02*
X-1831600D01*
G01X-1820200Y1275000D02*
Y1281000D01*
X-1818520D01*
X-1817960Y1280700D01*
X-1817540Y1280000D01*
X-1817400Y1279200D01*
X-1817540Y1278400D01*
X-1817890Y1277800D01*
X-1818520Y1277500D01*
X-1820200D01*
G01X-1814500Y1275000D02*
Y1281000D01*
X-1812750D01*
X-1812190Y1280700D01*
X-1811840Y1280300D01*
X-1811700Y1279500D01*
X-1811840Y1278700D01*
X-1812260Y1278200D01*
X-1812750Y1277900D01*
X-1814500D01*
G01X-1812750D02*
X-1811700Y1275000D01*
G01X-1807400D02*
X-1807960Y1275100D01*
X-1808450Y1275500D01*
X-1808870Y1276100D01*
X-1809150Y1276800D01*
X-1809290Y1277600D01*
Y1278400D01*
X-1809150Y1279200D01*
X-1808870Y1279900D01*
X-1808450Y1280500D01*
X-1807960Y1280900D01*
X-1807400Y1281000D01*
X-1806840Y1280900D01*
X-1806350Y1280500D01*
X-1805930Y1279900D01*
X-1805650Y1279200D01*
X-1805510Y1278400D01*
Y1277600D01*
X-1805650Y1276800D01*
X-1805930Y1276100D01*
X-1806350Y1275500D01*
X-1806840Y1275100D01*
X-1807400Y1275000D01*
G01X-1803100D02*
Y1281000D01*
X-1801420D01*
X-1800860Y1280700D01*
X-1800440Y1280000D01*
X-1800300Y1279200D01*
X-1800440Y1278400D01*
X-1800790Y1277800D01*
X-1801420Y1277500D01*
X-1803100D01*
G01X-1797400Y1275000D02*
Y1281000D01*
X-1795650D01*
X-1795090Y1280700D01*
X-1794740Y1280300D01*
X-1794600Y1279500D01*
X-1794740Y1278700D01*
X-1795160Y1278200D01*
X-1795650Y1277900D01*
X-1797400D01*
G01X-1795650D02*
X-1794600Y1275000D01*
G01X-1791140Y1281000D02*
X-1789460D01*
G01X-1790300D02*
Y1275000D01*
G01X-1791140D02*
X-1789460D01*
G01X-1783200D02*
X-1786000D01*
Y1281000D01*
X-1783200D01*
G01X-1784320Y1278100D02*
X-1786000D01*
G01X-1778900Y1281000D02*
Y1275000D01*
G01X-1780510Y1281000D02*
X-1777290D01*
G01X-1774950Y1275000D02*
X-1773200Y1281000D01*
X-1771450Y1275000D01*
G01X-1772080Y1277100D02*
X-1774320D01*
G01X-1768900Y1275000D02*
Y1281000D01*
X-1767150D01*
X-1766590Y1280700D01*
X-1766240Y1280300D01*
X-1766100Y1279500D01*
X-1766240Y1278700D01*
X-1766660Y1278200D01*
X-1767150Y1277900D01*
X-1768900D01*
G01X-1767150D02*
X-1766100Y1275000D01*
G01X-1761800D02*
Y1277700D01*
X-1763200Y1281000D01*
G01X-1760400D02*
X-1761800Y1277700D01*
G01X-1751800Y1275000D02*
Y1281000D01*
X-1750120D01*
X-1749560Y1280700D01*
X-1749140Y1280000D01*
X-1749000Y1279200D01*
X-1749140Y1278400D01*
X-1749490Y1277800D01*
X-1750120Y1277500D01*
X-1751800D01*
G01X-1746100Y1275000D02*
Y1281000D01*
X-1744350D01*
X-1743790Y1280700D01*
X-1743440Y1280300D01*
X-1743300Y1279500D01*
X-1743440Y1278700D01*
X-1743860Y1278200D01*
X-1744350Y1277900D01*
X-1746100D01*
G01X-1744350D02*
X-1743300Y1275000D01*
G01X-1739000D02*
X-1739560Y1275100D01*
X-1740050Y1275500D01*
X-1740470Y1276100D01*
X-1740750Y1276800D01*
X-1740890Y1277600D01*
Y1278400D01*
X-1740750Y1279200D01*
X-1740470Y1279900D01*
X-1740050Y1280500D01*
X-1739560Y1280900D01*
X-1739000Y1281000D01*
X-1738440Y1280900D01*
X-1737950Y1280500D01*
X-1737530Y1279900D01*
X-1737250Y1279200D01*
X-1737110Y1278400D01*
Y1277600D01*
X-1737250Y1276800D01*
X-1737530Y1276100D01*
X-1737950Y1275500D01*
X-1738440Y1275100D01*
X-1739000Y1275000D01*
G01X-1734700D02*
Y1281000D01*
X-1733020D01*
X-1732460Y1280700D01*
X-1732040Y1280000D01*
X-1731900Y1279200D01*
X-1732040Y1278400D01*
X-1732390Y1277800D01*
X-1733020Y1277500D01*
X-1734700D01*
G01X-1726200Y1275000D02*
X-1729000D01*
Y1281000D01*
X-1726200D01*
G01X-1727320Y1278100D02*
X-1729000D01*
G01X-1723300Y1275000D02*
Y1281000D01*
X-1721550D01*
X-1720990Y1280700D01*
X-1720640Y1280300D01*
X-1720500Y1279500D01*
X-1720640Y1278700D01*
X-1721060Y1278200D01*
X-1721550Y1277900D01*
X-1723300D01*
G01X-1721550D02*
X-1720500Y1275000D01*
G01X-1716200Y1281000D02*
Y1275000D01*
G01X-1717810Y1281000D02*
X-1714590D01*
G01X-1710500Y1275000D02*
Y1277700D01*
X-1711900Y1281000D01*
G01X-1709100D02*
X-1710500Y1277700D01*
G01X-1892900Y1293520D02*
Y1287520D01*
G01X-1894510Y1293520D02*
X-1891290D01*
G01X-1888670Y1287520D02*
Y1293520D01*
G01X-1885730D02*
Y1287520D01*
G01Y1290520D02*
X-1888670D01*
G01X-1882340Y1293520D02*
X-1880660D01*
G01X-1881500D02*
Y1287520D01*
G01X-1882340D02*
X-1880660D01*
G01X-1877270Y1288320D02*
X-1876710Y1287820D01*
X-1876080Y1287520D01*
X-1875520D01*
X-1874960Y1287820D01*
X-1874540Y1288320D01*
X-1874330Y1289020D01*
X-1874470Y1289720D01*
X-1874820Y1290320D01*
X-1875450Y1290720D01*
X-1876290Y1290920D01*
X-1876780Y1291320D01*
X-1876990Y1292020D01*
X-1876850Y1292720D01*
X-1876500Y1293220D01*
X-1876010Y1293520D01*
X-1875520D01*
X-1875030Y1293320D01*
X-1874610Y1292820D01*
G01X-1865940Y1287520D02*
Y1293520D01*
X-1864540D01*
X-1863980Y1293220D01*
X-1863560Y1292820D01*
X-1863210Y1292220D01*
X-1862930Y1291520D01*
X-1862860Y1290520D01*
X-1862930Y1289520D01*
X-1863210Y1288820D01*
X-1863560Y1288220D01*
X-1863980Y1287820D01*
X-1864540Y1287520D01*
X-1865940D01*
G01X-1860100D02*
Y1293520D01*
X-1858350D01*
X-1857790Y1293220D01*
X-1857440Y1292820D01*
X-1857300Y1292020D01*
X-1857440Y1291220D01*
X-1857860Y1290720D01*
X-1858350Y1290420D01*
X-1860100D01*
G01X-1858350D02*
X-1857300Y1287520D01*
G01X-1854750D02*
X-1853000Y1293520D01*
X-1851250Y1287520D01*
G01X-1851880Y1289620D02*
X-1854120D01*
G01X-1849400Y1293520D02*
X-1848420Y1287520D01*
X-1847300Y1293520D01*
X-1846180Y1287520D01*
X-1845200Y1293520D01*
G01X-1842440D02*
X-1840760D01*
G01X-1841600D02*
Y1287520D01*
G01X-1842440D02*
X-1840760D01*
G01X-1837510D02*
Y1293520D01*
X-1834290Y1287520D01*
Y1293520D01*
G01X-1829780Y1290520D02*
X-1828380D01*
Y1288720D01*
X-1828800Y1288120D01*
X-1829290Y1287720D01*
X-1829990Y1287520D01*
X-1830690Y1287720D01*
X-1831180Y1288120D01*
X-1831600Y1288720D01*
X-1831880Y1289420D01*
X-1832020Y1290220D01*
Y1290920D01*
X-1831880Y1291520D01*
X-1831600Y1292220D01*
X-1831180Y1292820D01*
X-1830760Y1293220D01*
X-1830200Y1293520D01*
X-1829710D01*
X-1829150Y1293320D01*
X-1828730Y1292920D01*
G01X-1817260Y1293020D02*
X-1817680Y1293320D01*
X-1818170Y1293520D01*
X-1818730D01*
X-1819360Y1293220D01*
X-1819850Y1292720D01*
X-1820200Y1292120D01*
X-1820480Y1291120D01*
X-1820550Y1290220D01*
X-1820410Y1289320D01*
X-1820200Y1288720D01*
X-1819780Y1288120D01*
X-1819290Y1287720D01*
X-1818800Y1287520D01*
X-1818310D01*
X-1817820Y1287720D01*
X-1817400Y1288020D01*
X-1817050Y1288420D01*
G01X-1813100Y1287520D02*
X-1813660Y1287620D01*
X-1814150Y1288020D01*
X-1814570Y1288620D01*
X-1814850Y1289320D01*
X-1814990Y1290120D01*
Y1290920D01*
X-1814850Y1291720D01*
X-1814570Y1292420D01*
X-1814150Y1293020D01*
X-1813660Y1293420D01*
X-1813100Y1293520D01*
X-1812540Y1293420D01*
X-1812050Y1293020D01*
X-1811630Y1292420D01*
X-1811350Y1291720D01*
X-1811210Y1290920D01*
Y1290120D01*
X-1811350Y1289320D01*
X-1811630Y1288620D01*
X-1812050Y1288020D01*
X-1812540Y1287620D01*
X-1813100Y1287520D01*
G01X-1809010D02*
Y1293520D01*
X-1805790Y1287520D01*
Y1293520D01*
G01X-1801700D02*
Y1287520D01*
G01X-1803310Y1293520D02*
X-1800090D01*
G01X-1797750Y1287520D02*
X-1796000Y1293520D01*
X-1794250Y1287520D01*
G01X-1794880Y1289620D02*
X-1797120D01*
G01X-1791140Y1293520D02*
X-1789460D01*
G01X-1790300D02*
Y1287520D01*
G01X-1791140D02*
X-1789460D01*
G01X-1786210D02*
Y1293520D01*
X-1782990Y1287520D01*
Y1293520D01*
G01X-1780370Y1288320D02*
X-1779810Y1287820D01*
X-1779180Y1287520D01*
X-1778620D01*
X-1778060Y1287820D01*
X-1777640Y1288320D01*
X-1777430Y1289020D01*
X-1777570Y1289720D01*
X-1777920Y1290320D01*
X-1778550Y1290720D01*
X-1779390Y1290920D01*
X-1779880Y1291320D01*
X-1780090Y1292020D01*
X-1779950Y1292720D01*
X-1779600Y1293220D01*
X-1779110Y1293520D01*
X-1778620D01*
X-1778130Y1293320D01*
X-1777710Y1292820D01*
G01X-1768340Y1293520D02*
X-1766660D01*
G01X-1767500D02*
Y1287520D01*
G01X-1768340D02*
X-1766660D01*
G01X-1763410D02*
Y1293520D01*
X-1760190Y1287520D01*
Y1293520D01*
G01X-1757430Y1287520D02*
Y1293520D01*
X-1754770D01*
G01X-1755750Y1290620D02*
X-1757430D01*
G01X-1750400Y1287520D02*
X-1750960Y1287620D01*
X-1751450Y1288020D01*
X-1751870Y1288620D01*
X-1752150Y1289320D01*
X-1752290Y1290120D01*
Y1290920D01*
X-1752150Y1291720D01*
X-1751870Y1292420D01*
X-1751450Y1293020D01*
X-1750960Y1293420D01*
X-1750400Y1293520D01*
X-1749840Y1293420D01*
X-1749350Y1293020D01*
X-1748930Y1292420D01*
X-1748650Y1291720D01*
X-1748510Y1290920D01*
Y1290120D01*
X-1748650Y1289320D01*
X-1748930Y1288620D01*
X-1749350Y1288020D01*
X-1749840Y1287620D01*
X-1750400Y1287520D01*
G01X-1746100D02*
Y1293520D01*
X-1744350D01*
X-1743790Y1293220D01*
X-1743440Y1292820D01*
X-1743300Y1292020D01*
X-1743440Y1291220D01*
X-1743860Y1290720D01*
X-1744350Y1290420D01*
X-1746100D01*
G01X-1744350D02*
X-1743300Y1287520D01*
G01X-1740820D02*
Y1293520D01*
X-1739000Y1288520D01*
X-1737180Y1293520D01*
Y1287520D01*
G01X-1735050D02*
X-1733300Y1293520D01*
X-1731550Y1287520D01*
G01X-1732180Y1289620D02*
X-1734420D01*
G01X-1727600Y1293520D02*
Y1287520D01*
G01X-1729210Y1293520D02*
X-1725990D01*
G01X-1722740D02*
X-1721060D01*
G01X-1721900D02*
Y1287520D01*
G01X-1722740D02*
X-1721060D01*
G01X-1716200D02*
X-1716760Y1287620D01*
X-1717250Y1288020D01*
X-1717670Y1288620D01*
X-1717950Y1289320D01*
X-1718090Y1290120D01*
Y1290920D01*
X-1717950Y1291720D01*
X-1717670Y1292420D01*
X-1717250Y1293020D01*
X-1716760Y1293420D01*
X-1716200Y1293520D01*
X-1715640Y1293420D01*
X-1715150Y1293020D01*
X-1714730Y1292420D01*
X-1714450Y1291720D01*
X-1714310Y1290920D01*
Y1290120D01*
X-1714450Y1289320D01*
X-1714730Y1288620D01*
X-1715150Y1288020D01*
X-1715640Y1287620D01*
X-1716200Y1287520D01*
G01X-1712110D02*
Y1293520D01*
X-1708890Y1287520D01*
Y1293520D01*
G54D19*
G01X666400Y1207600D02*
X665770Y1208050D01*
X665035Y1208350D01*
X664195D01*
X663250Y1207900D01*
X662515Y1207150D01*
X661990Y1206250D01*
X661570Y1204750D01*
X661465Y1203400D01*
X661675Y1202050D01*
X661990Y1201150D01*
X662620Y1200250D01*
X663355Y1199650D01*
X664090Y1199350D01*
X664825D01*
X665560Y1199650D01*
X666190Y1200100D01*
X666715Y1200700D01*
G01X670905Y1199350D02*
Y1208350D01*
G01Y1204000D02*
X671430Y1204750D01*
X671955Y1205200D01*
X672795Y1205350D01*
X673425Y1205200D01*
X674160Y1204600D01*
X674475Y1203700D01*
Y1199350D01*
G01X683180D02*
Y1205350D01*
G01Y1204300D02*
X682760Y1204900D01*
X682130Y1205200D01*
X681395Y1205350D01*
X680660Y1205050D01*
X680030Y1204450D01*
X679610Y1203550D01*
X679400Y1202350D01*
X679610Y1201150D01*
X680030Y1200250D01*
X680660Y1199650D01*
X681395Y1199350D01*
X682130Y1199500D01*
X682760Y1199950D01*
X683180Y1200550D01*
G01X688105Y1199350D02*
Y1205350D01*
G01Y1203850D02*
X688525Y1204600D01*
X689155Y1205200D01*
X689995Y1205350D01*
X690730Y1205200D01*
X691360Y1204600D01*
X691675Y1203550D01*
Y1199350D01*
G01X697020Y1197100D02*
X697755Y1196500D01*
X698595Y1196350D01*
X699330Y1196500D01*
X699960Y1197250D01*
X700380Y1198300D01*
Y1205350D01*
G01Y1204150D02*
X699960Y1204750D01*
X699330Y1205200D01*
X698595Y1205350D01*
X697755Y1205050D01*
X697230Y1204450D01*
X696810Y1203400D01*
X696600Y1202350D01*
X696705Y1201450D01*
X697125Y1200400D01*
X697755Y1199650D01*
X698595Y1199350D01*
X699225Y1199500D01*
X699960Y1200100D01*
X700380Y1200700D01*
G01X705515Y1203400D02*
X708875D01*
X708560Y1204450D01*
X708035Y1205050D01*
X707300Y1205350D01*
X706565Y1205200D01*
X705935Y1204750D01*
X705515Y1203700D01*
X705305Y1202800D01*
Y1201900D01*
X705515Y1201000D01*
X706040Y1200100D01*
X706670Y1199500D01*
X707405Y1199350D01*
X708140Y1199650D01*
X708875Y1200550D01*
G01X724290Y1208350D02*
Y1199350D01*
G01X722820Y1205350D02*
X725760D01*
G01X732890Y1199350D02*
X732260Y1199500D01*
X731630Y1200100D01*
X731210Y1201150D01*
X731000Y1202350D01*
X731210Y1203550D01*
X731630Y1204600D01*
X732260Y1205200D01*
X732890Y1205350D01*
X733520Y1205200D01*
X734150Y1204600D01*
X734570Y1203550D01*
X734675Y1202350D01*
X734570Y1201150D01*
X734150Y1200100D01*
X733520Y1199500D01*
X732890Y1199350D01*
G01X750720Y1203850D02*
X752820D01*
Y1201150D01*
X752190Y1200250D01*
X751455Y1199650D01*
X750405Y1199350D01*
X749355Y1199650D01*
X748620Y1200250D01*
X747990Y1201150D01*
X747570Y1202200D01*
X747360Y1203400D01*
Y1204450D01*
X747570Y1205350D01*
X747990Y1206400D01*
X748620Y1207300D01*
X749250Y1207900D01*
X750090Y1208350D01*
X750825D01*
X751665Y1208050D01*
X752295Y1207450D01*
G01X757220Y1199350D02*
Y1205350D01*
G01Y1204150D02*
X757745Y1204750D01*
X758270Y1205200D01*
X759005Y1205350D01*
X759530Y1205200D01*
X760160Y1204750D01*
G01X765715Y1203400D02*
X769075D01*
X768760Y1204450D01*
X768235Y1205050D01*
X767500Y1205350D01*
X766765Y1205200D01*
X766135Y1204750D01*
X765715Y1203700D01*
X765505Y1202800D01*
Y1201900D01*
X765715Y1201000D01*
X766240Y1200100D01*
X766870Y1199500D01*
X767605Y1199350D01*
X768340Y1199650D01*
X769075Y1200550D01*
G01X774315Y1203400D02*
X777675D01*
X777360Y1204450D01*
X776835Y1205050D01*
X776100Y1205350D01*
X775365Y1205200D01*
X774735Y1204750D01*
X774315Y1203700D01*
X774105Y1202800D01*
Y1201900D01*
X774315Y1201000D01*
X774840Y1200100D01*
X775470Y1199500D01*
X776205Y1199350D01*
X776940Y1199650D01*
X777675Y1200550D01*
G01X782705Y1199350D02*
Y1205350D01*
G01Y1203850D02*
X783125Y1204600D01*
X783755Y1205200D01*
X784595Y1205350D01*
X785330Y1205200D01*
X785960Y1204600D01*
X786275Y1203550D01*
Y1199350D01*
G01X799485Y1200550D02*
X800325Y1199800D01*
X801270Y1199350D01*
X802110D01*
X802950Y1199800D01*
X803580Y1200550D01*
X803895Y1201600D01*
X803685Y1202650D01*
X803160Y1203550D01*
X802215Y1204150D01*
X800955Y1204450D01*
X800220Y1205050D01*
X799905Y1206100D01*
X800115Y1207150D01*
X800640Y1207900D01*
X801375Y1208350D01*
X802110D01*
X802845Y1208050D01*
X803475Y1207300D01*
G01X810290Y1199350D02*
X809660Y1199500D01*
X809030Y1200100D01*
X808610Y1201150D01*
X808400Y1202350D01*
X808610Y1203550D01*
X809030Y1204600D01*
X809660Y1205200D01*
X810290Y1205350D01*
X810920Y1205200D01*
X811550Y1204600D01*
X811970Y1203550D01*
X812075Y1202350D01*
X811970Y1201150D01*
X811550Y1200100D01*
X810920Y1199500D01*
X810290Y1199350D01*
G01X818890D02*
Y1208350D01*
G01X829380D02*
Y1199350D01*
G01Y1200700D02*
X828960Y1199950D01*
X828330Y1199500D01*
X827595Y1199350D01*
X826755Y1199650D01*
X826125Y1200400D01*
X825705Y1201300D01*
X825600Y1202350D01*
X825705Y1203400D01*
X826125Y1204300D01*
X826755Y1205050D01*
X827595Y1205350D01*
X828330Y1205200D01*
X828855Y1204900D01*
X829380Y1204300D01*
G01X834515Y1203400D02*
X837875D01*
X837560Y1204450D01*
X837035Y1205050D01*
X836300Y1205350D01*
X835565Y1205200D01*
X834935Y1204750D01*
X834515Y1203700D01*
X834305Y1202800D01*
Y1201900D01*
X834515Y1201000D01*
X835040Y1200100D01*
X835670Y1199500D01*
X836405Y1199350D01*
X837140Y1199650D01*
X837875Y1200550D01*
G01X843220Y1199350D02*
Y1205350D01*
G01Y1204150D02*
X843745Y1204750D01*
X844270Y1205200D01*
X845005Y1205350D01*
X845530Y1205200D01*
X846160Y1204750D01*
G01X850140Y1199350D02*
Y1205350D01*
G01Y1203700D02*
X850455Y1204450D01*
X850980Y1205050D01*
X851715Y1205350D01*
X852450Y1205050D01*
X852975Y1204450D01*
X853290Y1203700D01*
Y1199350D01*
G01Y1203700D02*
X853605Y1204450D01*
X854130Y1205050D01*
X854865Y1205350D01*
X855600Y1205050D01*
X856125Y1204450D01*
X856440Y1203550D01*
Y1199350D01*
G01X863780D02*
Y1205350D01*
G01Y1204300D02*
X863360Y1204900D01*
X862730Y1205200D01*
X861995Y1205350D01*
X861260Y1205050D01*
X860630Y1204450D01*
X860210Y1203550D01*
X860000Y1202350D01*
X860210Y1201150D01*
X860630Y1200250D01*
X861260Y1199650D01*
X861995Y1199350D01*
X862730Y1199500D01*
X863360Y1199950D01*
X863780Y1200550D01*
G01X868915Y1200400D02*
X869440Y1199800D01*
X870175Y1199350D01*
X870805D01*
X871435Y1199650D01*
X871855Y1200100D01*
X872065Y1200700D01*
X871960Y1201600D01*
X871540Y1202050D01*
X869650Y1202950D01*
X869230Y1204000D01*
X869440Y1204750D01*
X869860Y1205200D01*
X870490Y1205350D01*
X871120Y1205200D01*
X871750Y1204750D01*
G01X877305Y1199350D02*
Y1208350D01*
G01X880665Y1205350D02*
X877305Y1201900D01*
G01X878670Y1203250D02*
X880875Y1199350D01*
G01X662830Y1237620D02*
X665350D01*
G01X664090D02*
Y1228620D01*
G01X662830D02*
X665350D01*
G01X670905D02*
Y1234620D01*
G01Y1233120D02*
X671325Y1233870D01*
X671955Y1234470D01*
X672795Y1234620D01*
X673530Y1234470D01*
X674160Y1233870D01*
X674475Y1232820D01*
Y1228620D01*
G01X681290Y1234620D02*
Y1228620D01*
G01Y1237020D02*
X681080Y1237170D01*
Y1237470D01*
X681290Y1237620D01*
X681500Y1237470D01*
Y1237170D01*
X681290Y1237020D01*
G01X689890Y1237620D02*
Y1228620D01*
G01X688420Y1234620D02*
X691360D01*
G01X698490D02*
Y1228620D01*
G01Y1237020D02*
X698280Y1237170D01*
Y1237470D01*
X698490Y1237620D01*
X698700Y1237470D01*
Y1237170D01*
X698490Y1237020D01*
G01X708980Y1228620D02*
Y1234620D01*
G01Y1233570D02*
X708560Y1234170D01*
X707930Y1234470D01*
X707195Y1234620D01*
X706460Y1234320D01*
X705830Y1233720D01*
X705410Y1232820D01*
X705200Y1231620D01*
X705410Y1230420D01*
X705830Y1229520D01*
X706460Y1228920D01*
X707195Y1228620D01*
X707930Y1228770D01*
X708560Y1229220D01*
X708980Y1229820D01*
G01X715690Y1228620D02*
Y1237620D01*
G01X730790Y1228620D02*
Y1237620D01*
X733415D01*
X734255Y1237170D01*
X734780Y1236570D01*
X734990Y1235370D01*
X734780Y1234170D01*
X734150Y1233420D01*
X733415Y1232970D01*
X730790D01*
G01X733415D02*
X734990Y1228620D01*
G01X739915Y1232670D02*
X743275D01*
X742960Y1233720D01*
X742435Y1234320D01*
X741700Y1234620D01*
X740965Y1234470D01*
X740335Y1234020D01*
X739915Y1232970D01*
X739705Y1232070D01*
Y1231170D01*
X739915Y1230270D01*
X740440Y1229370D01*
X741070Y1228770D01*
X741805Y1228620D01*
X742540Y1228920D01*
X743275Y1229820D01*
G01X750090Y1228620D02*
Y1237620D01*
G01X757115Y1232670D02*
X760475D01*
X760160Y1233720D01*
X759635Y1234320D01*
X758900Y1234620D01*
X758165Y1234470D01*
X757535Y1234020D01*
X757115Y1232970D01*
X756905Y1232070D01*
Y1231170D01*
X757115Y1230270D01*
X757640Y1229370D01*
X758270Y1228770D01*
X759005Y1228620D01*
X759740Y1228920D01*
X760475Y1229820D01*
G01X769180Y1228620D02*
Y1234620D01*
G01Y1233570D02*
X768760Y1234170D01*
X768130Y1234470D01*
X767395Y1234620D01*
X766660Y1234320D01*
X766030Y1233720D01*
X765610Y1232820D01*
X765400Y1231620D01*
X765610Y1230420D01*
X766030Y1229520D01*
X766660Y1228920D01*
X767395Y1228620D01*
X768130Y1228770D01*
X768760Y1229220D01*
X769180Y1229820D01*
G01X774315Y1229670D02*
X774840Y1229070D01*
X775575Y1228620D01*
X776205D01*
X776835Y1228920D01*
X777255Y1229370D01*
X777465Y1229970D01*
X777360Y1230870D01*
X776940Y1231320D01*
X775050Y1232220D01*
X774630Y1233270D01*
X774840Y1234020D01*
X775260Y1234470D01*
X775890Y1234620D01*
X776520Y1234470D01*
X777150Y1234020D01*
G01X782915Y1232670D02*
X786275D01*
X785960Y1233720D01*
X785435Y1234320D01*
X784700Y1234620D01*
X783965Y1234470D01*
X783335Y1234020D01*
X782915Y1232970D01*
X782705Y1232070D01*
Y1231170D01*
X782915Y1230270D01*
X783440Y1229370D01*
X784070Y1228770D01*
X784805Y1228620D01*
X785540Y1228920D01*
X786275Y1229820D01*
G01X662830Y1237620D02*
X665350D01*
G01X664090D02*
Y1228620D01*
G01X662830D02*
X665350D01*
G01X670905D02*
Y1234620D01*
G01Y1233120D02*
X671325Y1233870D01*
X671955Y1234470D01*
X672795Y1234620D01*
X673530Y1234470D01*
X674160Y1233870D01*
X674475Y1232820D01*
Y1228620D01*
G01X681290Y1234620D02*
Y1228620D01*
G01Y1237020D02*
X681080Y1237170D01*
Y1237470D01*
X681290Y1237620D01*
X681500Y1237470D01*
Y1237170D01*
X681290Y1237020D01*
G01X689890Y1237620D02*
Y1228620D01*
G01X688420Y1234620D02*
X691360D01*
G01X698490D02*
Y1228620D01*
G01Y1237020D02*
X698280Y1237170D01*
Y1237470D01*
X698490Y1237620D01*
X698700Y1237470D01*
Y1237170D01*
X698490Y1237020D01*
G01X708980Y1228620D02*
Y1234620D01*
G01Y1233570D02*
X708560Y1234170D01*
X707930Y1234470D01*
X707195Y1234620D01*
X706460Y1234320D01*
X705830Y1233720D01*
X705410Y1232820D01*
X705200Y1231620D01*
X705410Y1230420D01*
X705830Y1229520D01*
X706460Y1228920D01*
X707195Y1228620D01*
X707930Y1228770D01*
X708560Y1229220D01*
X708980Y1229820D01*
G01X715690Y1228620D02*
Y1237620D01*
G01X730790Y1228620D02*
Y1237620D01*
X733415D01*
X734255Y1237170D01*
X734780Y1236570D01*
X734990Y1235370D01*
X734780Y1234170D01*
X734150Y1233420D01*
X733415Y1232970D01*
X730790D01*
G01X733415D02*
X734990Y1228620D01*
G01X739915Y1232670D02*
X743275D01*
X742960Y1233720D01*
X742435Y1234320D01*
X741700Y1234620D01*
X740965Y1234470D01*
X740335Y1234020D01*
X739915Y1232970D01*
X739705Y1232070D01*
Y1231170D01*
X739915Y1230270D01*
X740440Y1229370D01*
X741070Y1228770D01*
X741805Y1228620D01*
X742540Y1228920D01*
X743275Y1229820D01*
G01X750090Y1228620D02*
Y1237620D01*
G01X757115Y1232670D02*
X760475D01*
X760160Y1233720D01*
X759635Y1234320D01*
X758900Y1234620D01*
X758165Y1234470D01*
X757535Y1234020D01*
X757115Y1232970D01*
X756905Y1232070D01*
Y1231170D01*
X757115Y1230270D01*
X757640Y1229370D01*
X758270Y1228770D01*
X759005Y1228620D01*
X759740Y1228920D01*
X760475Y1229820D01*
G01X769180Y1228620D02*
Y1234620D01*
G01Y1233570D02*
X768760Y1234170D01*
X768130Y1234470D01*
X767395Y1234620D01*
X766660Y1234320D01*
X766030Y1233720D01*
X765610Y1232820D01*
X765400Y1231620D01*
X765610Y1230420D01*
X766030Y1229520D01*
X766660Y1228920D01*
X767395Y1228620D01*
X768130Y1228770D01*
X768760Y1229220D01*
X769180Y1229820D01*
G01X774315Y1229670D02*
X774840Y1229070D01*
X775575Y1228620D01*
X776205D01*
X776835Y1228920D01*
X777255Y1229370D01*
X777465Y1229970D01*
X777360Y1230870D01*
X776940Y1231320D01*
X775050Y1232220D01*
X774630Y1233270D01*
X774840Y1234020D01*
X775260Y1234470D01*
X775890Y1234620D01*
X776520Y1234470D01*
X777150Y1234020D01*
G01X782915Y1232670D02*
X786275D01*
X785960Y1233720D01*
X785435Y1234320D01*
X784700Y1234620D01*
X783965Y1234470D01*
X783335Y1234020D01*
X782915Y1232970D01*
X782705Y1232070D01*
Y1231170D01*
X782915Y1230270D01*
X783440Y1229370D01*
X784070Y1228770D01*
X784805Y1228620D01*
X785540Y1228920D01*
X786275Y1229820D01*
G01X724695Y-600500D02*
Y-591500D01*
G01X729105D02*
Y-600500D01*
G01Y-596000D02*
X724695D01*
G01X735500Y-600800D02*
X735290Y-600650D01*
Y-600350D01*
X735500Y-600200D01*
X735710Y-600350D01*
Y-600650D01*
X735500Y-600800D01*
G01X742105Y-600500D02*
Y-591500D01*
X746095D01*
G01X744625Y-595850D02*
X742105D01*
G01X750600Y-591500D02*
Y-600500D01*
X754800D01*
G01X761300D02*
X760460Y-600350D01*
X759725Y-599750D01*
X759095Y-598850D01*
X758675Y-597800D01*
X758465Y-596600D01*
Y-595400D01*
X758675Y-594200D01*
X759095Y-593150D01*
X759725Y-592250D01*
X760460Y-591650D01*
X761300Y-591500D01*
X762140Y-591650D01*
X762875Y-592250D01*
X763505Y-593150D01*
X763925Y-594200D01*
X764135Y-595400D01*
Y-596600D01*
X763925Y-597800D01*
X763505Y-598850D01*
X762875Y-599750D01*
X762140Y-600350D01*
X761300Y-600500D01*
G01X767800D02*
Y-591500D01*
X770425D01*
X771265Y-591950D01*
X771790Y-592550D01*
X772000Y-593750D01*
X771790Y-594950D01*
X771160Y-595700D01*
X770425Y-596150D01*
X767800D01*
G01X770425D02*
X772000Y-600500D01*
G01X777240Y-591500D02*
X779760D01*
G01X778500D02*
Y-600500D01*
G01X777240D02*
X779760D01*
G01X787100D02*
X786260Y-600350D01*
X785525Y-599750D01*
X784895Y-598850D01*
X784475Y-597800D01*
X784265Y-596600D01*
Y-595400D01*
X784475Y-594200D01*
X784895Y-593150D01*
X785525Y-592250D01*
X786260Y-591650D01*
X787100Y-591500D01*
X787940Y-591650D01*
X788675Y-592250D01*
X789305Y-593150D01*
X789725Y-594200D01*
X789935Y-595400D01*
Y-596600D01*
X789725Y-597800D01*
X789305Y-598850D01*
X788675Y-599750D01*
X787940Y-600350D01*
X787100Y-600500D01*
G01X1327240Y1200650D02*
X1327870Y1199900D01*
X1328605Y1199450D01*
X1329550Y1199300D01*
X1330495Y1199600D01*
X1331230Y1200200D01*
X1331755Y1201250D01*
X1331860Y1202450D01*
X1331650Y1203650D01*
X1331125Y1204400D01*
X1330390Y1205000D01*
X1329655Y1205150D01*
X1328920Y1205000D01*
X1327975Y1204400D01*
X1328290Y1208300D01*
X1331125D01*
G01X1336260Y1199000D02*
X1340040Y1208300D01*
G01X1346750D02*
X1345910Y1208000D01*
X1345280Y1207250D01*
X1344860Y1206350D01*
X1344545Y1205150D01*
X1344440Y1203800D01*
X1344545Y1202450D01*
X1344860Y1201250D01*
X1345280Y1200350D01*
X1345910Y1199600D01*
X1346750Y1199300D01*
X1347590Y1199600D01*
X1348220Y1200350D01*
X1348640Y1201250D01*
X1348955Y1202450D01*
X1349060Y1203800D01*
X1348955Y1205150D01*
X1348640Y1206350D01*
X1348220Y1207250D01*
X1347590Y1208000D01*
X1346750Y1208300D01*
G01X1353565Y1200350D02*
X1354300Y1199600D01*
X1355140Y1199300D01*
X1355980Y1199600D01*
X1356715Y1200500D01*
X1357240Y1201850D01*
X1357450Y1203200D01*
Y1204850D01*
X1357240Y1206200D01*
X1356715Y1207400D01*
X1356085Y1208000D01*
X1355350Y1208300D01*
X1354510Y1208000D01*
X1353880Y1207400D01*
X1353460Y1206500D01*
X1353250Y1205300D01*
X1353460Y1204250D01*
X1353985Y1203200D01*
X1354615Y1202600D01*
X1355350Y1202450D01*
X1356190Y1202750D01*
X1356820Y1203500D01*
X1357450Y1204850D01*
G01X1362060Y1199000D02*
X1365840Y1208300D01*
G01X1372550Y1199300D02*
Y1208300D01*
X1371290Y1206500D01*
G01Y1199300D02*
X1373810D01*
G01X1382410D02*
Y1208300D01*
X1378525Y1201850D01*
X1383775D01*
G01X1327555Y1237740D02*
X1328185Y1238640D01*
X1328920Y1239090D01*
X1329760Y1239240D01*
X1330810Y1238940D01*
X1331545Y1238190D01*
X1331755Y1237290D01*
X1331650Y1236390D01*
X1331230Y1235640D01*
X1329130Y1234140D01*
X1328185Y1233090D01*
X1327555Y1231590D01*
X1327345Y1230240D01*
X1331755D01*
G01X1336260Y1229940D02*
X1340040Y1239240D01*
G01X1346750Y1230240D02*
Y1239240D01*
X1345490Y1237440D01*
G01Y1230240D02*
X1348010D01*
G01X1355350Y1239240D02*
X1354510Y1238940D01*
X1353880Y1238190D01*
X1353460Y1237290D01*
X1353145Y1236090D01*
X1353040Y1234740D01*
X1353145Y1233390D01*
X1353460Y1232190D01*
X1353880Y1231290D01*
X1354510Y1230540D01*
X1355350Y1230240D01*
X1356190Y1230540D01*
X1356820Y1231290D01*
X1357240Y1232190D01*
X1357555Y1233390D01*
X1357660Y1234740D01*
X1357555Y1236090D01*
X1357240Y1237290D01*
X1356820Y1238190D01*
X1356190Y1238940D01*
X1355350Y1239240D01*
G01X1362060Y1229940D02*
X1365840Y1239240D01*
G01X1372550Y1230240D02*
Y1239240D01*
X1371290Y1237440D01*
G01Y1230240D02*
X1373810D01*
G01X1382410D02*
Y1239240D01*
X1378525Y1232790D01*
X1383775D01*
M02*
